(kicad_pcb
	(version 20241229)
	(generator "pcbnew")
	(generator_version "9.0")
	(general
		(thickness 1.599998)
		(legacy_teardrops no)
	)
	(paper "A4")
	(title_block
		(date "2023-02-12")
		(rev "1.1.5")
	)
	(layers
		(0 "F.Cu" signal)
		(4 "In1.Cu" power "In1.GND")
		(6 "In2.Cu" signal)
		(8 "In3.Cu" power "In3.GND")
		(10 "In4.Cu" power "In4.VCC")
		(12 "In5.Cu" signal)
		(14 "In6.Cu" power "In6.VCC")
		(2 "B.Cu" signal)
		(9 "F.Adhes" user "F.Adhesive")
		(11 "B.Adhes" user "B.Adhesive")
		(13 "F.Paste" user)
		(15 "B.Paste" user)
		(5 "F.SilkS" user "F.Silkscreen")
		(7 "B.SilkS" user "B.Silkscreen")
		(1 "F.Mask" user)
		(3 "B.Mask" user)
		(17 "Dwgs.User" user "User.Drawings")
		(19 "Cmts.User" user "User.Comments")
		(21 "Eco1.User" user "User.Eco1")
		(23 "Eco2.User" user "User.Eco2")
		(25 "Edge.Cuts" user)
		(27 "Margin" user)
		(31 "F.CrtYd" user "F.Courtyard")
		(29 "B.CrtYd" user "B.Courtyard")
		(35 "F.Fab" user)
		(33 "B.Fab" user)
	)
	(setup
		(stackup
			(layer "F.SilkS"
				(type "Top Silk Screen")
			)
			(layer "F.Paste"
				(type "Top Solder Paste")
			)
			(layer "F.Mask"
				(type "Top Solder Mask")
				(thickness 0.01)
			)
			(layer "F.Cu"
				(type "copper")
				(thickness 0.035)
			)
			(layer "dielectric 1"
				(type "core")
				(thickness 0.185714)
				(material "FR4")
				(epsilon_r 4.5)
				(loss_tangent 0.02)
			)
			(layer "In1.Cu"
				(type "copper")
				(thickness 0.035)
			)
			(layer "dielectric 2"
				(type "prepreg")
				(thickness 0.185714)
				(material "FR4")
				(epsilon_r 4.5)
				(loss_tangent 0.02)
			)
			(layer "In2.Cu"
				(type "copper")
				(thickness 0.035)
			)
			(layer "dielectric 3"
				(type "core")
				(thickness 0.185714)
				(material "FR4")
				(epsilon_r 4.5)
				(loss_tangent 0.02)
			)
			(layer "In3.Cu"
				(type "copper")
				(thickness 0.035)
			)
			(layer "dielectric 4"
				(type "prepreg")
				(thickness 0.185714)
				(material "FR4")
				(epsilon_r 4.5)
				(loss_tangent 0.02)
			)
			(layer "In4.Cu"
				(type "copper")
				(thickness 0.035)
			)
			(layer "dielectric 5"
				(type "core")
				(thickness 0.185714)
				(material "FR4")
				(epsilon_r 4.5)
				(loss_tangent 0.02)
			)
			(layer "In5.Cu"
				(type "copper")
				(thickness 0.035)
			)
			(layer "dielectric 6"
				(type "prepreg")
				(thickness 0.185714)
				(material "FR4")
				(epsilon_r 4.5)
				(loss_tangent 0.02)
			)
			(layer "In6.Cu"
				(type "copper")
				(thickness 0.035)
			)
			(layer "dielectric 7"
				(type "core")
				(thickness 0.185714)
				(material "FR4")
				(epsilon_r 4.5)
				(loss_tangent 0.02)
			)
			(layer "B.Cu"
				(type "copper")
				(thickness 0.035)
			)
			(layer "B.Mask"
				(type "Bottom Solder Mask")
				(thickness 0.01)
			)
			(layer "B.Paste"
				(type "Bottom Solder Paste")
			)
			(layer "B.SilkS"
				(type "Bottom Silk Screen")
			)
			(copper_finish "None")
			(dielectric_constraints no)
		)
		(pad_to_mask_clearance 0)
		(allow_soldermask_bridges_in_footprints no)
		(tenting front back)
		(aux_axis_origin 107 136)
		(pcbplotparams
			(layerselection 0x00000000_00000000_55555555_5755f5ff)
			(plot_on_all_layers_selection 0x00000000_00000000_00000000_00000000)
			(disableapertmacros no)
			(usegerberextensions no)
			(usegerberattributes yes)
			(usegerberadvancedattributes yes)
			(creategerberjobfile yes)
			(dashed_line_dash_ratio 12.000000)
			(dashed_line_gap_ratio 3.000000)
			(svgprecision 6)
			(plotframeref no)
			(mode 1)
			(useauxorigin no)
			(hpglpennumber 1)
			(hpglpenspeed 20)
			(hpglpendiameter 15.000000)
			(pdf_front_fp_property_popups yes)
			(pdf_back_fp_property_popups yes)
			(pdf_metadata yes)
			(pdf_single_document no)
			(dxfpolygonmode yes)
			(dxfimperialunits yes)
			(dxfusepcbnewfont yes)
			(psnegative no)
			(psa4output no)
			(plot_black_and_white yes)
			(sketchpadsonfab no)
			(plotpadnumbers no)
			(hidednponfab no)
			(sketchdnponfab yes)
			(crossoutdnponfab yes)
			(subtractmaskfromsilk no)
			(outputformat 1)
			(mirror no)
			(drillshape 0)
			(scaleselection 1)
			(outputdirectory "./fab")
		)
	)
	(net 0 "")
	(net 1 "VBUS")
	(net 2 "/Interfaces/1V8_FT")
	(net 3 "Net-(U4-OSCI)")
	(net 4 "Net-(U4-OSCO)")
	(net 5 "GND")
	(net 6 "DBG_USB_P")
	(net 7 "DBG_USB_N")
	(net 8 "TCK_JTAG")
	(net 9 "TMS_JTAG")
	(net 10 "TDI_JTAG")
	(net 11 "TDO_JTAG")
	(net 12 "LED_LINK")
	(net 13 "LED_SPD")
	(net 14 "MODE2")
	(net 15 "QSPI_DQ0")
	(net 16 "QSPI_DQ1")
	(net 17 "QSPI_DQ2")
	(net 18 "QSPI_DQ3")
	(net 19 "MODE0")
	(net 20 "MODE1")
	(net 21 "DONE")
	(net 22 "ETH_RXD0")
	(net 23 "ETH_RXD1")
	(net 24 "ETH_RSTN")
	(net 25 "ETH_MDIO")
	(net 26 "ETH_REF_CLK")
	(net 27 "ETH_TXD1")
	(net 28 "ETH_TXD2")
	(net 29 "ETH_TXD3")
	(net 30 "ETH_TX_CLK")
	(net 31 "ETH_TX_EN")
	(net 32 "ETH_TXD0")
	(net 33 "ETH_RXD3")
	(net 34 "ETH_RX_DV")
	(net 35 "ETH_MDC")
	(net 36 "ETH_RX_CLK")
	(net 37 "ETH_RXD2")
	(net 38 "GCLK100")
	(net 39 "Net-(IC2-SS{slash}TR)")
	(net 40 "Net-(IC2-COMP)")
	(net 41 "Net-(C129-Pad1)")
	(net 42 "Net-(IC2-SW)")
	(net 43 "Net-(IC2-BOOT)")
	(net 44 "TMDS_CLK_P")
	(net 45 "TMDS_CLK_N")
	(net 46 "TMDS_D0_P")
	(net 47 "TMDS_D0_N")
	(net 48 "TMDS_D1_P")
	(net 49 "TMDS_D1_N")
	(net 50 "TMDS_D2_P")
	(net 51 "TMDS_D2_N")
	(net 52 "Net-(D5-Pad2)")
	(net 53 "Net-(D6-Pad2)")
	(net 54 "Net-(D8-Pad2)")
	(net 55 "Net-(C141-Pad1)")
	(net 56 "USR_LED1")
	(net 57 "USR_LED3")
	(net 58 "Net-(U7-TADJ)")
	(net 59 "USR_LED2")
	(net 60 "Net-(U15-CAP)")
	(net 61 "USR_LED4")
	(net 62 "Net-(U16-CAP)")
	(net 63 "USR_LED5")
	(net 64 "unconnected-(D7-D2+-Pad12)")
	(net 65 "unconnected-(D7-D2--Pad11)")
	(net 66 "VDDQ")
	(net 67 "Net-(D9-Pad2)")
	(net 68 "CA5_A")
	(net 69 "CA4_A")
	(net 70 "CA3_A")
	(net 71 "CA2_A")
	(net 72 "Net-(D2-Pad2)")
	(net 73 "Net-(D3-Pad2)")
	(net 74 "Net-(J1-SHIELD)")
	(net 75 "unconnected-(IC1-NC-Pad14)")
	(net 76 "Net-(J6-Pad1)")
	(net 77 "Net-(IC2-RT{slash}CLK)")
	(net 78 "unconnected-(J1-ID-Pad4)")
	(net 79 "unconnected-(J2-UTILITY{slash}HEAC+-Pad14)")
	(net 80 "Net-(J2-CEC)")
	(net 81 "Net-(J2-SCL)")
	(net 82 "Net-(J2-SDA)")
	(net 83 "Net-(J2-+5V)")
	(net 84 "Net-(J2-HPD{slash}HEAC-)")
	(net 85 "Net-(J3-CD1)")
	(net 86 "unconnected-(J4-Pad12)")
	(net 87 "unconnected-(J4-Pad14)")
	(net 88 "unconnected-(J5-VCC-Pad9)")
	(net 89 "Net-(J5-LED1_Y+)")
	(net 90 "Net-(J5-LED2_G+)")
	(net 91 "unconnected-(J9-Pad51)")
	(net 92 "unconnected-(J9-Pad52)")
	(net 93 "unconnected-(J9-Pad53)")
	(net 94 "unconnected-(J9-Pad54)")
	(net 95 "PUDC_B")
	(net 96 "unconnected-(J9-Pad55)")
	(net 97 "unconnected-(J9-Pad56)")
	(net 98 "unconnected-(J9-Pad57)")
	(net 99 "unconnected-(J9-Pad58)")
	(net 100 "unconnected-(J9-Pad59)")
	(net 101 "unconnected-(J9-Pad60)")
	(net 102 "unconnected-(J9-Pad61)")
	(net 103 "unconnected-(J9-Pad62)")
	(net 104 "unconnected-(J9-Pad63)")
	(net 105 "unconnected-(J9-Pad64)")
	(net 106 "unconnected-(J9-Pad65)")
	(net 107 "unconnected-(J9-Pad66)")
	(net 108 "unconnected-(J9-Pad67)")
	(net 109 "unconnected-(J9-Pad68)")
	(net 110 "unconnected-(J9-Pad69)")
	(net 111 "unconnected-(J9-Pad70)")
	(net 112 "unconnected-(J9-Pad71)")
	(net 113 "unconnected-(J9-Pad72)")
	(net 114 "unconnected-(J9-Pad73)")
	(net 115 "unconnected-(J9-Pad74)")
	(net 116 "unconnected-(J9-Pad75)")
	(net 117 "unconnected-(J9-Pad76)")
	(net 118 "unconnected-(J9-Pad77)")
	(net 119 "unconnected-(J9-Pad78)")
	(net 120 "unconnected-(J9-Pad79)")
	(net 121 "unconnected-(J9-Pad80)")
	(net 122 "unconnected-(J9-Pad81)")
	(net 123 "unconnected-(J9-Pad82)")
	(net 124 "unconnected-(J9-Pad83)")
	(net 125 "unconnected-(J9-Pad84)")
	(net 126 "unconnected-(J9-Pad85)")
	(net 127 "unconnected-(J9-Pad86)")
	(net 128 "unconnected-(J9-Pad87)")
	(net 129 "unconnected-(J9-Pad88)")
	(net 130 "unconnected-(J9-Pad89)")
	(net 131 "unconnected-(J9-Pad90)")
	(net 132 "unconnected-(J9-Pad91)")
	(net 133 "unconnected-(J9-Pad92)")
	(net 134 "unconnected-(J9-Pad94)")
	(net 135 "unconnected-(J9-Pad96)")
	(net 136 "unconnected-(J9-Pad98)")
	(net 137 "unconnected-(J9-Pad100)")
	(net 138 "unconnected-(J9-Pad102)")
	(net 139 "unconnected-(J9-Pad104)")
	(net 140 "unconnected-(J9-Pad106)")
	(net 141 "unconnected-(J9-Pad108)")
	(net 142 "unconnected-(J9-Pad109)")
	(net 143 "unconnected-(J9-Pad110)")
	(net 144 "unconnected-(J9-Pad111)")
	(net 145 "unconnected-(J9-Pad112)")
	(net 146 "unconnected-(J9-Pad113)")
	(net 147 "unconnected-(J9-Pad114)")
	(net 148 "unconnected-(J9-Pad115)")
	(net 149 "unconnected-(J9-Pad117)")
	(net 150 "unconnected-(J9-Pad119)")
	(net 151 "unconnected-(J9-Pad121)")
	(net 152 "unconnected-(J9-Pad123)")
	(net 153 "unconnected-(J9-Pad125)")
	(net 154 "unconnected-(J9-Pad132)")
	(net 155 "unconnected-(J9-Pad134)")
	(net 156 "unconnected-(J9-Pad136)")
	(net 157 "unconnected-(J9-Pad138)")
	(net 158 "unconnected-(J9-Pad140)")
	(net 159 "unconnected-(J9-Pad142)")
	(net 160 "unconnected-(J9-Pad144)")
	(net 161 "unconnected-(J9-Pad145)")
	(net 162 "unconnected-(J9-Pad146)")
	(net 163 "unconnected-(J9-Pad147)")
	(net 164 "unconnected-(J9-Pad148)")
	(net 165 "unconnected-(J9-Pad149)")
	(net 166 "unconnected-(J9-Pad150)")
	(net 167 "unconnected-(J9-Pad151)")
	(net 168 "unconnected-(J9-Pad152)")
	(net 169 "unconnected-(J9-Pad153)")
	(net 170 "unconnected-(J9-Pad155)")
	(net 171 "unconnected-(J9-Pad157)")
	(net 172 "unconnected-(J9-Pad159)")
	(net 173 "unconnected-(J9-Pad188)")
	(net 174 "unconnected-(J9-Pad190)")
	(net 175 "unconnected-(J9-Pad202)")
	(net 176 "unconnected-(J9-Pad212)")
	(net 177 "unconnected-(J9-Pad213)")
	(net 178 "unconnected-(J9-Pad214)")
	(net 179 "unconnected-(J9-Pad215)")
	(net 180 "unconnected-(J9-Pad216)")
	(net 181 "unconnected-(J9-Pad217)")
	(net 182 "unconnected-(J9-Pad218)")
	(net 183 "unconnected-(J9-Pad219)")
	(net 184 "unconnected-(J9-Pad220)")
	(net 185 "unconnected-(J9-Pad221)")
	(net 186 "unconnected-(J9-Pad222)")
	(net 187 "unconnected-(J9-Pad223)")
	(net 188 "unconnected-(J9-Pad224)")
	(net 189 "unconnected-(J9-Pad225)")
	(net 190 "unconnected-(J9-Pad226)")
	(net 191 "unconnected-(J9-Pad227)")
	(net 192 "SD_DAT1")
	(net 193 "SD_DAT0")
	(net 194 "SD_CLK")
	(net 195 "SD_CMD")
	(net 196 "SD_DAT3")
	(net 197 "SD_DAT2")
	(net 198 "SD_CD")
	(net 199 "unconnected-(J9-Pad228)")
	(net 200 "unconnected-(J9-Pad229)")
	(net 201 "unconnected-(J9-Pad230)")
	(net 202 "unconnected-(S1-Pad1)")
	(net 203 "unconnected-(SP1-Pad1)")
	(net 204 "unconnected-(J9-Pad231)")
	(net 205 "unconnected-(J9-Pad232)")
	(net 206 "Net-(D1-Pad2)")
	(net 207 "unconnected-(J9-Pad233)")
	(net 208 "PROGRAM_B")
	(net 209 "Net-(Q1-D)")
	(net 210 "INIT_B")
	(net 211 "Net-(Q2-D)")
	(net 212 "FCS_B")
	(net 213 "CCLK")
	(net 214 "unconnected-(J9-Pad234)")
	(net 215 "unconnected-(J9-Pad235)")
	(net 216 "unconnected-(J9-Pad236)")
	(net 217 "EMCCLK")
	(net 218 "unconnected-(J9-Pad237)")
	(net 219 "CFGBVS")
	(net 220 "unconnected-(J9-Pad238)")
	(net 221 "unconnected-(J9-Pad239)")
	(net 222 "unconnected-(J9-Pad240)")
	(net 223 "unconnected-(J9-Pad241)")
	(net 224 "VIN")
	(net 225 "unconnected-(J9-Pad242)")
	(net 226 "unconnected-(J9-Pad243)")
	(net 227 "unconnected-(J9-Pad244)")
	(net 228 "Net-(Q3-D)")
	(net 229 "Net-(PWR1-Pad2)")
	(net 230 "Net-(Q4-D)")
	(net 231 "Net-(Q5-D)")
	(net 232 "Net-(Q6-D)")
	(net 233 "Net-(Q7-D)")
	(net 234 "Net-(Q8-D)")
	(net 235 "Net-(Q9-D)")
	(net 236 "Net-(Q10-D)")
	(net 237 "Net-(Q11-D)")
	(net 238 "Net-(Q13-G)")
	(net 239 "Net-(U4-REF)")
	(net 240 "Net-(U4-~{RESET})")
	(net 241 "Net-(U4-ADBUS0)")
	(net 242 "Net-(U4-ADBUS1)")
	(net 243 "Net-(U4-ADBUS2)")
	(net 244 "Net-(R103-Pad2)")
	(net 245 "Net-(U4-ADBUS3)")
	(net 246 "Net-(U4-BDBUS0)")
	(net 247 "Net-(U4-BDBUS1)")
	(net 248 "Net-(U4-BDBUS2)")
	(net 249 "Net-(U4-BDBUS3)")
	(net 250 "Net-(U4-BDBUS5)")
	(net 251 "Net-(U4-CDBUS0)")
	(net 252 "Net-(U4-CDBUS1)")
	(net 253 "Net-(U4-DDBUS0)")
	(net 254 "Net-(U4-DDBUS1)")
	(net 255 "Net-(U5-*CS)")
	(net 256 "Net-(U5-SCK)")
	(net 257 "Net-(U5-*HOLD{slash}IO3)")
	(net 258 "Net-(U5-*WP{slash}IO2)")
	(net 259 "Net-(U5-SI{slash}IO0)")
	(net 260 "Net-(U5-SO{slash}IO1)")
	(net 261 "Net-(U6-ISET)")
	(net 262 "Net-(U7-INV)")
	(net 263 "Net-(U15-ON)")
	(net 264 "Net-(U16-ON)")
	(net 265 "Net-(U4-ADBUS5)")
	(net 266 "unconnected-(U1-NC-PadA2)")
	(net 267 "unconnected-(U1-NC-PadA5)")
	(net 268 "unconnected-(U1-NC-PadB5)")
	(net 269 "unconnected-(U1-NC-PadC2)")
	(net 270 "unconnected-(U1-NC-PadC5)")
	(net 271 "unconnected-(U3A-MGTAVTT-PadA2)")
	(net 272 "unconnected-(U3C-MGTXTXN3_115-PadA3)")
	(net 273 "1V1_DDR")
	(net 274 "unconnected-(U3C-MGTXTXP3_115-PadA4)")
	(net 275 "unconnected-(U3A-MGTAVCC-PadA6)")
	(net 276 "unconnected-(U3F-IO_L21P_T3_DQS_16-PadA9)")
	(net 277 "unconnected-(U3F-IO_L23N_T3_16-PadA10)")
	(net 278 "unconnected-(U3F-IO_L23P_T3_16-PadA11)")
	(net 279 "unconnected-(U3G-IO_L22P_T3_A17_15-PadA20)")
	(net 280 "unconnected-(U3G-IO_L22N_T3_A16_15-PadA21)")
	(net 281 "unconnected-(U3E-IO_L1P_T0_33-PadAA5)")
	(net 282 "unconnected-(U3E-IO_L3P_T0_DQS_33-PadAA6)")
	(net 283 "unconnected-(U3E-IO_L5N_T0_33-PadAA8)")
	(net 284 "unconnected-(U3E-IO_L5P_T0_33-PadAA9)")
	(net 285 "unconnected-(U3E-IO_L4P_T0_33-PadAA10)")
	(net 286 "unconnected-(U3E-IO_L21N_T3_DQS_33-PadAA13)")
	(net 287 "unconnected-(U3I-IO_L10P_T1_13-PadAA19)")
	(net 288 "unconnected-(U3E-IO_L1N_T0_33-PadAB5)")
	(net 289 "unconnected-(U3E-IO_L3N_T0_DQS_33-PadAB6)")
	(net 290 "unconnected-(U3E-IO_L2N_T0_33-PadAB7)")
	(net 291 "unconnected-(U3E-IO_L2P_T0_33-PadAB8)")
	(net 292 "unconnected-(U3E-IO_L22N_T3_33-PadAB12)")
	(net 293 "unconnected-(U3E-IO_L22P_T3_33-PadAB13)")
	(net 294 "unconnected-(U3C-MGTXTXN2_115-PadB1)")
	(net 295 "unconnected-(U3C-MGTXTXP2_115-PadB2)")
	(net 296 "unconnected-(U3C-MGTXRXN3_115-PadB5)")
	(net 297 "unconnected-(U3C-MGTXRXP3_115-PadB6)")
	(net 298 "unconnected-(U3F-IO_L20N_T3_16-PadB10)")
	(net 299 "unconnected-(U3F-IO_L20P_T3_16-PadB11)")
	(net 300 "unconnected-(U3G-IO_L2N_T0_AD8N_15-PadB12)")
	(net 301 "unconnected-(U3G-IO_L5N_T0_AD2N_15-PadB13)")
	(net 302 "unconnected-(U3G-IO_L20P_T3_A20_15-PadB18)")
	(net 303 "unconnected-(U3C-MGTXRXN2_115-PadC3)")
	(net 304 "unconnected-(U3C-MGTXRXP2_115-PadC4)")
	(net 305 "unconnected-(U3F-IO_L7N_T1_16-PadC10)")
	(net 306 "unconnected-(U3G-IO_L5P_T0_AD2P_15-PadC13)")
	(net 307 "unconnected-(U3G-IO_L12N_T1_MRCC_AD5N_15-PadC18)")
	(net 308 "unconnected-(U3G-IO_L19P_T3_A22_15-PadC19)")
	(net 309 "unconnected-(U3C-MGTXTXN1_115-PadD1)")
	(net 310 "unconnected-(U3C-MGTXTXP1_115-PadD2)")
	(net 311 "unconnected-(U3C-MGTREFCLK0N_115-PadD5)")
	(net 312 "unconnected-(U3C-MGTREFCLK0P_115-PadD6)")
	(net 313 "unconnected-(U3F-IO_L7P_T1_16-PadD10)")
	(net 314 "unconnected-(U3F-IO_L12N_T1_MRCC_16-PadD11)")
	(net 315 "unconnected-(U3G-IO_0_15-PadD12)")
	(net 316 "unconnected-(U3G-IO_L6N_T0_VREF_15-PadD14)")
	(net 317 "unconnected-(U3G-IO_L11P_T1_SRCC_AD12P_15-PadD15)")
	(net 318 "unconnected-(U3G-IO_L11N_T1_SRCC_AD12N_15-PadD16)")
	(net 319 "unconnected-(U3G-IO_L14N_T2_SRCC_15-PadD17)")
	(net 320 "unconnected-(U3C-MGTXRXN1_115-PadE3)")
	(net 321 "unconnected-(U3C-MGTXRXP1_115-PadE4)")
	(net 322 "unconnected-(U3F-IO_L12P_T1_MRCC_16-PadE11)")
	(net 323 "unconnected-(U3F-IO_L10N_T1_16-PadE12)")
	(net 324 "unconnected-(U3F-IO_L10P_T1_16-PadE13)")
	(net 325 "unconnected-(U3G-IO_L6P_T0_15-PadE14)")
	(net 326 "unconnected-(U3G-IO_L13N_T2_MRCC_15-PadE18)")
	(net 327 "unconnected-(U3G-IO_L17N_T2_A25_15-PadE19)")
	(net 328 "unconnected-(U3H-IO_L7P_T1_D09_14-PadE21)")
	(net 329 "unconnected-(U3H-IO_L7N_T1_D10_14-PadE22)")
	(net 330 "unconnected-(U3C-MGTXTXN0_115-PadF1)")
	(net 331 "unconnected-(U3C-MGTXTXP0_115-PadF2)")
	(net 332 "DQ11_A")
	(net 333 "DQ10_A")
	(net 334 "DQ09_A")
	(net 335 "DQ08_A")
	(net 336 "DMI_1A")
	(net 337 "unconnected-(U3C-MGTREFCLK1N_115-PadF5)")
	(net 338 "DQ15_A")
	(net 339 "DQ14_A")
	(net 340 "DQ13_A")
	(net 341 "DQ12_A")
	(net 342 "unconnected-(U3C-MGTREFCLK1P_115-PadF6)")
	(net 343 "DQ04_A")
	(net 344 "DQ05_A")
	(net 345 "DQ06_A")
	(net 346 "DQ07_A")
	(net 347 "DMI_0A")
	(net 348 "DQ03_A")
	(net 349 "DQ02_A")
	(net 350 "DQ01_A")
	(net 351 "DQ00_A")
	(net 352 "CK_A_N")
	(net 353 "CK_A_P")
	(net 354 "unconnected-(U3F-IO_L11N_T1_SRCC_16-PadF10)")
	(net 355 "unconnected-(U3F-IO_L11P_T1_SRCC_16-PadF11)")
	(net 356 "unconnected-(U3F-IO_L8N_T1_16-PadF13)")
	(net 357 "unconnected-(U3F-IO_6_T0_VREF_16-PadF14)")
	(net 358 "unconnected-(U3G-IO_L3P_T0_DQS_AD1P_15-PadF15)")
	(net 359 "unconnected-(U3G-IO_L3N_T0_DQS_AD1N_15-PadF16)")
	(net 360 "unconnected-(U3G-IO_L17P_T2_A26_15-PadF18)")
	(net 361 "unconnected-(U3H-IO_L4N_T0_D05_14-PadF20)")
	(net 362 "unconnected-(U3H-IO_L9N_T1_DQS_D13_14-PadF21)")
	(net 363 "unconnected-(U3C-MGTXRXN0_115-PadG3)")
	(net 364 "unconnected-(U3C-MGTXRXP0_115-PadG4)")
	(net 365 "unconnected-(U3F-IO_L17P_T2_16-PadG8)")
	(net 366 "unconnected-(U3F-IO_L13N_T2_MRCC_16-PadG10)")
	(net 367 "unconnected-(U3F-IO_L13P_T2_MRCC_16-PadG11)")
	(net 368 "unconnected-(U3F-IO_L14N_T2_SRCC_16-PadG12)")
	(net 369 "unconnected-(U3F-IO_L8P_T1_16-PadG13)")
	(net 370 "unconnected-(U3G-IO_L1P_T0_AD0P_15-PadG15)")
	(net 371 "unconnected-(U3G-IO_L1N_T0_AD0N_15-PadG16)")
	(net 372 "unconnected-(U3G-IO_L15N_T2_DQS_ADV_B_15-PadG17)")
	(net 373 "unconnected-(U3H-IO_L4P_T0_D04_14-PadG20)")
	(net 374 "unconnected-(U3H-IO_L9P_T1_DQS_14-PadG21)")
	(net 375 "unconnected-(U3H-IO_L8N_T1_D12_14-PadG22)")
	(net 376 "unconnected-(U3A-MGTAVTTRCAL_115-PadH1)")
	(net 377 "unconnected-(U3A-MGTRREF_115-PadH2)")
	(net 378 "unconnected-(U3F-IO_L16N_T2_16-PadH8)")
	(net 379 "unconnected-(U3F-IO_L16P_T2_16-PadH9)")
	(net 380 "unconnected-(U3F-IO_18_T2_16-PadH10)")
	(net 381 "unconnected-(U3F-IO_L14P_T2_SRCC_16-PadH12)")
	(net 382 "unconnected-(U3F-IO_L9N_T1_DQS_16-PadH13)")
	(net 383 "unconnected-(U3F-IO_L9P_T1_DQS_16-PadH14)")
	(net 384 "unconnected-(U3G-IO_25_15-PadH15)")
	(net 385 "unconnected-(U3G-IO_L15P_T2_DQS_15-PadH17)")
	(net 386 "unconnected-(U3H-IO_L11N_T1_SRCC_14-PadH20)")
	(net 387 "unconnected-(U3H-IO_L8P_T1_D11_14-PadH22)")
	(net 388 "unconnected-(U3A-MGTVCCAUX-PadJ4)")
	(net 389 "unconnected-(U3G-IO_L16P_T2_A28_15-PadJ16)")
	(net 390 "USR_BTN1")
	(net 391 "USR_BTN2")
	(net 392 "USR_BTN3")
	(net 393 "CA_1A")
	(net 394 "CA_0A")
	(net 395 "CS0_A")
	(net 396 "CKE0_A")
	(net 397 "IO_M5")
	(net 398 "IO_W4")
	(net 399 "IO_V4")
	(net 400 "IO_T4")
	(net 401 "IO_R4")
	(net 402 "IO_P4")
	(net 403 "IO_V3")
	(net 404 "IO_U3")
	(net 405 "IO_U5")
	(net 406 "IO_N5")
	(net 407 "IO_K4")
	(net 408 "unconnected-(U3G-IO_L16N_T2_A27_15-PadJ17)")
	(net 409 "unconnected-(U3H-IO_L11P_T1_SRCC_14-PadJ20)")
	(net 410 "unconnected-(U3H-IO_0_14-PadK16)")
	(net 411 "unconnected-(U3H-IO_L6N_T0_D08_VREF_14-PadK17)")
	(net 412 "unconnected-(U3H-IO_L5N_T0_D07_14-PadK19)")
	(net 413 "unconnected-(U3H-IO_L5P_T0_D06_14-PadL18)")
	(net 414 "unconnected-(U3H-IO_L12N_T1_MRCC_14-PadL20)")
	(net 415 "unconnected-(U3H-IO_L18N_T2_A11_D27_14-PadL21)")
	(net 416 "unconnected-(U3H-IO_25_14-PadM16)")
	(net 417 "unconnected-(U3H-IO_L14P_T2_SRCC_14-PadM17)")
	(net 418 "unconnected-(U3H-IO_L14N_T2_SRCC_14-PadM18)")
	(net 419 "unconnected-(U3H-IO_L18P_T2_A12_D28_14-PadM20)")
	(net 420 "unconnected-(U3H-IO_L17N_T2_A13_D29_14-PadM21)")
	(net 421 "unconnected-(U3H-IO_L15N_T2_DQS_DOUT_CSO_B_14-PadM22)")
	(net 422 "unconnected-(U3H-IO_L23N_T3_A02_D18_14-PadN17)")
	(net 423 "unconnected-(U3H-IO_L13P_T2_MRCC_14-PadN18)")
	(net 424 "unconnected-(U3H-IO_L13N_T2_MRCC_14-PadN19)")
	(net 425 "unconnected-(U3H-IO_L17P_T2_A14_D30_14-PadN20)")
	(net 426 "unconnected-(U3H-IO_L15P_T2_DQS_RDWR_B_14-PadN22)")
	(net 427 "unconnected-(U3D-IO_L18N_T2_34-PadP5)")
	(net 428 "unconnected-(U3H-IO_L23P_T3_A03_D19_14-PadP16)")
	(net 429 "unconnected-(U3H-IO_L21N_T3_DQS_A06_D22_14-PadP17)")
	(net 430 "unconnected-(U3H-IO_L20P_T3_A08_D24_14-PadP19)")
	(net 431 "unconnected-(U3H-IO_L20N_T3_A07_D23_14-PadP20)")
	(net 432 "unconnected-(U3D-IO_L12P_T1_MRCC_34-PadR3)")
	(net 433 "unconnected-(U3E-IO_L8N_T1_33-PadR6)")
	(net 434 "unconnected-(U3E-IO_L8P_T1_33-PadR7)")
	(net 435 "unconnected-(U3I-IO_L20P_T3_13-PadR16)")
	(net 436 "USR_BTN4")
	(net 437 "unconnected-(U3H-IO_L21P_T3_DQS_14-PadR17)")
	(net 438 "unconnected-(U3H-IO_L19P_T3_A10_D26_14-PadR18)")
	(net 439 "unconnected-(U3H-IO_L19N_T3_A09_D25_VREF_14-PadR19)")
	(net 440 "unconnected-(U3D-IO_L16P_T2_34-PadT5)")
	(net 441 "unconnected-(U3E-IO_0_VRN_33-PadT6)")
	(net 442 "AUX_JTAG_TCK")
	(net 443 "unconnected-(U3E-IO_L18N_T2_33-PadT8)")
	(net 444 "AUX_JTAG_TDI")
	(net 445 "unconnected-(U3E-IO_L18P_T2_33-PadT9)")
	(net 446 "unconnected-(U3E-IO_L16N_T2_33-PadT10)")
	(net 447 "AUX_JTAG_TMS")
	(net 448 "unconnected-(U3E-IO_L16P_T2_33-PadT11)")
	(net 449 "AUX_JTAG_RST")
	(net 450 "unconnected-(U3E-IO_L24P_T3_33-PadT13)")
	(net 451 "UART0_RX")
	(net 452 "unconnected-(U3E-IO_25_VRP_33-PadT14)")
	(net 453 "UART0_TX")
	(net 454 "unconnected-(U3I-IO_L24P_T3_13-PadT15)")
	(net 455 "UART1_RX")
	(net 456 "unconnected-(U3I-IO_L20N_T3_13-PadT16)")
	(net 457 "UART1_TX")
	(net 458 "unconnected-(U3I-IO_L3P_T0_DQS_13-PadT18)")
	(net 459 "3V3_SYS")
	(net 460 "1V8_SYS")
	(net 461 "1V1_SYS")
	(net 462 "unconnected-(U3I-IO_0_13-PadT19)")
	(net 463 "VCC5V0_INT")
	(net 464 "AUX_JTAG_TDO")
	(net 465 "1V0_SYS")
	(net 466 "SYS_ON")
	(net 467 "unconnected-(U3I-IO_L6P_T0_13-PadT20)")
	(net 468 "/Supply/VCC_INT_EN")
	(net 469 "/Supply/VCC_AUX_EN")
	(net 470 "/Supply/VCC_IO_EN")
	(net 471 "unconnected-(U3I-IO_L1P_T0_13-PadT21)")
	(net 472 "unconnected-(U3E-IO_L10N_T1_33-PadU6)")
	(net 473 "unconnected-(U3E-IO_L10P_T1_33-PadU7)")
	(net 474 "unconnected-(U3E-IO_L9P_T1_DQS_33-PadU8)")
	(net 475 "unconnected-(U3E-IO_L14P_T2_SRCC_33-PadU10)")
	(net 476 "unconnected-(U3E-IO_L17N_T2_33-PadU11)")
	(net 477 "unconnected-(U3E-IO_L24N_T3_33-PadU13)")
	(net 478 "unconnected-(U3I-IO_L24N_T3_13-PadU15)")
	(net 479 "IO_AB11")
	(net 480 "IO_AB10")
	(net 481 "IO_AA11")
	(net 482 "IO_Y11")
	(net 483 "IO_W11")
	(net 484 "IO_Y12")
	(net 485 "IO_W12")
	(net 486 "IO_V12")
	(net 487 "IO_U12")
	(net 488 "HR_RST")
	(net 489 "HR_CS")
	(net 490 "HR_DQ1")
	(net 491 "HR_DQ0")
	(net 492 "HR_RW")
	(net 493 "HR_CKN")
	(net 494 "HR_DQ5")
	(net 495 "HR_DQ4")
	(net 496 "HR_DQ7")
	(net 497 "HR_DQ6")
	(net 498 "HR_CKP")
	(net 499 "HR_DQ3")
	(net 500 "HR_DQ2")
	(net 501 "unconnected-(U3I-IO_L19P_T3_13-PadU16)")
	(net 502 "unconnected-(U3I-IO_L5P_T0_13-PadU17)")
	(net 503 "unconnected-(U3I-IO_L3N_T0_DQS_13-PadU18)")
	(net 504 "unconnected-(U3I-IO_L6N_T0_VREF_13-PadU20)")
	(net 505 "unconnected-(U3I-IO_L1N_T0_13-PadU21)")
	(net 506 "unconnected-(U3I-IO_L2P_T0_13-PadU22)")
	(net 507 "unconnected-(U3E-IO_L11P_T1_SRCC_33-PadV7)")
	(net 508 "unconnected-(U3E-IO_L9N_T1_DQS_33-PadV8)")
	(net 509 "unconnected-(U3E-IO_L14N_T2_SRCC_33-PadV9)")
	(net 510 "VREF_34")
	(net 511 "VRN")
	(net 512 "VRP")
	(net 513 "unconnected-(U3E-IO_L15P_T2_DQS_33-PadV10)")
	(net 514 "/Supply/SYS_EN")
	(net 515 "unconnected-(U3E-IO_L23P_T3_33-PadV13)")
	(net 516 "unconnected-(U3I-IO_25_13-PadV14)")
	(net 517 "unconnected-(U3I-IO_L5N_T0_13-PadV18)")
	(net 518 "unconnected-(U3I-IO_L12P_T1_MRCC_13-PadV19)")
	(net 519 "/Ethernet/ETH3_P")
	(net 520 "/Ethernet/ETH2_P")
	(net 521 "Net-(FB7-Pad1)")
	(net 522 "/Ethernet/ETH1_P")
	(net 523 "/Ethernet/ETH4_P")
	(net 524 "/Ethernet/ETH2_N")
	(net 525 "/Ethernet/ETH1_N")
	(net 526 "/Ethernet/ETH3_N")
	(net 527 "/Ethernet/ETH4_N")
	(net 528 "unconnected-(U3I-IO_L11P_T1_SRCC_13-PadV20)")
	(net 529 "/Ethernet/AVDDL")
	(net 530 "/Ethernet/AVDDL_PLL")
	(net 531 "/Ethernet/AVDDH")
	(net 532 "unconnected-(U3I-IO_L2N_T0_13-PadV22)")
	(net 533 "unconnected-(U3D-IO_L19P_T3_34-PadW5)")
	(net 534 "unconnected-(U3E-IO_L7P_T1_33-PadW6)")
	(net 535 "unconnected-(U3E-IO_L11N_T1_SRCC_33-PadW7)")
	(net 536 "unconnected-(U3E-IO_L13P_T2_MRCC_33-PadW9)")
	(net 537 "unconnected-(U3E-IO_L15N_T2_DQS_33-PadW10)")
	(net 538 "unconnected-(U3I-IO_L21P_T3_DQS_13-PadW16)")
	(net 539 "unconnected-(U3I-IO_L12N_T1_MRCC_13-PadW19)")
	(net 540 "unconnected-(U3E-IO_L7N_T1_33-PadY6)")
	(net 541 "ETH_INT_N")
	(net 542 "unconnected-(U3E-IO_L12N_T1_MRCC_33-PadY7)")
	(net 543 "unconnected-(U3E-IO_L12P_T1_MRCC_33-PadY8)")
	(net 544 "unconnected-(U3E-IO_L13N_T2_MRCC_33-PadY9)")
	(net 545 "unconnected-(U3E-IO_L21P_T3_DQS_33-PadY13)")
	(net 546 "unconnected-(U3I-IO_L13P_T2_MRCC_13-PadY18)")
	(net 547 "unconnected-(U3I-IO_L13N_T2_MRCC_13-PadY19)")
	(net 548 "unconnected-(U3I-IO_L7N_T1_13-PadY22)")
	(net 549 "unconnected-(U4-EECS-Pad1)")
	(net 550 "VDD1V1")
	(net 551 "/Supply/VDD1V8")
	(net 552 "/Supply/1V8_BST")
	(net 553 "Net-(PWR2-Pad2)")
	(net 554 "unconnected-(U4-ADBUS4-Pad17)")
	(net 555 "Net-(PWR3-Pad2)")
	(net 556 "Net-(PWR4-Pad2)")
	(net 557 "Net-(PWR5-Pad2)")
	(net 558 "unconnected-(U4-ADBUS6-Pad19)")
	(net 559 "unconnected-(U4-ADBUS7-Pad20)")
	(net 560 "unconnected-(U4-BDBUS4-Pad26)")
	(net 561 "unconnected-(U4-BDBUS6-Pad28)")
	(net 562 "unconnected-(U4-BDBUS7-Pad29)")
	(net 563 "unconnected-(U4-~{SUSPEND}-Pad30)")
	(net 564 "unconnected-(U4-CDBUS2-Pad34)")
	(net 565 "unconnected-(U4-CDBUS3-Pad35)")
	(net 566 "unconnected-(U4-CDBUS4-Pad37)")
	(net 567 "unconnected-(U4-CDBUS5-Pad38)")
	(net 568 "unconnected-(U4-CDBUS6-Pad39)")
	(net 569 "unconnected-(U4-CDBUS7-Pad40)")
	(net 570 "unconnected-(U4-DDBUS2-Pad47)")
	(net 571 "unconnected-(U4-DDBUS3-Pad48)")
	(net 572 "unconnected-(U4-DDBUS4-Pad49)")
	(net 573 "unconnected-(U4-DDBUS5-Pad51)")
	(net 574 "/Supply/3V3_BST")
	(net 575 "/Supply/3V3_SW")
	(net 576 "/Supply/3V3_REG")
	(net 577 "/Supply/3V3_EN")
	(net 578 "/Supply/3V3_FB")
	(net 579 "/Supply/1V1_SW")
	(net 580 "/Supply/1V1_BST")
	(net 581 "/Supply/1V0_BST")
	(net 582 "/Supply/1V0_SW")
	(net 583 "/Supply/1V8_REG")
	(net 584 "/Supply/1V8_SW")
	(net 585 "/Supply/1V2_BST")
	(net 586 "/Supply/1V2_SW")
	(net 587 "/Supply/1V1_REG")
	(net 588 "/Supply/1V0_REG")
	(net 589 "/Supply/1V2_REG")
	(net 590 "/Supply/1V1_EN")
	(net 591 "/Supply/1V1_VCC_INT")
	(net 592 "/Supply/1V0_EN")
	(net 593 "/Supply/1V0_VCC_INT")
	(net 594 "/Supply/1V8_EN")
	(net 595 "/Supply/1V8_VCC_INT")
	(net 596 "/Supply/1V2_EN")
	(net 597 "/Supply/1V2_VCC_INT")
	(net 598 "/Supply/1V1_FB")
	(net 599 "/Supply/1V0_FB")
	(net 600 "/Supply/1V8_FB")
	(net 601 "/Supply/1V2_FB")
	(net 602 "1V2_SYS")
	(net 603 "unconnected-(J8-Pad2)")
	(net 604 "unconnected-(U4-DDBUS6-Pad52)")
	(net 605 "/Supply/1V8_PG")
	(net 606 "unconnected-(U4-DDBUS7-Pad53)")
	(net 607 "unconnected-(U4-~{PWR_{EN}}-Pad54)")
	(net 608 "unconnected-(U4-EEDATA-Pad55)")
	(net 609 "/Supply/3V3_VCC_INT")
	(net 610 "/Supply/3V3_FSEL")
	(net 611 "/Supply/1V0_FSEL")
	(net 612 "/Supply/1V0_MODE")
	(net 613 "/Supply/1V0_SS{slash}TR")
	(net 614 "/Supply/1V8_FSEL")
	(net 615 "/Supply/1V1_FSEL")
	(net 616 "/Supply/1V2_FSEL")
	(net 617 "/Supply/3V3_MODE")
	(net 618 "/Supply/3V3_SS{slash}TR")
	(net 619 "/Supply/1V8_MODE")
	(net 620 "/Supply/1V8_SS{slash}TR")
	(net 621 "/Supply/1V1_MODE")
	(net 622 "/Supply/1V1_SS{slash}TR")
	(net 623 "/Supply/1V2_MODE")
	(net 624 "/Supply/1V2_SS{slash}TR")
	(net 625 "/Supply/VDD2_SW")
	(net 626 "/Supply/VDDQ_REF")
	(net 627 "/Supply/VDDQ_0V6")
	(net 628 "/Supply/VDD1_SW")
	(net 629 "/Supply/VDD2_BST")
	(net 630 "/Supply/LPDDR4_PGOOD")
	(net 631 "/Supply/VDDQ_SNS")
	(net 632 "Net-(PWR6-Pad2)")
	(net 633 "/Supply/0V6_REG")
	(net 634 "unconnected-(U4-EECLK-Pad56)")
	(net 635 "/Supply/0V6_FB")
	(net 636 "/Supply/0V6_EN")
	(net 637 "unconnected-(U5-EP-Pad9)")
	(net 638 "unconnected-(U6-NC-Pad13)")
	(net 639 "/Supply/0V6_CP")
	(net 640 "0V6_DDR")
	(net 641 "1V8_DDR")
	(net 642 "unconnected-(U6-LDO_O-Pad43)")
	(net 643 "FPGA_AB22_BALL")
	(net 644 "FPGA_AB21_BALL")
	(net 645 "unconnected-(U6-NC-Pad47)")
	(net 646 "FPGA_AA21_BALL")
	(net 647 "unconnected-(U8-PG-Pad6)")
	(net 648 "DQ_S1_N")
	(net 649 "DQ_S1_P")
	(net 650 "DQ_S0_N")
	(net 651 "DQ_S0_P")
	(net 652 "/Interfaces/VPLL")
	(net 653 "/Interfaces/VPHY")
	(net 654 "unconnected-(U10-PG-Pad6)")
	(net 655 "unconnected-(U11-PG-Pad6)")
	(net 656 "ETH_XO")
	(net 657 "ETH_XI")
	(net 658 "unconnected-(U12-PG-Pad6)")
	(net 659 "Net-(C191-Pad1)")
	(net 660 "/Supply/5V0_FB")
	(net 661 "unconnected-(U14-NC-Pad5)")
	(net 662 "unconnected-(U14-NC-Pad6)")
	(net 663 "/Interfaces/C_TMDS_CLK_N")
	(net 664 "/Interfaces/C_TMDS_CLK_P")
	(net 665 "/Interfaces/C_TMDS_D0_N")
	(net 666 "/Interfaces/C_TMDS_D0_P")
	(net 667 "/Interfaces/C_TMDS_D1_N")
	(net 668 "/Interfaces/C_TMDS_D1_P")
	(net 669 "/Interfaces/C_TMDS_D2_N")
	(net 670 "/Interfaces/C_TMDS_D2_P")
	(footprint "antmicro-footprints:C_0402_1005Metric"
		(layer "F.Cu")
		(at 180.1885 115.731 180)
		(descr "Capacitor SMD 0402")
		(tags "capacitor SMD 0402")
		(property "Reference" "C22"
			(at -0.8115 -0.369 180)
			(layer "F.SilkS")
			(effects
				(font
					(size 0.7 0.7)
					(thickness 0.15)
				)
				(justify left bottom)
			)
		)
		(property "Value" "C_100n_6V3_0402"
			(at 0 1.4 180)
			(layer "F.Fab")
			(effects
				(font
					(size 0.7 0.7)
					(thickness 0.15)
				)
				(justify left bottom)
			)
		)
		(property "Description" " "
			(at 0 0 180)
			(layer "F.Fab")
			(hide yes)
			(effects
				(font
					(size 1.27 1.27)
					(thickness 0.15)
				)
			)
		)
		(property "Author" "Antmicro"
			(at 360.377 231.462 0)
			(layer "F.Fab")
			(hide yes)
			(effects
				(font
					(size 1 1)
					(thickness 0.15)
				)
			)
		)
		(property "Dielectric" ""
			(at 360.377 231.462 0)
			(layer "F.Fab")
			(hide yes)
			(effects
				(font
					(size 1 1)
					(thickness 0.15)
				)
			)
		)
		(property "License" "Apache-2.0"
			(at 360.377 231.462 0)
			(layer "F.Fab")
			(hide yes)
			(effects
				(font
					(size 1 1)
					(thickness 0.15)
				)
			)
		)
		(property "MPN" "0402X104K6R3CT"
			(at 360.377 231.462 0)
			(layer "F.Fab")
			(hide yes)
			(effects
				(font
					(size 1 1)
					(thickness 0.15)
				)
			)
		)
		(property "Manufacturer" "Walsin"
			(at 360.377 231.462 0)
			(layer "F.Fab")
			(hide yes)
			(effects
				(font
					(size 1 1)
					(thickness 0.15)
				)
			)
		)
		(property "Val" "100n"
			(at 360.377 231.462 0)
			(layer "F.Fab")
			(hide yes)
			(effects
				(font
					(size 1 1)
					(thickness 0.15)
				)
			)
		)
		(property "Voltage" ""
			(at 360.377 231.462 0)
			(layer "F.Fab")
			(hide yes)
			(effects
				(font
					(size 1 1)
					(thickness 0.15)
				)
			)
		)
		(sheetname "Config SPI flash")
		(sheetfile "config-spi.kicad_sch")
		(attr smd)
		(fp_rect
			(start -0.94 -0.47)
			(end 0.94 0.47)
			(stroke
				(width 0.05)
				(type solid)
			)
			(fill no)
			(layer "F.CrtYd")
		)
		(fp_rect
			(start -0.499 -0.249)
			(end 0.499 0.249)
			(stroke
				(width 0.15)
				(type solid)
			)
			(fill no)
			(layer "F.Fab")
		)
		(pad "1" smd roundrect
			(at -0.484 0 180)
			(size 0.59 0.64)
			(layers "F.Cu" "F.Mask" "F.Paste")
			(roundrect_rratio 0.25)
			(net 5 "GND")
			(pintype "passive")
		)
		(pad "2" smd roundrect
			(at 0.484 0 180)
			(size 0.59 0.64)
			(layers "F.Cu" "F.Mask" "F.Paste")
			(roundrect_rratio 0.25)
			(net 459 "3V3_SYS")
			(pintype "passive")
		)
	)
	(footprint "antmicro-footprints:R_0402_1005Metric"
		(layer "F.Cu")
		(at 157.094 113.05 -90)
		(descr "Resistor SMD 0402")
		(tags "resistor SMD 0402")
		(property "Reference" "R43"
			(at -0.835 -0.416 270)
			(layer "F.SilkS")
			(effects
				(font
					(size 0.7 0.7)
					(thickness 0.15)
				)
				(justify left bottom)
			)
		)
		(property "Value" "R_0R_0402"
			(at 0 1.4 270)
			(layer "F.Fab")
			(effects
				(font
					(size 0.7 0.7)
					(thickness 0.15)
				)
				(justify left bottom)
			)
		)
		(property "Description" "0R resistor in 0402 package with unspecified tolerance"
			(at 0 0 270)
			(layer "F.Fab")
			(hide yes)
			(effects
				(font
					(size 1.27 1.27)
					(thickness 0.15)
				)
			)
		)
		(property "Author" "Antmicro"
			(at 44.044 270.144 0)
			(layer "F.Fab")
			(hide yes)
			(effects
				(font
					(size 1 1)
					(thickness 0.15)
				)
			)
		)
		(property "Current" "1A"
			(at 44.044 270.144 0)
			(layer "F.Fab")
			(hide yes)
			(effects
				(font
					(size 1 1)
					(thickness 0.15)
				)
			)
		)
		(property "License" "Apache-2.0"
			(at 44.044 270.144 0)
			(layer "F.Fab")
			(hide yes)
			(effects
				(font
					(size 1 1)
					(thickness 0.15)
				)
			)
		)
		(property "MPN" "ERJ2GE0R00X"
			(at 44.044 270.144 0)
			(layer "F.Fab")
			(hide yes)
			(effects
				(font
					(size 1 1)
					(thickness 0.15)
				)
			)
		)
		(property "Manufacturer" "Panasonic"
			(at 44.044 270.144 0)
			(layer "F.Fab")
			(hide yes)
			(effects
				(font
					(size 1 1)
					(thickness 0.15)
				)
			)
		)
		(property "Tolerance" ""
			(at 44.044 270.144 0)
			(layer "F.Fab")
			(hide yes)
			(effects
				(font
					(size 1 1)
					(thickness 0.15)
				)
			)
		)
		(property "Val" "0R"
			(at 44.044 270.144 0)
			(layer "F.Fab")
			(hide yes)
			(effects
				(font
					(size 1 1)
					(thickness 0.15)
				)
			)
		)
		(sheetname "Interfaces")
		(sheetfile "interfaces.kicad_sch")
		(attr smd)
		(fp_rect
			(start -0.93 -0.47)
			(end 0.93 0.47)
			(stroke
				(width 0.05)
				(type solid)
			)
			(fill no)
			(layer "F.CrtYd")
		)
		(fp_rect
			(start -0.5 -0.25)
			(end 0.5 0.25)
			(stroke
				(width 0.15)
				(type solid)
			)
			(fill no)
			(layer "F.Fab")
		)
		(pad "1" smd roundrect
			(at -0.485 0 270)
			(size 0.59 0.64)
			(layers "F.Cu" "F.Mask" "F.Paste")
			(roundrect_rratio 0.25)
			(net 49 "TMDS_D1_N")
			(pintype "passive")
		)
		(pad "2" smd roundrect
			(at 0.485 0 270)
			(size 0.59 0.64)
			(layers "F.Cu" "F.Mask" "F.Paste")
			(roundrect_rratio 0.25)
			(net 667 "/Interfaces/C_TMDS_D1_N")
			(pintype "passive")
		)
	)
	(footprint "antmicro-footprints:Bus_DDR4_SODIMM_TE_2309409"
		(layer "F.Cu")
		(at 150.411328 66.671157 180)
		(descr "260 pin DDR4 SODIMM Right Angle Socket, 5.2 mm (0.205 in) Stack Height, https://www.te.com/usa-en/product-2309409-1.html")
		(property "Reference" "J9"
			(at -36.726 -13.477 180)
			(layer "F.SilkS")
			(effects
				(font
					(size 0.7 0.7)
					(thickness 0.15)
				)
				(justify left bottom)
			)
		)
		(property "Value" "Bus_DDR4_SODIMM_TE_2309409"
			(at -8.1 -7.7 180)
			(layer "F.Fab")
			(effects
				(font
					(size 0.7 0.7)
					(thickness 0.15)
				)
				(justify left bottom)
			)
		)
		(property "Description" "Memory Card Connector, DDR4, SODIMM, Cam-In Locking, 260 Contacts, Copper Alloy"
			(at 0 0 180)
			(layer "F.Fab")
			(hide yes)
			(effects
				(font
					(size 1.27 1.27)
					(thickness 0.15)
				)
			)
		)
		(property "Author" "Antmicro"
			(at 300.822656 133.342314 0)
			(layer "F.Fab")
			(hide yes)
			(effects
				(font
					(size 1 1)
					(thickness 0.15)
				)
			)
		)
		(property "License" "Apache-2.0"
			(at 300.822656 133.342314 0)
			(layer "F.Fab")
			(hide yes)
			(effects
				(font
					(size 1 1)
					(thickness 0.15)
				)
			)
		)
		(property "MPN" "2309409-1"
			(at 300.822656 133.342314 0)
			(layer "F.Fab")
			(hide yes)
			(effects
				(font
					(size 1 1)
					(thickness 0.15)
				)
			)
		)
		(property "Manufacturer" "TE Connectivity"
			(at 300.822656 133.342314 0)
			(layer "F.Fab")
			(hide yes)
			(effects
				(font
					(size 1 1)
					(thickness 0.15)
				)
			)
		)
		(sheetname "SO-DIMM")
		(sheetfile "sodimm.kicad_sch")
		(attr smd)
		(fp_line
			(start 36.499 12.774)
			(end 33.228 12.774)
			(stroke
				(width 0.15)
				(type solid)
			)
			(layer "F.SilkS")
		)
		(fp_line
			(start 36.499 -13.077)
			(end 36.499 12.774)
			(stroke
				(width 0.15)
				(type solid)
			)
			(layer "F.SilkS")
		)
		(fp_line
			(start 33.899 -11.978)
			(end 33.899 -13.077)
			(stroke
				(width 0.15)
				(type solid)
			)
			(layer "F.SilkS")
		)
		(fp_line
			(start 33.899 -13.077)
			(end 36.499 -13.077)
			(stroke
				(width 0.15)
				(type solid)
			)
			(layer "F.SilkS")
		)
		(fp_line
			(start 33.228 12.774)
			(end 33.228 6.544)
			(stroke
				(width 0.15)
				(type solid)
			)
			(layer "F.SilkS")
		)
		(fp_line
			(start -33.232 12.774)
			(end -33.232 6.544)
			(stroke
				(width 0.15)
				(type solid)
			)
			(layer "F.SilkS")
		)
		(fp_line
			(start -33.902 -11.978)
			(end -33.902 -13.077)
			(stroke
				(width 0.15)
				(type solid)
			)
			(layer "F.SilkS")
		)
		(fp_line
			(start -33.902 -13.077)
			(end -36.5 -13.077)
			(stroke
				(width 0.15)
				(type solid)
			)
			(layer "F.SilkS")
		)
		(fp_line
			(start -36.5 12.774)
			(end -33.232 12.774)
			(stroke
				(width 0.15)
				(type solid)
			)
			(layer "F.SilkS")
		)
		(fp_line
			(start -36.5 -13.077)
			(end -36.5 12.774)
			(stroke
				(width 0.15)
				(type solid)
			)
			(layer "F.SilkS")
		)
		(fp_circle
			(center 33.374 -13.375)
			(end 33.424 -13.375)
			(stroke
				(width 0.15)
				(type solid)
			)
			(fill yes)
			(layer "F.SilkS")
		)
		(fp_line
			(start 39.23 13)
			(end 31.78 13)
			(stroke
				(width 0.05)
				(type solid)
			)
			(layer "F.CrtYd")
		)
		(fp_line
			(start 39.23 -13.34)
			(end 39.23 13)
			(stroke
				(width 0.05)
				(type solid)
			)
			(layer "F.CrtYd")
		)
		(fp_line
			(start 31.78 13)
			(end 31.78 -2.86)
			(stroke
				(width 0.05)
				(type solid)
			)
			(layer "F.CrtYd")
		)
		(fp_line
			(start 31.78 -2.86)
			(end -31.82 -2.86)
			(stroke
				(width 0.05)
				(type solid)
			)
			(layer "F.CrtYd")
		)
		(fp_line
			(start -31.82 13)
			(end -39.26 13)
			(stroke
				(width 0.05)
				(type solid)
			)
			(layer "F.CrtYd")
		)
		(fp_line
			(start -31.82 -2.86)
			(end -31.82 13)
			(stroke
				(width 0.05)
				(type solid)
			)
			(layer "F.CrtYd")
		)
		(fp_line
			(start -39.26 13)
			(end -39.26 -13.34)
			(stroke
				(width 0.05)
				(type solid)
			)
			(layer "F.CrtYd")
		)
		(fp_line
			(start -39.26 -13.34)
			(end 39.23 -13.34)
			(stroke
				(width 0.05)
				(type solid)
			)
			(layer "F.CrtYd")
		)
		(fp_line
			(start 36.499 12.774)
			(end 36.499 -13.077)
			(stroke
				(width 0.15)
				(type solid)
			)
			(layer "F.Fab")
		)
		(fp_line
			(start 33.899 -11.978)
			(end 33.899 -13.077)
			(stroke
				(width 0.15)
				(type solid)
			)
			(layer "F.Fab")
		)
		(fp_line
			(start 33.899 -13.077)
			(end 36.499 -13.077)
			(stroke
				(width 0.15)
				(type solid)
			)
			(layer "F.Fab")
		)
		(fp_line
			(start 33.228 12.774)
			(end 36.499 12.774)
			(stroke
				(width 0.15)
				(type solid)
			)
			(layer "F.Fab")
		)
		(fp_line
			(start 33.228 -4.178)
			(end 33.228 12.774)
			(stroke
				(width 0.15)
				(type solid)
			)
			(layer "F.Fab")
		)
		(fp_line
			(start -33.232 12.774)
			(end -33.232 -4.178)
			(stroke
				(width 0.15)
				(type solid)
			)
			(layer "F.Fab")
		)
		(fp_line
			(start -33.232 -4.178)
			(end 33.228 -4.178)
			(stroke
				(width 0.15)
				(type solid)
			)
			(layer "F.Fab")
		)
		(fp_line
			(start -33.902 -11.978)
			(end 33.899 -11.978)
			(stroke
				(width 0.15)
				(type solid)
			)
			(layer "F.Fab")
		)
		(fp_line
			(start -33.902 -13.077)
			(end -33.902 -11.978)
			(stroke
				(width 0.15)
				(type solid)
			)
			(layer "F.Fab")
		)
		(fp_line
			(start -36.5 12.774)
			(end -33.232 12.774)
			(stroke
				(width 0.15)
				(type solid)
			)
			(layer "F.Fab")
		)
		(fp_line
			(start -36.5 -13.077)
			(end -33.902 -13.077)
			(stroke
				(width 0.15)
				(type solid)
			)
			(layer "F.Fab")
		)
		(fp_line
			(start -36.5 -13.077)
			(end -36.5 12.774)
			(stroke
				(width 0.15)
				(type solid)
			)
			(layer "F.Fab")
		)
		(fp_circle
			(center 33.374 -12.875)
			(end 33.424 -12.875)
			(stroke
				(width 0.15)
				(type solid)
			)
			(fill no)
			(layer "F.Fab")
		)
		(pad "" np_thru_hole circle
			(at -34.402 -8.077 180)
			(size 1.15 1.15)
			(drill 1.15)
			(layers "*.Cu" "*.Mask")
		)
		(pad "" np_thru_hole circle
			(at 34.399 -8.077 180)
			(size 1.65 1.65)
			(drill 1.65)
			(layers "*.Cu" "*.Mask")
		)
		(pad "1" smd rect
			(at 33.374 -12.176 180)
			(size 0.3 1.75)
			(layers "F.Cu" "F.Mask" "F.Paste")
			(net 5 "GND")
			(pinfunction "1")
			(pintype "passive")
		)
		(pad "2" smd rect
			(at 33.124 -3.979 180)
			(size 0.3 1.75)
			(layers "F.Cu" "F.Mask" "F.Paste")
			(net 5 "GND")
			(pinfunction "2")
			(pintype "passive")
		)
		(pad "3" smd rect
			(at 32.874 -12.176 180)
			(size 0.3 1.75)
			(layers "F.Cu" "F.Mask" "F.Paste")
			(net 5 "GND")
			(pinfunction "3")
			(pintype "passive")
		)
		(pad "4" smd rect
			(at 32.624 -3.979 180)
			(size 0.3 1.75)
			(layers "F.Cu" "F.Mask" "F.Paste")
			(net 5 "GND")
			(pinfunction "4")
			(pintype "passive")
		)
		(pad "5" smd rect
			(at 32.374 -12.176 180)
			(size 0.3 1.75)
			(layers "F.Cu" "F.Mask" "F.Paste")
			(net 5 "GND")
			(pinfunction "5")
			(pintype "passive")
		)
		(pad "6" smd rect
			(at 32.124 -3.979 180)
			(size 0.3 1.75)
			(layers "F.Cu" "F.Mask" "F.Paste")
			(net 5 "GND")
			(pinfunction "6")
			(pintype "passive")
		)
		(pad "7" smd rect
			(at 31.874 -12.176 180)
			(size 0.3 1.75)
			(layers "F.Cu" "F.Mask" "F.Paste")
			(net 5 "GND")
			(pinfunction "7")
			(pintype "passive")
		)
		(pad "8" smd rect
			(at 31.624 -3.979 180)
			(size 0.3 1.75)
			(layers "F.Cu" "F.Mask" "F.Paste")
			(net 5 "GND")
			(pinfunction "8")
			(pintype "passive")
		)
		(pad "9" smd rect
			(at 31.374 -12.176 180)
			(size 0.3 1.75)
			(layers "F.Cu" "F.Mask" "F.Paste")
			(net 5 "GND")
			(pinfunction "9")
			(pintype "passive")
		)
		(pad "10" smd rect
			(at 31.124 -3.979 180)
			(size 0.3 1.75)
			(layers "F.Cu" "F.Mask" "F.Paste")
			(net 5 "GND")
			(pinfunction "10")
			(pintype "passive")
		)
		(pad "11" smd rect
			(at 30.874 -12.176 180)
			(size 0.3 1.75)
			(layers "F.Cu" "F.Mask" "F.Paste")
			(net 5 "GND")
			(pinfunction "11")
			(pintype "passive")
		)
		(pad "12" smd rect
			(at 30.624 -3.979 180)
			(size 0.3 1.75)
			(layers "F.Cu" "F.Mask" "F.Paste")
			(net 5 "GND")
			(pinfunction "12")
			(pintype "passive")
		)
		(pad "13" smd rect
			(at 30.374 -12.176 180)
			(size 0.3 1.75)
			(layers "F.Cu" "F.Mask" "F.Paste")
			(net 5 "GND")
			(pinfunction "13")
			(pintype "passive")
		)
		(pad "14" smd rect
			(at 30.124 -3.979 180)
			(size 0.3 1.75)
			(layers "F.Cu" "F.Mask" "F.Paste")
			(net 5 "GND")
			(pinfunction "14")
			(pintype "passive")
		)
		(pad "15" smd rect
			(at 29.874 -12.176 180)
			(size 0.3 1.75)
			(layers "F.Cu" "F.Mask" "F.Paste")
			(net 5 "GND")
			(pinfunction "15")
			(pintype "passive")
		)
		(pad "16" smd rect
			(at 29.624 -3.979 180)
			(size 0.3 1.75)
			(layers "F.Cu" "F.Mask" "F.Paste")
			(net 5 "GND")
			(pinfunction "16")
			(pintype "passive")
		)
		(pad "17" smd rect
			(at 29.374 -12.176 180)
			(size 0.3 1.75)
			(layers "F.Cu" "F.Mask" "F.Paste")
			(net 5 "GND")
			(pinfunction "17")
			(pintype "passive")
		)
		(pad "18" smd rect
			(at 29.124 -3.979 180)
			(size 0.3 1.75)
			(layers "F.Cu" "F.Mask" "F.Paste")
			(net 5 "GND")
			(pinfunction "18")
			(pintype "passive")
		)
		(pad "19" smd rect
			(at 28.874 -12.176 180)
			(size 0.3 1.75)
			(layers "F.Cu" "F.Mask" "F.Paste")
			(net 5 "GND")
			(pinfunction "19")
			(pintype "passive")
		)
		(pad "20" smd rect
			(at 28.624 -3.979 180)
			(size 0.3 1.75)
			(layers "F.Cu" "F.Mask" "F.Paste")
			(net 5 "GND")
			(pinfunction "20")
			(pintype "passive")
		)
		(pad "21" smd rect
			(at 28.374 -12.176 180)
			(size 0.3 1.75)
			(layers "F.Cu" "F.Mask" "F.Paste")
			(net 5 "GND")
			(pinfunction "21")
			(pintype "passive")
		)
		(pad "22" smd rect
			(at 28.124 -3.979 180)
			(size 0.3 1.75)
			(layers "F.Cu" "F.Mask" "F.Paste")
			(net 5 "GND")
			(pinfunction "22")
			(pintype "passive")
		)
		(pad "23" smd rect
			(at 27.874 -12.176 180)
			(size 0.3 1.75)
			(layers "F.Cu" "F.Mask" "F.Paste")
			(net 5 "GND")
			(pinfunction "23")
			(pintype "passive")
		)
		(pad "24" smd rect
			(at 27.624 -3.979 180)
			(size 0.3 1.75)
			(layers "F.Cu" "F.Mask" "F.Paste")
			(net 5 "GND")
			(pinfunction "24")
			(pintype "passive")
		)
		(pad "25" smd rect
			(at 27.374 -12.176 180)
			(size 0.3 1.75)
			(layers "F.Cu" "F.Mask" "F.Paste")
			(net 5 "GND")
			(pinfunction "25")
			(pintype "passive")
		)
		(pad "26" smd rect
			(at 27.124 -3.979 180)
			(size 0.3 1.75)
			(layers "F.Cu" "F.Mask" "F.Paste")
			(net 5 "GND")
			(pinfunction "26")
			(pintype "passive")
		)
		(pad "27" smd rect
			(at 26.874 -12.176 180)
			(size 0.3 1.75)
			(layers "F.Cu" "F.Mask" "F.Paste")
			(net 5 "GND")
			(pinfunction "27")
			(pintype "passive")
		)
		(pad "28" smd rect
			(at 26.624 -3.979 180)
			(size 0.3 1.75)
			(layers "F.Cu" "F.Mask" "F.Paste")
			(net 5 "GND")
			(pinfunction "28")
			(pintype "passive")
		)
		(pad "29" smd rect
			(at 26.374 -12.176 180)
			(size 0.3 1.75)
			(layers "F.Cu" "F.Mask" "F.Paste")
			(net 5 "GND")
			(pinfunction "29")
			(pintype "passive")
		)
		(pad "30" smd rect
			(at 26.124 -3.979 180)
			(size 0.3 1.75)
			(layers "F.Cu" "F.Mask" "F.Paste")
			(net 5 "GND")
			(pinfunction "30")
			(pintype "passive")
		)
		(pad "31" smd rect
			(at 25.874 -12.176 180)
			(size 0.3 1.75)
			(layers "F.Cu" "F.Mask" "F.Paste")
			(net 5 "GND")
			(pinfunction "31")
			(pintype "passive")
		)
		(pad "32" smd rect
			(at 25.624 -3.979 180)
			(size 0.3 1.75)
			(layers "F.Cu" "F.Mask" "F.Paste")
			(net 5 "GND")
			(pinfunction "32")
			(pintype "passive")
		)
		(pad "33" smd rect
			(at 25.374 -12.176 180)
			(size 0.3 1.75)
			(layers "F.Cu" "F.Mask" "F.Paste")
			(net 5 "GND")
			(pinfunction "33")
			(pintype "passive")
		)
		(pad "34" smd rect
			(at 25.124 -3.979 180)
			(size 0.3 1.75)
			(layers "F.Cu" "F.Mask" "F.Paste")
			(net 5 "GND")
			(pinfunction "34")
			(pintype "passive")
		)
		(pad "35" smd rect
			(at 24.874 -12.176 180)
			(size 0.3 1.75)
			(layers "F.Cu" "F.Mask" "F.Paste")
			(net 5 "GND")
			(pinfunction "35")
			(pintype "passive")
		)
		(pad "36" smd rect
			(at 24.624 -3.979 180)
			(size 0.3 1.75)
			(layers "F.Cu" "F.Mask" "F.Paste")
			(net 5 "GND")
			(pinfunction "36")
			(pintype "passive")
		)
		(pad "37" smd rect
			(at 24.374 -12.176 180)
			(size 0.3 1.75)
			(layers "F.Cu" "F.Mask" "F.Paste")
			(net 5 "GND")
			(pinfunction "37")
			(pintype "passive")
		)
		(pad "38" smd rect
			(at 24.124 -3.979 180)
			(size 0.3 1.75)
			(layers "F.Cu" "F.Mask" "F.Paste")
			(net 5 "GND")
			(pinfunction "38")
			(pintype "passive")
		)
		(pad "39" smd rect
			(at 23.874 -12.176 180)
			(size 0.3 1.75)
			(layers "F.Cu" "F.Mask" "F.Paste")
			(net 5 "GND")
			(pinfunction "39")
			(pintype "passive")
		)
		(pad "40" smd rect
			(at 23.624 -3.979 180)
			(size 0.3 1.75)
			(layers "F.Cu" "F.Mask" "F.Paste")
			(net 5 "GND")
			(pinfunction "40")
			(pintype "passive")
		)
		(pad "41" smd rect
			(at 23.374 -12.176 180)
			(size 0.3 1.75)
			(layers "F.Cu" "F.Mask" "F.Paste")
			(net 5 "GND")
			(pinfunction "41")
			(pintype "passive")
		)
		(pad "42" smd rect
			(at 23.124 -3.979 180)
			(size 0.3 1.75)
			(layers "F.Cu" "F.Mask" "F.Paste")
			(net 5 "GND")
			(pinfunction "42")
			(pintype "passive")
		)
		(pad "43" smd rect
			(at 22.874 -12.176 180)
			(size 0.3 1.75)
			(layers "F.Cu" "F.Mask" "F.Paste")
			(net 5 "GND")
			(pinfunction "43")
			(pintype "passive")
		)
		(pad "44" smd rect
			(at 22.624 -3.979 180)
			(size 0.3 1.75)
			(layers "F.Cu" "F.Mask" "F.Paste")
			(net 5 "GND")
			(pinfunction "44")
			(pintype "passive")
		)
		(pad "45" smd rect
			(at 22.374 -12.176 180)
			(size 0.3 1.75)
			(layers "F.Cu" "F.Mask" "F.Paste")
			(net 5 "GND")
			(pinfunction "45")
			(pintype "passive")
		)
		(pad "46" smd rect
			(at 22.124 -3.979 180)
			(size 0.3 1.75)
			(layers "F.Cu" "F.Mask" "F.Paste")
			(net 5 "GND")
			(pinfunction "46")
			(pintype "passive")
		)
		(pad "47" smd rect
			(at 21.874 -12.176 180)
			(size 0.3 1.75)
			(layers "F.Cu" "F.Mask" "F.Paste")
			(net 5 "GND")
			(pinfunction "47")
			(pintype "passive")
		)
		(pad "48" smd rect
			(at 21.624 -3.979 180)
			(size 0.3 1.75)
			(layers "F.Cu" "F.Mask" "F.Paste")
			(net 5 "GND")
			(pinfunction "48")
			(pintype "passive")
		)
		(pad "49" smd rect
			(at 21.374 -12.176 180)
			(size 0.3 1.75)
			(layers "F.Cu" "F.Mask" "F.Paste")
			(net 5 "GND")
			(pinfunction "49")
			(pintype "passive")
		)
		(pad "50" smd rect
			(at 21.124 -3.979 180)
			(size 0.3 1.75)
			(layers "F.Cu" "F.Mask" "F.Paste")
			(net 5 "GND")
			(pinfunction "50")
			(pintype "passive")
		)
		(pad "51" smd rect
			(at 20.874 -12.176 180)
			(size 0.3 1.75)
			(layers "F.Cu" "F.Mask" "F.Paste")
			(net 91 "unconnected-(J9-Pad51)")
			(pinfunction "51")
			(pintype "passive+no_connect")
		)
		(pad "52" smd rect
			(at 20.624 -3.979 180)
			(size 0.3 1.75)
			(layers "F.Cu" "F.Mask" "F.Paste")
			(net 92 "unconnected-(J9-Pad52)")
			(pinfunction "52")
			(pintype "passive+no_connect")
		)
		(pad "53" smd rect
			(at 20.374 -12.176 180)
			(size 0.3 1.75)
			(layers "F.Cu" "F.Mask" "F.Paste")
			(net 93 "unconnected-(J9-Pad53)")
			(pinfunction "53")
			(pintype "passive+no_connect")
		)
		(pad "54" smd rect
			(at 20.124 -3.979 180)
			(size 0.3 1.75)
			(layers "F.Cu" "F.Mask" "F.Paste")
			(net 94 "unconnected-(J9-Pad54)")
			(pinfunction "54")
			(pintype "passive+no_connect")
		)
		(pad "55" smd rect
			(at 19.874 -12.176 180)
			(size 0.3 1.75)
			(layers "F.Cu" "F.Mask" "F.Paste")
			(net 96 "unconnected-(J9-Pad55)")
			(pinfunction "55")
			(pintype "passive+no_connect")
		)
		(pad "56" smd rect
			(at 19.624 -3.979 180)
			(size 0.3 1.75)
			(layers "F.Cu" "F.Mask" "F.Paste")
			(net 97 "unconnected-(J9-Pad56)")
			(pinfunction "56")
			(pintype "passive+no_connect")
		)
		(pad "57" smd rect
			(at 19.374 -12.176 180)
			(size 0.3 1.75)
			(layers "F.Cu" "F.Mask" "F.Paste")
			(net 98 "unconnected-(J9-Pad57)")
			(pinfunction "57")
			(pintype "passive+no_connect")
		)
		(pad "58" smd rect
			(at 19.124 -3.979 180)
			(size 0.3 1.75)
			(layers "F.Cu" "F.Mask" "F.Paste")
			(net 99 "unconnected-(J9-Pad58)")
			(pinfunction "58")
			(pintype "passive+no_connect")
		)
		(pad "59" smd rect
			(at 18.874 -12.176 180)
			(size 0.3 1.75)
			(layers "F.Cu" "F.Mask" "F.Paste")
			(net 100 "unconnected-(J9-Pad59)")
			(pinfunction "59")
			(pintype "passive+no_connect")
		)
		(pad "60" smd rect
			(at 18.624 -3.979 180)
			(size 0.3 1.75)
			(layers "F.Cu" "F.Mask" "F.Paste")
			(net 101 "unconnected-(J9-Pad60)")
			(pinfunction "60")
			(pintype "passive+no_connect")
		)
		(pad "61" smd rect
			(at 18.374 -12.176 180)
			(size 0.3 1.75)
			(layers "F.Cu" "F.Mask" "F.Paste")
			(net 102 "unconnected-(J9-Pad61)")
			(pinfunction "61")
			(pintype "passive+no_connect")
		)
		(pad "62" smd rect
			(at 18.124 -3.979 180)
			(size 0.3 1.75)
			(layers "F.Cu" "F.Mask" "F.Paste")
			(net 103 "unconnected-(J9-Pad62)")
			(pinfunction "62")
			(pintype "passive+no_connect")
		)
		(pad "63" smd rect
			(at 17.874 -12.176 180)
			(size 0.3 1.75)
			(layers "F.Cu" "F.Mask" "F.Paste")
			(net 104 "unconnected-(J9-Pad63)")
			(pinfunction "63")
			(pintype "passive+no_connect")
		)
		(pad "64" smd rect
			(at 17.624 -3.979 180)
			(size 0.3 1.75)
			(layers "F.Cu" "F.Mask" "F.Paste")
			(net 105 "unconnected-(J9-Pad64)")
			(pinfunction "64")
			(pintype "passive+no_connect")
		)
		(pad "65" smd rect
			(at 17.374 -12.176 180)
			(size 0.3 1.75)
			(layers "F.Cu" "F.Mask" "F.Paste")
			(net 106 "unconnected-(J9-Pad65)")
			(pinfunction "65")
			(pintype "passive+no_connect")
		)
		(pad "66" smd rect
			(at 17.124 -3.979 180)
			(size 0.3 1.75)
			(layers "F.Cu" "F.Mask" "F.Paste")
			(net 107 "unconnected-(J9-Pad66)")
			(pinfunction "66")
			(pintype "passive+no_connect")
		)
		(pad "67" smd rect
			(at 16.874 -12.176 180)
			(size 0.3 1.75)
			(layers "F.Cu" "F.Mask" "F.Paste")
			(net 108 "unconnected-(J9-Pad67)")
			(pinfunction "67")
			(pintype "passive+no_connect")
		)
		(pad "68" smd rect
			(at 16.624 -3.979 180)
			(size 0.3 1.75)
			(layers "F.Cu" "F.Mask" "F.Paste")
			(net 109 "unconnected-(J9-Pad68)")
			(pinfunction "68")
			(pintype "passive+no_connect")
		)
		(pad "69" smd rect
			(at 16.374 -12.176 180)
			(size 0.3 1.75)
			(layers "F.Cu" "F.Mask" "F.Paste")
			(net 110 "unconnected-(J9-Pad69)")
			(pinfunction "69")
			(pintype "passive+no_connect")
		)
		(pad "70" smd rect
			(at 16.124 -3.979 180)
			(size 0.3 1.75)
			(layers "F.Cu" "F.Mask" "F.Paste")
			(net 111 "unconnected-(J9-Pad70)")
			(pinfunction "70")
			(pintype "passive+no_connect")
		)
		(pad "71" smd rect
			(at 15.874 -12.176 180)
			(size 0.3 1.75)
			(layers "F.Cu" "F.Mask" "F.Paste")
			(net 112 "unconnected-(J9-Pad71)")
			(pinfunction "71")
			(pintype "passive+no_connect")
		)
		(pad "72" smd rect
			(at 15.624 -3.979 180)
			(size 0.3 1.75)
			(layers "F.Cu" "F.Mask" "F.Paste")
			(net 113 "unconnected-(J9-Pad72)")
			(pinfunction "72")
			(pintype "passive+no_connect")
		)
		(pad "73" smd rect
			(at 15.374 -12.176 180)
			(size 0.3 1.75)
			(layers "F.Cu" "F.Mask" "F.Paste")
			(net 114 "unconnected-(J9-Pad73)")
			(pinfunction "73")
			(pintype "passive+no_connect")
		)
		(pad "74" smd rect
			(at 15.124 -3.979 180)
			(size 0.3 1.75)
			(layers "F.Cu" "F.Mask" "F.Paste")
			(net 115 "unconnected-(J9-Pad74)")
			(pinfunction "74")
			(pintype "passive+no_connect")
		)
		(pad "75" smd rect
			(at 14.874 -12.176 180)
			(size 0.3 1.75)
			(layers "F.Cu" "F.Mask" "F.Paste")
			(net 116 "unconnected-(J9-Pad75)")
			(pinfunction "75")
			(pintype "passive+no_connect")
		)
		(pad "76" smd rect
			(at 14.624 -3.979 180)
			(size 0.3 1.75)
			(layers "F.Cu" "F.Mask" "F.Paste")
			(net 117 "unconnected-(J9-Pad76)")
			(pinfunction "76")
			(pintype "passive+no_connect")
		)
		(pad "77" smd rect
			(at 14.374 -12.176 180)
			(size 0.3 1.75)
			(layers "F.Cu" "F.Mask" "F.Paste")
			(net 118 "unconnected-(J9-Pad77)")
			(pinfunction "77")
			(pintype "passive+no_connect")
		)
		(pad "78" smd rect
			(at 14.124 -3.979 180)
			(size 0.3 1.75)
			(layers "F.Cu" "F.Mask" "F.Paste")
			(net 119 "unconnected-(J9-Pad78)")
			(pinfunction "78")
			(pintype "passive+no_connect")
		)
		(pad "79" smd rect
			(at 13.874 -12.176 180)
			(size 0.3 1.75)
			(layers "F.Cu" "F.Mask" "F.Paste")
			(net 120 "unconnected-(J9-Pad79)")
			(pinfunction "79")
			(pintype "passive+no_connect")
		)
		(pad "80" smd rect
			(at 13.624 -3.979 180)
			(size 0.3 1.75)
			(layers "F.Cu" "F.Mask" "F.Paste")
			(net 121 "unconnected-(J9-Pad80)")
			(pinfunction "80")
			(pintype "passive+no_connect")
		)
		(pad "81" smd rect
			(at 13.374 -12.176 180)
			(size 0.3 1.75)
			(layers "F.Cu" "F.Mask" "F.Paste")
			(net 122 "unconnected-(J9-Pad81)")
			(pinfunction "81")
			(pintype "passive+no_connect")
		)
		(pad "82" smd rect
			(at 13.124 -3.979 180)
			(size 0.3 1.75)
			(layers "F.Cu" "F.Mask" "F.Paste")
			(net 123 "unconnected-(J9-Pad82)")
			(pinfunction "82")
			(pintype "passive+no_connect")
		)
		(pad "83" smd rect
			(at 12.874 -12.176 180)
			(size 0.3 1.75)
			(layers "F.Cu" "F.Mask" "F.Paste")
			(net 124 "unconnected-(J9-Pad83)")
			(pinfunction "83")
			(pintype "passive+no_connect")
		)
		(pad "84" smd rect
			(at 12.624 -3.979 180)
			(size 0.3 1.75)
			(layers "F.Cu" "F.Mask" "F.Paste")
			(net 125 "unconnected-(J9-Pad84)")
			(pinfunction "84")
			(pintype "passive+no_connect")
		)
		(pad "85" smd rect
			(at 12.374 -12.176 180)
			(size 0.3 1.75)
			(layers "F.Cu" "F.Mask" "F.Paste")
			(net 126 "unconnected-(J9-Pad85)")
			(pinfunction "85")
			(pintype "passive+no_connect")
		)
		(pad "86" smd rect
			(at 12.124 -3.979 180)
			(size 0.3 1.75)
			(layers "F.Cu" "F.Mask" "F.Paste")
			(net 127 "unconnected-(J9-Pad86)")
			(pinfunction "86")
			(pintype "passive+no_connect")
		)
		(pad "87" smd rect
			(at 11.874 -12.176 180)
			(size 0.3 1.75)
			(layers "F.Cu" "F.Mask" "F.Paste")
			(net 128 "unconnected-(J9-Pad87)")
			(pinfunction "87")
			(pintype "passive+no_connect")
		)
		(pad "88" smd rect
			(at 11.624 -3.979 180)
			(size 0.3 1.75)
			(layers "F.Cu" "F.Mask" "F.Paste")
			(net 129 "unconnected-(J9-Pad88)")
			(pinfunction "88")
			(pintype "passive+no_connect")
		)
		(pad "89" smd rect
			(at 11.374 -12.176 180)
			(size 0.3 1.75)
			(layers "F.Cu" "F.Mask" "F.Paste")
			(net 130 "unconnected-(J9-Pad89)")
			(pinfunction "89")
			(pintype "passive+no_connect")
		)
		(pad "90" smd rect
			(at 11.124 -3.979 180)
			(size 0.3 1.75)
			(layers "F.Cu" "F.Mask" "F.Paste")
			(net 131 "unconnected-(J9-Pad90)")
			(pinfunction "90")
			(pintype "passive+no_connect")
		)
		(pad "91" smd rect
			(at 10.874 -12.176 180)
			(size 0.3 1.75)
			(layers "F.Cu" "F.Mask" "F.Paste")
			(net 132 "unconnected-(J9-Pad91)")
			(pinfunction "91")
			(pintype "passive+no_connect")
		)
		(pad "92" smd rect
			(at 10.624 -3.979 180)
			(size 0.3 1.75)
			(layers "F.Cu" "F.Mask" "F.Paste")
			(net 133 "unconnected-(J9-Pad92)")
			(pinfunction "92")
			(pintype "passive+no_connect")
		)
		(pad "93" smd rect
			(at 10.374 -12.176 180)
			(size 0.3 1.75)
			(layers "F.Cu" "F.Mask" "F.Paste")
			(net 273 "1V1_DDR")
			(pinfunction "93")
			(pintype "passive")
		)
		(pad "94" smd rect
			(at 10.124 -3.979 180)
			(size 0.3 1.75)
			(layers "F.Cu" "F.Mask" "F.Paste")
			(net 134 "unconnected-(J9-Pad94)")
			(pinfunction "94")
			(pintype "passive+no_connect")
		)
		(pad "95" smd rect
			(at 9.874 -12.176 180)
			(size 0.3 1.75)
			(layers "F.Cu" "F.Mask" "F.Paste")
			(net 273 "1V1_DDR")
			(pinfunction "95")
			(pintype "passive")
		)
		(pad "96" smd rect
			(at 9.624 -3.979 180)
			(size 0.3 1.75)
			(layers "F.Cu" "F.Mask" "F.Paste")
			(net 135 "unconnected-(J9-Pad96)")
			(pinfunction "96")
			(pintype "passive+no_connect")
		)
		(pad "97" smd rect
			(at 9.374 -12.176 180)
			(size 0.3 1.75)
			(layers "F.Cu" "F.Mask" "F.Paste")
			(net 273 "1V1_DDR")
			(pinfunction "97")
			(pintype "passive")
		)
		(pad "98" smd rect
			(at 9.124 -3.979 180)
			(size 0.3 1.75)
			(layers "F.Cu" "F.Mask" "F.Paste")
			(net 136 "unconnected-(J9-Pad98)")
			(pinfunction "98")
			(pintype "passive+no_connect")
		)
		(pad "99" smd rect
			(at 8.874 -12.176 180)
			(size 0.3 1.75)
			(layers "F.Cu" "F.Mask" "F.Paste")
			(net 273 "1V1_DDR")
			(pinfunction "99")
			(pintype "passive")
		)
		(pad "100" smd rect
			(at 8.624 -3.979 180)
			(size 0.3 1.75)
			(layers "F.Cu" "F.Mask" "F.Paste")
			(net 137 "unconnected-(J9-Pad100)")
			(pinfunction "100")
			(pintype "passive+no_connect")
		)
		(pad "101" smd rect
			(at 8.374 -12.176 180)
			(size 0.3 1.75)
			(layers "F.Cu" "F.Mask" "F.Paste")
			(net 273 "1V1_DDR")
			(pinfunction "101")
			(pintype "passive")
		)
		(pad "102" smd rect
			(at 8.124 -3.979 180)
			(size 0.3 1.75)
			(layers "F.Cu" "F.Mask" "F.Paste")
			(net 138 "unconnected-(J9-Pad102)")
			(pinfunction "102")
			(pintype "passive+no_connect")
		)
		(pad "103" smd rect
			(at 7.874 -12.176 180)
			(size 0.3 1.75)
			(layers "F.Cu" "F.Mask" "F.Paste")
			(net 273 "1V1_DDR")
			(pinfunction "103")
			(pintype "passive")
		)
		(pad "104" smd rect
			(at 7.624 -3.979 180)
			(size 0.3 1.75)
			(layers "F.Cu" "F.Mask" "F.Paste")
			(net 139 "unconnected-(J9-Pad104)")
			(pinfunction "104")
			(pintype "passive+no_connect")
		)
		(pad "105" smd rect
			(at 7.374 -12.176 180)
			(size 0.3 1.75)
			(layers "F.Cu" "F.Mask" "F.Paste")
			(net 273 "1V1_DDR")
			(pinfunction "105")
			(pintype "passive")
		)
		(pad "106" smd rect
			(at 7.124 -3.979 180)
			(size 0.3 1.75)
			(layers "F.Cu" "F.Mask" "F.Paste")
			(net 140 "unconnected-(J9-Pad106)")
			(pinfunction "106")
			(pintype "passive+no_connect")
		)
		(pad "107" smd rect
			(at 6.874 -12.176 180)
			(size 0.3 1.75)
			(layers "F.Cu" "F.Mask" "F.Paste")
			(net 273 "1V1_DDR")
			(pinfunction "107")
			(pintype "passive")
		)
		(pad "108" smd rect
			(at 6.624 -3.979 180)
			(size 0.3 1.75)
			(layers "F.Cu" "F.Mask" "F.Paste")
			(net 141 "unconnected-(J9-Pad108)")
			(pinfunction "108")
			(pintype "passive+no_connect")
		)
		(pad "109" smd rect
			(at 6.374 -12.176 180)
			(size 0.3 1.75)
			(layers "F.Cu" "F.Mask" "F.Paste")
			(net 142 "unconnected-(J9-Pad109)")
			(pinfunction "109")
			(pintype "passive+no_connect")
		)
		(pad "110" smd rect
			(at 6.124 -3.979 180)
			(size 0.3 1.75)
			(layers "F.Cu" "F.Mask" "F.Paste")
			(net 143 "unconnected-(J9-Pad110)")
			(pinfunction "110")
			(pintype "passive+no_connect")
		)
		(pad "111" smd rect
			(at 5.874 -12.176 180)
			(size 0.3 1.75)
			(layers "F.Cu" "F.Mask" "F.Paste")
			(net 144 "unconnected-(J9-Pad111)")
			(pinfunction "111")
			(pintype "passive+no_connect")
		)
		(pad "112" smd rect
			(at 5.624 -3.979 180)
			(size 0.3 1.75)
			(layers "F.Cu" "F.Mask" "F.Paste")
			(net 145 "unconnected-(J9-Pad112)")
			(pinfunction "112")
			(pintype "passive+no_connect")
		)
		(pad "113" smd rect
			(at 5.374 -12.176 180)
			(size 0.3 1.75)
			(layers "F.Cu" "F.Mask" "F.Paste")
			(net 146 "unconnected-(J9-Pad113)")
			(pinfunction "113")
			(pintype "passive+no_connect")
		)
		(pad "114" smd rect
			(at 5.124 -3.979 180)
			(size 0.3 1.75)
			(layers "F.Cu" "F.Mask" "F.Paste")
			(net 147 "unconnected-(J9-Pad114)")
			(pinfunction "114")
			(pintype "passive+no_connect")
		)
		(pad "115" smd rect
			(at 4.874 -12.176 180)
			(size 0.3 1.75)
			(layers "F.Cu" "F.Mask" "F.Paste")
			(net 148 "unconnected-(J9-Pad115)")
			(pinfunction "115")
			(pintype "passive+no_connect")
		)
		(pad "116" smd rect
			(at 4.624 -3.979 180)
			(size 0.3 1.75)
			(layers "F.Cu" "F.Mask" "F.Paste")
			(net 641 "1V8_DDR")
			(pinfunction "116")
			(pintype "passive")
		)
		(pad "117" smd rect
			(at 4.374 -12.176 180)
			(size 0.3 1.75)
			(layers "F.Cu" "F.Mask" "F.Paste")
			(net 149 "unconnected-(J9-Pad117)")
			(pinfunction "117")
			(pintype "passive+no_connect")
		)
		(pad "118" smd rect
			(at 4.124 -3.979 180)
			(size 0.3 1.75)
			(layers "F.Cu" "F.Mask" "F.Paste")
			(net 641 "1V8_DDR")
			(pinfunction "118")
			(pintype "passive")
		)
		(pad "119" smd rect
			(at 3.874 -12.176 180)
			(size 0.3 1.75)
			(layers "F.Cu" "F.Mask" "F.Paste")
			(net 150 "unconnected-(J9-Pad119)")
			(pinfunction "119")
			(pintype "passive+no_connect")
		)
		(pad "120" smd rect
			(at 3.624 -3.979 180)
			(size 0.3 1.75)
			(layers "F.Cu" "F.Mask" "F.Paste")
			(net 641 "1V8_DDR")
			(pinfunction "120")
			(pintype "passive")
		)
		(pad "121" smd rect
			(at 3.374 -12.176 180)
			(size 0.3 1.75)
			(layers "F.Cu" "F.Mask" "F.Paste")
			(net 151 "unconnected-(J9-Pad121)")
			(pinfunction "121")
			(pintype "passive+no_connect")
		)
		(pad "122" smd rect
			(at 3.124 -3.979 180)
			(size 0.3 1.75)
			(layers "F.Cu" "F.Mask" "F.Paste")
			(net 641 "1V8_DDR")
			(pinfunction "122")
			(pintype "passive")
		)
		(pad "123" smd rect
			(at 2.874 -12.176 180)
			(size 0.3 1.75)
			(layers "F.Cu" "F.Mask" "F.Paste")
			(net 152 "unconnected-(J9-Pad123)")
			(pinfunction "123")
			(pintype "passive+no_connect")
		)
		(pad "124" smd rect
			(at 2.624 -3.979 180)
			(size 0.3 1.75)
			(layers "F.Cu" "F.Mask" "F.Paste")
			(net 641 "1V8_DDR")
			(pinfunction "124")
			(pintype "passive")
		)
		(pad "125" smd rect
			(at 2.374 -12.176 180)
			(size 0.3 1.75)
			(layers "F.Cu" "F.Mask" "F.Paste")
			(net 153 "unconnected-(J9-Pad125)")
			(pinfunction "125")
			(pintype "passive+no_connect")
		)
		(pad "126" smd rect
			(at 2.124 -3.979 180)
			(size 0.3 1.75)
			(layers "F.Cu" "F.Mask" "F.Paste")
			(net 66 "VDDQ")
			(pinfunction "126")
			(pintype "passive")
		)
		(pad "127" smd rect
			(at 1.874 -12.176 180)
			(size 0.3 1.75)
			(layers "F.Cu" "F.Mask" "F.Paste")
			(net 487 "IO_U12")
			(pinfunction "127")
			(pintype "passive")
		)
		(pad "128" smd rect
			(at 1.624 -3.979 180)
			(size 0.3 1.75)
			(layers "F.Cu" "F.Mask" "F.Paste")
			(net 66 "VDDQ")
			(pinfunction "128")
			(pintype "passive")
		)
		(pad "129" smd rect
			(at 1.374 -12.176 180)
			(size 0.3 1.75)
			(layers "F.Cu" "F.Mask" "F.Paste")
			(net 486 "IO_V12")
			(pinfunction "129")
			(pintype "passive")
		)
		(pad "130" smd rect
			(at 1.124 -3.979 180)
			(size 0.3 1.75)
			(layers "F.Cu" "F.Mask" "F.Paste")
			(net 66 "VDDQ")
			(pinfunction "130")
			(pintype "passive")
		)
		(pad "131" smd rect
			(at 0.874 -12.176 180)
			(size 0.3 1.75)
			(layers "F.Cu" "F.Mask" "F.Paste")
			(net 485 "IO_W12")
			(pinfunction "131")
			(pintype "passive")
		)
		(pad "132" smd rect
			(at 0.624 -3.979 180)
			(size 0.3 1.75)
			(layers "F.Cu" "F.Mask" "F.Paste")
			(net 154 "unconnected-(J9-Pad132)")
			(pinfunction "132")
			(pintype "passive+no_connect")
		)
		(pad "133" smd rect
			(at 0.374 -12.176 180)
			(size 0.3 1.75)
			(layers "F.Cu" "F.Mask" "F.Paste")
			(net 484 "IO_Y12")
			(pinfunction "133")
			(pintype "passive")
		)
		(pad "134" smd rect
			(at 0.124 -3.979 180)
			(size 0.3 1.75)
			(layers "F.Cu" "F.Mask" "F.Paste")
			(net 155 "unconnected-(J9-Pad134)")
			(pinfunction "134")
			(pintype "passive+no_connect")
		)
		(pad "135" smd rect
			(at -0.125 -12.176 180)
			(size 0.3 1.75)
			(layers "F.Cu" "F.Mask" "F.Paste")
			(net 483 "IO_W11")
			(pinfunction "135")
			(pintype "passive")
		)
		(pad "136" smd rect
			(at -0.375 -3.979 180)
			(size 0.3 1.75)
			(layers "F.Cu" "F.Mask" "F.Paste")
			(net 156 "unconnected-(J9-Pad136)")
			(pinfunction "136")
			(pintype "passive+no_connect")
		)
		(pad "137" smd rect
			(at -0.625 -12.176 180)
			(size 0.3 1.75)
			(layers "F.Cu" "F.Mask" "F.Paste")
			(net 482 "IO_Y11")
			(pinfunction "137")
			(pintype "passive")
		)
		(pad "138" smd rect
			(at -0.875 -3.979 180)
			(size 0.3 1.75)
			(layers "F.Cu" "F.Mask" "F.Paste")
			(net 157 "unconnected-(J9-Pad138)")
			(pinfunction "138")
			(pintype "passive+no_connect")
		)
		(pad "139" smd rect
			(at -1.125 -12.176 180)
			(size 0.3 1.75)
			(layers "F.Cu" "F.Mask" "F.Paste")
			(net 481 "IO_AA11")
			(pinfunction "139")
			(pintype "passive")
		)
		(pad "140" smd rect
			(at -1.375 -3.979 180)
			(size 0.3 1.75)
			(layers "F.Cu" "F.Mask" "F.Paste")
			(net 158 "unconnected-(J9-Pad140)")
			(pinfunction "140")
			(pintype "passive+no_connect")
		)
		(pad "141" smd rect
			(at -1.625 -12.176 180)
			(size 0.3 1.75)
			(layers "F.Cu" "F.Mask" "F.Paste")
			(net 479 "IO_AB11")
			(pinfunction "141")
			(pintype "passive")
		)
		(pad "142" smd rect
			(at -1.875 -3.979 180)
			(size 0.3 1.75)
			(layers "F.Cu" "F.Mask" "F.Paste")
			(net 159 "unconnected-(J9-Pad142)")
			(pinfunction "142")
			(pintype "passive+no_connect")
		)
		(pad "143" smd rect
			(at -2.125 -12.176 180)
			(size 0.3 1.75)
			(layers "F.Cu" "F.Mask" "F.Paste")
			(net 480 "IO_AB10")
			(pinfunction "143")
			(pintype "passive")
		)
		(pad "144" smd rect
			(at -2.375 -3.979 180)
			(size 0.3 1.75)
			(layers "F.Cu" "F.Mask" "F.Paste")
			(net 160 "unconnected-(J9-Pad144)")
			(pinfunction "144")
			(pintype "passive+no_connect")
		)
		(pad "145" smd rect
			(at -4.625 -12.176 180)
			(size 0.3 1.75)
			(layers "F.Cu" "F.Mask" "F.Paste")
			(net 161 "unconnected-(J9-Pad145)")
			(pinfunction "145")
			(pintype "passive+no_connect")
		)
		(pad "146" smd rect
			(at -4.875 -3.979 180)
			(size 0.3 1.75)
			(layers "F.Cu" "F.Mask" "F.Paste")
			(net 162 "unconnected-(J9-Pad146)")
			(pinfunction "146")
			(pintype "passive+no_connect")
		)
		(pad "147" smd rect
			(at -5.125 -12.176 180)
			(size 0.3 1.75)
			(layers "F.Cu" "F.Mask" "F.Paste")
			(net 163 "unconnected-(J9-Pad147)")
			(pinfunction "147")
			(pintype "passive+no_connect")
		)
		(pad "148" smd rect
			(at -5.375 -3.979 180)
			(size 0.3 1.75)
			(layers "F.Cu" "F.Mask" "F.Paste")
			(net 164 "unconnected-(J9-Pad148)")
			(pinfunction "148")
			(pintype "passive+no_connect")
		)
		(pad "149" smd rect
			(at -5.625 -12.176 180)
			(size 0.3 1.75)
			(layers "F.Cu" "F.Mask" "F.Paste")
			(net 165 "unconnected-(J9-Pad149)")
			(pinfunction "149")
			(pintype "passive+no_connect")
		)
		(pad "150" smd rect
			(at -5.875 -3.979 180)
			(size 0.3 1.75)
			(layers "F.Cu" "F.Mask" "F.Paste")
			(net 166 "unconnected-(J9-Pad150)")
			(pinfunction "150")
			(pintype "passive+no_connect")
		)
		(pad "151" smd rect
			(at -6.125 -12.176 180)
			(size 0.3 1.75)
			(layers "F.Cu" "F.Mask" "F.Paste")
			(net 167 "unconnected-(J9-Pad151)")
			(pinfunction "151")
			(pintype "passive+no_connect")
		)
		(pad "152" smd rect
			(at -6.375 -3.979 180)
			(size 0.3 1.75)
			(layers "F.Cu" "F.Mask" "F.Paste")
			(net 168 "unconnected-(J9-Pad152)")
			(pinfunction "152")
			(pintype "passive+no_connect")
		)
		(pad "153" smd rect
			(at -6.625 -12.176 180)
			(size 0.3 1.75)
			(layers "F.Cu" "F.Mask" "F.Paste")
			(net 169 "unconnected-(J9-Pad153)")
			(pinfunction "153")
			(pintype "passive+no_connect")
		)
		(pad "154" smd rect
			(at -6.875 -3.979 180)
			(size 0.3 1.75)
			(layers "F.Cu" "F.Mask" "F.Paste")
			(net 5 "GND")
			(pinfunction "154")
			(pintype "passive")
		)
		(pad "155" smd rect
			(at -7.125 -12.176 180)
			(size 0.3 1.75)
			(layers "F.Cu" "F.Mask" "F.Paste")
			(net 170 "unconnected-(J9-Pad155)")
			(pinfunction "155")
			(pintype "passive+no_connect")
		)
		(pad "156" smd rect
			(at -7.375 -3.979 180)
			(size 0.3 1.75)
			(layers "F.Cu" "F.Mask" "F.Paste")
			(net 68 "CA5_A")
			(pinfunction "156")
			(pintype "passive")
		)
		(pad "157" smd rect
			(at -7.625 -12.176 180)
			(size 0.3 1.75)
			(layers "F.Cu" "F.Mask" "F.Paste")
			(net 171 "unconnected-(J9-Pad157)")
			(pinfunction "157")
			(pintype "passive+no_connect")
		)
		(pad "158" smd rect
			(at -7.875 -3.979 180)
			(size 0.3 1.75)
			(layers "F.Cu" "F.Mask" "F.Paste")
			(net 69 "CA4_A")
			(pinfunction "158")
			(pintype "passive")
		)
		(pad "159" smd rect
			(at -8.125 -12.176 180)
			(size 0.3 1.75)
			(layers "F.Cu" "F.Mask" "F.Paste")
			(net 172 "unconnected-(J9-Pad159)")
			(pinfunction "159")
			(pintype "passive+no_connect")
		)
		(pad "160" smd rect
			(at -8.375 -3.979 180)
			(size 0.3 1.75)
			(layers "F.Cu" "F.Mask" "F.Paste")
			(net 70 "CA3_A")
			(pinfunction "160")
			(pintype "passive")
		)
		(pad "161" smd rect
			(at -8.625 -12.176 180)
			(size 0.3 1.75)
			(layers "F.Cu" "F.Mask" "F.Paste")
			(net 5 "GND")
			(pinfunction "161")
			(pintype "passive")
		)
		(pad "162" smd rect
			(at -8.875 -3.979 180)
			(size 0.3 1.75)
			(layers "F.Cu" "F.Mask" "F.Paste")
			(net 71 "CA2_A")
			(pinfunction "162")
			(pintype "passive")
		)
		(pad "163" smd rect
			(at -9.125 -12.176 180)
			(size 0.3 1.75)
			(layers "F.Cu" "F.Mask" "F.Paste")
			(net 332 "DQ11_A")
			(pinfunction "163")
			(pintype "passive")
		)
		(pad "164" smd rect
			(at -9.375 -3.979 180)
			(size 0.3 1.75)
			(layers "F.Cu" "F.Mask" "F.Paste")
			(net 352 "CK_A_N")
			(pinfunction "164")
			(pintype "passive")
		)
		(pad "165" smd rect
			(at -9.625 -12.176 180)
			(size 0.3 1.75)
			(layers "F.Cu" "F.Mask" "F.Paste")
			(net 333 "DQ10_A")
			(pinfunction "165")
			(pintype "passive")
		)
		(pad "166" smd rect
			(at -9.875 -3.979 180)
			(size 0.3 1.75)
			(layers "F.Cu" "F.Mask" "F.Paste")
			(net 353 "CK_A_P")
			(pinfunction "166")
			(pintype "passive")
		)
		(pad "167" smd rect
			(at -10.125 -12.176 180)
			(size 0.3 1.75)
			(layers "F.Cu" "F.Mask" "F.Paste")
			(net 334 "DQ09_A")
			(pinfunction "167")
			(pintype "passive")
		)
		(pad "168" smd rect
			(at -10.375 -3.979 180)
			(size 0.3 1.75)
			(layers "F.Cu" "F.Mask" "F.Paste")
			(net 5 "GND")
			(pinfunction "168")
			(pintype "passive")
		)
		(pad "169" smd rect
			(at -10.625 -12.176 180)
			(size 0.3 1.75)
			(layers "F.Cu" "F.Mask" "F.Paste")
			(net 335 "DQ08_A")
			(pinfunction "169")
			(pintype "passive")
		)
		(pad "170" smd rect
			(at -10.875 -3.979 180)
			(size 0.3 1.75)
			(layers "F.Cu" "F.Mask" "F.Paste")
			(net 398 "IO_W4")
			(pinfunction "170")
			(pintype "passive")
		)
		(pad "171" smd rect
			(at -11.125 -12.176 180)
			(size 0.3 1.75)
			(layers "F.Cu" "F.Mask" "F.Paste")
			(net 336 "DMI_1A")
			(pinfunction "171")
			(pintype "passive")
		)
		(pad "172" smd rect
			(at -11.375 -3.979 180)
			(size 0.3 1.75)
			(layers "F.Cu" "F.Mask" "F.Paste")
			(net 403 "IO_V3")
			(pinfunction "172")
			(pintype "passive")
		)
		(pad "173" smd rect
			(at -11.625 -12.176 180)
			(size 0.3 1.75)
			(layers "F.Cu" "F.Mask" "F.Paste")
			(net 648 "DQ_S1_N")
			(pinfunction "173")
			(pintype "passive")
		)
		(pad "174" smd rect
			(at -11.875 -3.979 180)
			(size 0.3 1.75)
			(layers "F.Cu" "F.Mask" "F.Paste")
			(net 399 "IO_V4")
			(pinfunction "174")
			(pintype "passive")
		)
		(pad "175" smd rect
			(at -12.125 -12.176 180)
			(size 0.3 1.75)
			(layers "F.Cu" "F.Mask" "F.Paste")
			(net 649 "DQ_S1_P")
			(pinfunction "175")
			(pintype "passive")
		)
		(pad "176" smd rect
			(at -12.375 -3.979 180)
			(size 0.3 1.75)
			(layers "F.Cu" "F.Mask" "F.Paste")
			(net 404 "IO_U3")
			(pinfunction "176")
			(pintype "passive")
		)
		(pad "177" smd rect
			(at -12.625 -12.176 180)
			(size 0.3 1.75)
			(layers "F.Cu" "F.Mask" "F.Paste")
			(net 5 "GND")
			(pinfunction "177")
			(pintype "passive")
		)
		(pad "178" smd rect
			(at -12.875 -3.979 180)
			(size 0.3 1.75)
			(layers "F.Cu" "F.Mask" "F.Paste")
			(net 405 "IO_U5")
			(pinfunction "178")
			(pintype "passive")
		)
		(pad "179" smd rect
			(at -13.125 -12.176 180)
			(size 0.3 1.75)
			(layers "F.Cu" "F.Mask" "F.Paste")
			(net 338 "DQ15_A")
			(pinfunction "179")
			(pintype "passive")
		)
		(pad "180" smd rect
			(at -13.375 -3.979 180)
			(size 0.3 1.75)
			(layers "F.Cu" "F.Mask" "F.Paste")
			(net 400 "IO_T4")
			(pinfunction "180")
			(pintype "passive")
		)
		(pad "181" smd rect
			(at -13.625 -12.176 180)
			(size 0.3 1.75)
			(layers "F.Cu" "F.Mask" "F.Paste")
			(net 339 "DQ14_A")
			(pinfunction "181")
			(pintype "passive")
		)
		(pad "182" smd rect
			(at -13.875 -3.979 180)
			(size 0.3 1.75)
			(layers "F.Cu" "F.Mask" "F.Paste")
			(net 401 "IO_R4")
			(pinfunction "182")
			(pintype "passive")
		)
		(pad "183" smd rect
			(at -14.125 -12.176 180)
			(size 0.3 1.75)
			(layers "F.Cu" "F.Mask" "F.Paste")
			(net 340 "DQ13_A")
			(pinfunction "183")
			(pintype "passive")
		)
		(pad "184" smd rect
			(at -14.375 -3.979 180)
			(size 0.3 1.75)
			(layers "F.Cu" "F.Mask" "F.Paste")
			(net 5 "GND")
			(pinfunction "184")
			(pintype "passive")
		)
		(pad "185" smd rect
			(at -14.625 -12.176 180)
			(size 0.3 1.75)
			(layers "F.Cu" "F.Mask" "F.Paste")
			(net 341 "DQ12_A")
			(pinfunction "185")
			(pintype "passive")
		)
		(pad "186" smd rect
			(at -14.875 -3.979 180)
			(size 0.3 1.75)
			(layers "F.Cu" "F.Mask" "F.Paste")
			(net 402 "IO_P4")
			(pinfunction "186")
			(pintype "passive")
		)
		(pad "187" smd rect
			(at -15.125 -12.176 180)
			(size 0.3 1.75)
			(layers "F.Cu" "F.Mask" "F.Paste")
			(net 343 "DQ04_A")
			(pinfunction "187")
			(pintype "passive")
		)
		(pad "188" smd rect
			(at -15.375 -3.979 180)
			(size 0.3 1.75)
			(layers "F.Cu" "F.Mask" "F.Paste")
			(net 173 "unconnected-(J9-Pad188)")
			(pinfunction "188")
			(pintype "passive+no_connect")
		)
		(pad "189" smd rect
			(at -15.625 -12.176 180)
			(size 0.3 1.75)
			(layers "F.Cu" "F.Mask" "F.Paste")
			(net 344 "DQ05_A")
			(pinfunction "189")
			(pintype "passive")
		)
		(pad "190" smd rect
			(at -15.875 -3.979 180)
			(size 0.3 1.75)
			(layers "F.Cu" "F.Mask" "F.Paste")
			(net 174 "unconnected-(J9-Pad190)")
			(pinfunction "190")
			(pintype "passive+no_connect")
		)
		(pad "191" smd rect
			(at -16.125 -12.176 180)
			(size 0.3 1.75)
			(layers "F.Cu" "F.Mask" "F.Paste")
			(net 345 "DQ06_A")
			(pinfunction "191")
			(pintype "passive")
		)
		(pad "192" smd rect
			(at -16.375 -3.979 180)
			(size 0.3 1.75)
			(layers "F.Cu" "F.Mask" "F.Paste")
			(net 406 "IO_N5")
			(pinfunction "192")
			(pintype "passive")
		)
		(pad "193" smd rect
			(at -16.625 -12.176 180)
			(size 0.3 1.75)
			(layers "F.Cu" "F.Mask" "F.Paste")
			(net 346 "DQ07_A")
			(pinfunction "193")
			(pintype "passive")
		)
		(pad "194" smd rect
			(at -16.875 -3.979 180)
			(size 0.3 1.75)
			(layers "F.Cu" "F.Mask" "F.Paste")
			(net 395 "CS0_A")
			(pinfunction "194")
			(pintype "passive")
		)
		(pad "195" smd rect
			(at -17.125 -12.176 180)
			(size 0.3 1.75)
			(layers "F.Cu" "F.Mask" "F.Paste")
			(net 5 "GND")
			(pinfunction "195")
			(pintype "passive")
		)
		(pad "196" smd rect
			(at -17.375 -3.979 180)
			(size 0.3 1.75)
			(layers "F.Cu" "F.Mask" "F.Paste")
			(net 396 "CKE0_A")
			(pinfunction "196")
			(pintype "passive")
		)
		(pad "197" smd rect
			(at -17.625 -12.176 180)
			(size 0.3 1.75)
			(layers "F.Cu" "F.Mask" "F.Paste")
			(net 347 "DMI_0A")
			(pinfunction "197")
			(pintype "passive")
		)
		(pad "198" smd rect
			(at -17.875 -3.979 180)
			(size 0.3 1.75)
			(layers "F.Cu" "F.Mask" "F.Paste")
			(net 397 "IO_M5")
			(pinfunction "198")
			(pintype "passive")
		)
		(pad "199" smd rect
			(at -18.125 -12.176 180)
			(size 0.3 1.75)
			(layers "F.Cu" "F.Mask" "F.Paste")
			(net 650 "DQ_S0_N")
			(pinfunction "199")
			(pintype "passive")
		)
		(pad "200" smd rect
			(at -18.375 -3.979 180)
			(size 0.3 1.75)
			(layers "F.Cu" "F.Mask" "F.Paste")
			(net 5 "GND")
			(pinfunction "200")
			(pintype "passive")
		)
		(pad "201" smd rect
			(at -18.625 -12.176 180)
			(size 0.3 1.75)
			(layers "F.Cu" "F.Mask" "F.Paste")
			(net 651 "DQ_S0_P")
			(pinfunction "201")
			(pintype "passive")
		)
		(pad "202" smd rect
			(at -18.875 -3.979 180)
			(size 0.3 1.75)
			(layers "F.Cu" "F.Mask" "F.Paste")
			(net 175 "unconnected-(J9-Pad202)")
			(pinfunction "202")
			(pintype "passive+no_connect")
		)
		(pad "203" smd rect
			(at -19.125 -12.176 180)
			(size 0.3 1.75)
			(layers "F.Cu" "F.Mask" "F.Paste")
			(net 351 "DQ00_A")
			(pinfunction "203")
			(pintype "passive")
		)
		(pad "204" smd rect
			(at -19.375 -3.979 180)
			(size 0.3 1.75)
			(layers "F.Cu" "F.Mask" "F.Paste")
			(net 394 "CA_0A")
			(pinfunction "204")
			(pintype "passive")
		)
		(pad "205" smd rect
			(at -19.625 -12.176 180)
			(size 0.3 1.75)
			(layers "F.Cu" "F.Mask" "F.Paste")
			(net 350 "DQ01_A")
			(pinfunction "205")
			(pintype "passive")
		)
		(pad "206" smd rect
			(at -19.875 -3.979 180)
			(size 0.3 1.75)
			(layers "F.Cu" "F.Mask" "F.Paste")
			(net 393 "CA_1A")
			(pinfunction "206")
			(pintype "passive")
		)
		(pad "207" smd rect
			(at -20.125 -12.176 180)
			(size 0.3 1.75)
			(layers "F.Cu" "F.Mask" "F.Paste")
			(net 349 "DQ02_A")
			(pinfunction "207")
			(pintype "passive")
		)
		(pad "208" smd rect
			(at -20.375 -3.979 180)
			(size 0.3 1.75)
			(layers "F.Cu" "F.Mask" "F.Paste")
			(net 407 "IO_K4")
			(pinfunction "208")
			(pintype "passive")
		)
		(pad "209" smd rect
			(at -20.625 -12.176 180)
			(size 0.3 1.75)
			(layers "F.Cu" "F.Mask" "F.Paste")
			(net 348 "DQ03_A")
			(pinfunction "209")
			(pintype "passive")
		)
		(pad "210" smd rect
			(at -20.875 -3.979 180)
			(size 0.3 1.75)
			(layers "F.Cu" "F.Mask" "F.Paste")
			(net 5 "GND")
			(pinfunction "210")
			(pintype "passive")
		)
		(pad "211" smd rect
			(at -21.125 -12.176 180)
			(size 0.3 1.75)
			(layers "F.Cu" "F.Mask" "F.Paste")
			(net 5 "GND")
			(pinfunction "211")
			(pintype "passive")
		)
		(pad "212" smd rect
			(at -21.375 -3.979 180)
			(size 0.3 1.75)
			(layers "F.Cu" "F.Mask" "F.Paste")
			(net 176 "unconnected-(J9-Pad212)")
			(pinfunction "212")
			(pintype "passive+no_connect")
		)
		(pad "213" smd rect
			(at -21.625 -12.176 180)
			(size 0.3 1.75)
			(layers "F.Cu" "F.Mask" "F.Paste")
			(net 177 "unconnected-(J9-Pad213)")
			(pinfunction "213")
			(pintype "passive+no_connect")
		)
		(pad "214" smd rect
			(at -21.875 -3.979 180)
			(size 0.3 1.75)
			(layers "F.Cu" "F.Mask" "F.Paste")
			(net 178 "unconnected-(J9-Pad214)")
			(pinfunction "214")
			(pintype "passive+no_connect")
		)
		(pad "215" smd rect
			(at -22.125 -12.176 180)
			(size 0.3 1.75)
			(layers "F.Cu" "F.Mask" "F.Paste")
			(net 179 "unconnected-(J9-Pad215)")
			(pinfunction "215")
			(pintype "passive+no_connect")
		)
		(pad "216" smd rect
			(at -22.375 -3.979 180)
			(size 0.3 1.75)
			(layers "F.Cu" "F.Mask" "F.Paste")
			(net 180 "unconnected-(J9-Pad216)")
			(pinfunction "216")
			(pintype "passive+no_connect")
		)
		(pad "217" smd rect
			(at -22.625 -12.176 180)
			(size 0.3 1.75)
			(layers "F.Cu" "F.Mask" "F.Paste")
			(net 181 "unconnected-(J9-Pad217)")
			(pinfunction "217")
			(pintype "passive+no_connect")
		)
		(pad "218" smd rect
			(at -22.875 -3.979 180)
			(size 0.3 1.75)
			(layers "F.Cu" "F.Mask" "F.Paste")
			(net 182 "unconnected-(J9-Pad218)")
			(pinfunction "218")
			(pintype "passive+no_connect")
		)
		(pad "219" smd rect
			(at -23.125 -12.176 180)
			(size 0.3 1.75)
			(layers "F.Cu" "F.Mask" "F.Paste")
			(net 183 "unconnected-(J9-Pad219)")
			(pinfunction "219")
			(pintype "passive+no_connect")
		)
		(pad "220" smd rect
			(at -23.375 -3.979 180)
			(size 0.3 1.75)
			(layers "F.Cu" "F.Mask" "F.Paste")
			(net 184 "unconnected-(J9-Pad220)")
			(pinfunction "220")
			(pintype "passive+no_connect")
		)
		(pad "221" smd rect
			(at -23.625 -12.176 180)
			(size 0.3 1.75)
			(layers "F.Cu" "F.Mask" "F.Paste")
			(net 185 "unconnected-(J9-Pad221)")
			(pinfunction "221")
			(pintype "passive+no_connect")
		)
		(pad "222" smd rect
			(at -23.875 -3.979 180)
			(size 0.3 1.75)
			(layers "F.Cu" "F.Mask" "F.Paste")
			(net 186 "unconnected-(J9-Pad222)")
			(pinfunction "222")
			(pintype "passive+no_connect")
		)
		(pad "223" smd rect
			(at -24.125 -12.176 180)
			(size 0.3 1.75)
			(layers "F.Cu" "F.Mask" "F.Paste")
			(net 187 "unconnected-(J9-Pad223)")
			(pinfunction "223")
			(pintype "passive+no_connect")
		)
		(pad "224" smd rect
			(at -24.375 -3.979 180)
			(size 0.3 1.75)
			(layers "F.Cu" "F.Mask" "F.Paste")
			(net 188 "unconnected-(J9-Pad224)")
			(pinfunction "224")
			(pintype "passive+no_connect")
		)
		(pad "225" smd rect
			(at -24.625 -12.176 180)
			(size 0.3 1.75)
			(layers "F.Cu" "F.Mask" "F.Paste")
			(net 189 "unconnected-(J9-Pad225)")
			(pinfunction "225")
			(pintype "passive+no_connect")
		)
		(pad "226" smd rect
			(at -24.875 -3.979 180)
			(size 0.3 1.75)
			(layers "F.Cu" "F.Mask" "F.Paste")
			(net 190 "unconnected-(J9-Pad226)")
			(pinfunction "226")
			(pintype "passive+no_connect")
		)
		(pad "227" smd rect
			(at -25.125 -12.176 180)
			(size 0.3 1.75)
			(layers "F.Cu" "F.Mask" "F.Paste")
			(net 191 "unconnected-(J9-Pad227)")
			(pinfunction "227")
			(pintype "passive+no_connect")
		)
		(pad "228" smd rect
			(at -25.375 -3.979 180)
			(size 0.3 1.75)
			(layers "F.Cu" "F.Mask" "F.Paste")
			(net 199 "unconnected-(J9-Pad228)")
			(pinfunction "228")
			(pintype "passive+no_connect")
		)
		(pad "229" smd rect
			(at -25.625 -12.176 180)
			(size 0.3 1.75)
			(layers "F.Cu" "F.Mask" "F.Paste")
			(net 200 "unconnected-(J9-Pad229)")
			(pinfunction "229")
			(pintype "passive+no_connect")
		)
		(pad "230" smd rect
			(at -25.875 -3.979 180)
			(size 0.3 1.75)
			(layers "F.Cu" "F.Mask" "F.Paste")
			(net 201 "unconnected-(J9-Pad230)")
			(pinfunction "230")
			(pintype "passive+no_connect")
		)
		(pad "231" smd rect
			(at -26.125 -12.176 180)
			(size 0.3 1.75)
			(layers "F.Cu" "F.Mask" "F.Paste")
			(net 204 "unconnected-(J9-Pad231)")
			(pinfunction "231")
			(pintype "passive+no_connect")
		)
		(pad "232" smd rect
			(at -26.375 -3.979 180)
			(size 0.3 1.75)
			(layers "F.Cu" "F.Mask" "F.Paste")
			(net 205 "unconnected-(J9-Pad232)")
			(pinfunction "232")
			(pintype "passive+no_connect")
		)
		(pad "233" smd rect
			(at -26.625 -12.176 180)
			(size 0.3 1.75)
			(layers "F.Cu" "F.Mask" "F.Paste")
			(net 207 "unconnected-(J9-Pad233)")
			(pinfunction "233")
			(pintype "passive+no_connect")
		)
		(pad "234" smd rect
			(at -26.875 -3.979 180)
			(size 0.3 1.75)
			(layers "F.Cu" "F.Mask" "F.Paste")
			(net 214 "unconnected-(J9-Pad234)")
			(pinfunction "234")
			(pintype "passive+no_connect")
		)
		(pad "235" smd rect
			(at -27.125 -12.176 180)
			(size 0.3 1.75)
			(layers "F.Cu" "F.Mask" "F.Paste")
			(net 215 "unconnected-(J9-Pad235)")
			(pinfunction "235")
			(pintype "passive+no_connect")
		)
		(pad "236" smd rect
			(at -27.375 -3.979 180)
			(size 0.3 1.75)
			(layers "F.Cu" "F.Mask" "F.Paste")
			(net 216 "unconnected-(J9-Pad236)")
			(pinfunction "236")
			(pintype "passive+no_connect")
		)
		(pad "237" smd rect
			(at -27.625 -12.176 180)
			(size 0.3 1.75)
			(layers "F.Cu" "F.Mask" "F.Paste")
			(net 218 "unconnected-(J9-Pad237)")
			(pinfunction "237")
			(pintype "passive+no_connect")
		)
		(pad "238" smd rect
			(at -27.875 -3.979 180)
			(size 0.3 1.75)
			(layers "F.Cu" "F.Mask" "F.Paste")
			(net 220 "unconnected-(J9-Pad238)")
			(pinfunction "238")
			(pintype "passive+no_connect")
		)
		(pad "239" smd rect
			(at -28.125 -12.176 180)
			(size 0.3 1.75)
			(layers "F.Cu" "F.Mask" "F.Paste")
			(net 221 "unconnected-(J9-Pad239)")
			(pinfunction "239")
			(pintype "passive+no_connect")
		)
		(pad "240" smd rect
			(at -28.375 -3.979 180)
			(size 0.3 1.75)
			(layers "F.Cu" "F.Mask" "F.Paste")
			(net 222 "unconnected-(J9-Pad240)")
			(pinfunction "240")
			(pintype "passive+no_connect")
		)
		(pad "241" smd rect
			(at -28.625 -12.176 180)
			(size 0.3 1.75)
			(layers "F.Cu" "F.Mask" "F.Paste")
			(net 223 "unconnected-(J9-Pad241)")
			(pinfunction "241")
			(pintype "passive+no_connect")
		)
		(pad "242" smd rect
			(at -28.875 -3.979 180)
			(size 0.3 1.75)
			(layers "F.Cu" "F.Mask" "F.Paste")
			(net 225 "unconnected-(J9-Pad242)")
			(pinfunction "242")
			(pintype "passive+no_connect")
		)
		(pad "243" smd rect
			(at -29.125 -12.176 180)
			(size 0.3 1.75)
			(layers "F.Cu" "F.Mask" "F.Paste")
			(net 226 "unconnected-(J9-Pad243)")
			(pinfunction "243")
			(pintype "passive+no_connect")
		)
		(pad "244" smd rect
			(at -29.375 -3.979 180)
			(size 0.3 1.75)
			(layers "F.Cu" "F.Mask" "F.Paste")
			(net 227 "unconnected-(J9-Pad244)")
			(pinfunction "244")
			(pintype "passive+no_connect")
		)
		(pad "245" smd rect
			(at -29.625 -12.176 180)
			(size 0.3 1.75)
			(layers "F.Cu" "F.Mask" "F.Paste")
			(net 273 "1V1_DDR")
			(pinfunction "245")
			(pintype "passive")
		)
		(pad "246" smd rect
			(at -29.875 -3.979 180)
			(size 0.3 1.75)
			(layers "F.Cu" "F.Mask" "F.Paste")
			(net 66 "VDDQ")
			(pinfunction "246")
			(pintype "passive")
		)
		(pad "247" smd rect
			(at -30.125 -12.176 180)
			(size 0.3 1.75)
			(layers "F.Cu" "F.Mask" "F.Paste")
			(net 273 "1V1_DDR")
			(pinfunction "247")
			(pintype "passive")
		)
		(pad "248" smd rect
			(at -30.375 -3.979 180)
			(size 0.3 1.75)
			(layers "F.Cu" "F.Mask" "F.Paste")
			(net 66 "VDDQ")
			(pinfunction "248")
			(pintype "passive")
		)
		(pad "249" smd rect
			(at -30.625 -12.176 180)
			(size 0.3 1.75)
			(layers "F.Cu" "F.Mask" "F.Paste")
			(net 273 "1V1_DDR")
			(pinfunction "249")
			(pintype "passive")
		)
		(pad "250" smd rect
			(at -30.875 -3.979 180)
			(size 0.3 1.75)
			(layers "F.Cu" "F.Mask" "F.Paste")
			(net 66 "VDDQ")
			(pinfunction "250")
			(pintype "passive")
		)
		(pad "251" smd rect
			(at -31.125 -12.176 180)
			(size 0.3 1.75)
			(layers "F.Cu" "F.Mask" "F.Paste")
			(net 273 "1V1_DDR")
			(pinfunction "251")
			(pintype "passive")
		)
		(pad "252" smd rect
			(at -31.375 -3.979 180)
			(size 0.3 1.75)
			(layers "F.Cu" "F.Mask" "F.Paste")
			(net 641 "1V8_DDR")
			(pinfunction "252")
			(pintype "passive")
		)
		(pad "253" smd rect
			(at -31.625 -12.176 180)
			(size 0.3 1.75)
			(layers "F.Cu" "F.Mask" "F.Paste")
			(net 273 "1V1_DDR")
			(pinfunction "253")
			(pintype "passive")
		)
		(pad "254" smd rect
			(at -31.875 -3.979 180)
			(size 0.3 1.75)
			(layers "F.Cu" "F.Mask" "F.Paste")
			(net 641 "1V8_DDR")
			(pinfunction "254")
			(pintype "passive")
		)
		(pad "255" smd rect
			(at -32.125 -12.176 180)
			(size 0.3 1.75)
			(layers "F.Cu" "F.Mask" "F.Paste")
			(net 273 "1V1_DDR")
			(pinfunction "255")
			(pintype "passive")
		)
		(pad "256" smd rect
			(at -32.375 -3.979 180)
			(size 0.3 1.75)
			(layers "F.Cu" "F.Mask" "F.Paste")
			(net 641 "1V8_DDR")
			(pinfunction "256")
			(pintype "passive")
		)
		(pad "257" smd rect
			(at -32.625 -12.176 180)
			(size 0.3 1.75)
			(layers "F.Cu" "F.Mask" "F.Paste")
			(net 273 "1V1_DDR")
			(pinfunction "257")
			(pintype "passive")
		)
		(pad "258" smd rect
			(at -32.875 -3.979 180)
			(size 0.3 1.75)
			(layers "F.Cu" "F.Mask" "F.Paste")
			(net 641 "1V8_DDR")
			(pinfunction "258")
			(pintype "passive")
		)
		(pad "259" smd rect
			(at -33.125 -12.176 180)
			(size 0.3 1.75)
			(layers "F.Cu" "F.Mask" "F.Paste")
			(net 273 "1V1_DDR")
			(pinfunction "259")
			(pintype "passive")
		)
		(pad "260" smd rect
			(at -33.375 -3.979 180)
			(size 0.3 1.75)
			(layers "F.Cu" "F.Mask" "F.Paste")
			(net 641 "1V8_DDR")
			(pinfunction "260")
			(pintype "passive")
		)
		(pad "S1" smd rect
			(at 33.798 3.925 180)
			(size 3.5 4.6)
			(layers "F.Cu" "F.Mask" "F.Paste")
			(net 5 "GND")
			(pinfunction "SHIELD")
			(pintype "passive")
		)
		(pad "S2" smd rect
			(at -33.8 3.925 180)
			(size 3.5 4.6)
			(layers "F.Cu" "F.Mask" "F.Paste")
			(net 5 "GND")
			(pinfunction "SHIELD")
			(pintype "passive")
		)
	)
	(footprint "antmicro-footprints:TP_SMD_1mm"
		(layer "F.Cu")
		(at 152.01 119.16 90)
		(property "Reference" "TP2"
			(at 0.36 0.0008 90)
			(layer "F.SilkS")
			(effects
				(font
					(size 0.7 0.7)
					(thickness 0.15)
				)
				(justify left bottom)
			)
		)
		(property "Value" "TP_1mm_SMD"
			(at 0 1.4 90)
			(layer "F.Fab")
			(effects
				(font
					(size 0.7 0.7)
					(thickness 0.15)
				)
				(justify left bottom)
			)
		)
		(property "Description" "Test Point 1mm"
			(at 0 0 90)
			(layer "F.Fab")
			(hide yes)
			(effects
				(font
					(size 1.27 1.27)
					(thickness 0.15)
				)
			)
		)
		(property "Author" "Antmicro"
			(at 271.17 -32.85 0)
			(layer "F.Fab")
			(hide yes)
			(effects
				(font
					(size 1 1)
					(thickness 0.15)
				)
			)
		)
		(property "License" "Apache-2.0"
			(at 271.17 -32.85 0)
			(layer "F.Fab")
			(hide yes)
			(effects
				(font
					(size 1 1)
					(thickness 0.15)
				)
			)
		)
		(property "MPN" ""
			(at 271.17 -32.85 0)
			(layer "F.Fab")
			(hide yes)
			(effects
				(font
					(size 1 1)
					(thickness 0.15)
				)
			)
		)
		(property "Manufacturer" ""
			(at 271.17 -32.85 0)
			(layer "F.Fab")
			(hide yes)
			(effects
				(font
					(size 1 1)
					(thickness 0.15)
				)
			)
		)
		(sheetname "Interfaces")
		(sheetfile "interfaces.kicad_sch")
		(attr exclude_from_pos_files)
		(pad "1" smd circle
			(at 0 0 90)
			(size 1 1)
			(layers "F.Cu" "F.Mask")
			(net 80 "Net-(J2-CEC)")
			(pinfunction "1")
			(pintype "passive")
		)
	)
	(footprint "antmicro-footprints:C_0402_1005Metric"
		(layer "F.Cu")
		(at 138.286328 115.107157)
		(descr "Capacitor SMD 0402")
		(tags "capacitor SMD 0402")
		(property "Reference" "C18"
			(at -3.286328 -0.7 0)
			(layer "F.SilkS")
			(effects
				(font
					(size 0.7 0.7)
					(thickness 0.15)
				)
				(justify left bottom)
			)
		)
		(property "Value" "C_4u7_0402"
			(at 0 1.4 0)
			(layer "F.Fab")
			(effects
				(font
					(size 0.7 0.7)
					(thickness 0.15)
				)
				(justify left bottom)
			)
		)
		(property "Description" " "
			(at 0 0 0)
			(layer "F.Fab")
			(hide yes)
			(effects
				(font
					(size 1.27 1.27)
					(thickness 0.15)
				)
			)
		)
		(property "Author" "Antmicro"
			(at 0 0 0)
			(layer "F.Fab")
			(hide yes)
			(effects
				(font
					(size 1 1)
					(thickness 0.15)
				)
			)
		)
		(property "Dielectric" ""
			(at 0 0 0)
			(layer "F.Fab")
			(hide yes)
			(effects
				(font
					(size 1 1)
					(thickness 0.15)
				)
			)
		)
		(property "License" "Apache-2.0"
			(at 0 0 0)
			(layer "F.Fab")
			(hide yes)
			(effects
				(font
					(size 1 1)
					(thickness 0.15)
				)
			)
		)
		(property "MPN" "GRM155R61A475MEAAD"
			(at 0 0 0)
			(layer "F.Fab")
			(hide yes)
			(effects
				(font
					(size 1 1)
					(thickness 0.15)
				)
			)
		)
		(property "Manufacturer" "Murata"
			(at 0 0 0)
			(layer "F.Fab")
			(hide yes)
			(effects
				(font
					(size 1 1)
					(thickness 0.15)
				)
			)
		)
		(property "Val" "4u7"
			(at 0 0 0)
			(layer "F.Fab")
			(hide yes)
			(effects
				(font
					(size 1 1)
					(thickness 0.15)
				)
			)
		)
		(property "Voltage" ""
			(at 0 0 0)
			(layer "F.Fab")
			(hide yes)
			(effects
				(font
					(size 1 1)
					(thickness 0.15)
				)
			)
		)
		(sheetname "Interfaces")
		(sheetfile "interfaces.kicad_sch")
		(attr smd)
		(fp_rect
			(start -0.94 -0.47)
			(end 0.94 0.47)
			(stroke
				(width 0.05)
				(type solid)
			)
			(fill no)
			(layer "F.CrtYd")
		)
		(fp_rect
			(start -0.499 -0.249)
			(end 0.499 0.249)
			(stroke
				(width 0.15)
				(type solid)
			)
			(fill no)
			(layer "F.Fab")
		)
		(pad "1" smd roundrect
			(at -0.484 0)
			(size 0.59 0.64)
			(layers "F.Cu" "F.Mask" "F.Paste")
			(roundrect_rratio 0.25)
			(net 5 "GND")
			(pintype "passive")
		)
		(pad "2" smd roundrect
			(at 0.484 0)
			(size 0.59 0.64)
			(layers "F.Cu" "F.Mask" "F.Paste")
			(roundrect_rratio 0.25)
			(net 653 "/Interfaces/VPHY")
			(pintype "passive")
		)
	)
	(footprint "antmicro-footprints:R_0402_1005Metric"
		(layer "F.Cu")
		(at 145.046328 114.596157 90)
		(descr "Resistor SMD 0402")
		(tags "resistor SMD 0402")
		(property "Reference" "R8"
			(at -0.803843 1.253672 90)
			(layer "F.SilkS")
			(effects
				(font
					(size 0.7 0.7)
					(thickness 0.15)
				)
				(justify left bottom)
			)
		)
		(property "Value" "R_10k_0402"
			(at 0 1.4 90)
			(layer "F.Fab")
			(effects
				(font
					(size 0.7 0.7)
					(thickness 0.15)
				)
				(justify left bottom)
			)
		)
		(property "Description" "10k resistor in 0402 package with 1% tolerance"
			(at 0 0 90)
			(layer "F.Fab")
			(hide yes)
			(effects
				(font
					(size 1.27 1.27)
					(thickness 0.15)
				)
			)
		)
		(property "Author" "Antmicro"
			(at 259.642485 -30.450171 0)
			(layer "F.Fab")
			(hide yes)
			(effects
				(font
					(size 1 1)
					(thickness 0.15)
				)
			)
		)
		(property "License" "Apache-2.0"
			(at 259.642485 -30.450171 0)
			(layer "F.Fab")
			(hide yes)
			(effects
				(font
					(size 1 1)
					(thickness 0.15)
				)
			)
		)
		(property "MPN" "CR0402-FX-1002GLF"
			(at 259.642485 -30.450171 0)
			(layer "F.Fab")
			(hide yes)
			(effects
				(font
					(size 1 1)
					(thickness 0.15)
				)
			)
		)
		(property "Manufacturer" "Bourns"
			(at 259.642485 -30.450171 0)
			(layer "F.Fab")
			(hide yes)
			(effects
				(font
					(size 1 1)
					(thickness 0.15)
				)
			)
		)
		(property "Tolerance" "1%"
			(at 259.642485 -30.450171 0)
			(layer "F.Fab")
			(hide yes)
			(effects
				(font
					(size 1 1)
					(thickness 0.15)
				)
			)
		)
		(property "Val" "10k"
			(at 259.642485 -30.450171 0)
			(layer "F.Fab")
			(hide yes)
			(effects
				(font
					(size 1 1)
					(thickness 0.15)
				)
			)
		)
		(sheetname "Interfaces")
		(sheetfile "interfaces.kicad_sch")
		(attr smd)
		(fp_rect
			(start -0.93 -0.47)
			(end 0.93 0.47)
			(stroke
				(width 0.05)
				(type solid)
			)
			(fill no)
			(layer "F.CrtYd")
		)
		(fp_rect
			(start -0.5 -0.25)
			(end 0.5 0.25)
			(stroke
				(width 0.15)
				(type solid)
			)
			(fill no)
			(layer "F.Fab")
		)
		(pad "1" smd roundrect
			(at -0.485 0 90)
			(size 0.59 0.64)
			(layers "F.Cu" "F.Mask" "F.Paste")
			(roundrect_rratio 0.25)
			(net 459 "3V3_SYS")
			(pintype "passive")
		)
		(pad "2" smd roundrect
			(at 0.485 0 90)
			(size 0.59 0.64)
			(layers "F.Cu" "F.Mask" "F.Paste")
			(roundrect_rratio 0.25)
			(net 240 "Net-(U4-~{RESET})")
			(pintype "passive")
		)
	)
	(footprint "antmicro-footprints:C_0402_1005Metric"
		(layer "F.Cu")
		(at 135.1 112.099)
		(descr "Capacitor SMD 0402")
		(tags "capacitor SMD 0402")
		(property "Reference" "C13"
			(at -1.1 1.301 0)
			(layer "F.SilkS")
			(effects
				(font
					(size 0.7 0.7)
					(thickness 0.15)
				)
				(justify left bottom)
			)
		)
		(property "Value" "C_100n_6V3_0402"
			(at 0 1.4 0)
			(layer "F.Fab")
			(effects
				(font
					(size 0.7 0.7)
					(thickness 0.15)
				)
				(justify left bottom)
			)
		)
		(property "Description" " "
			(at 0 0 0)
			(layer "F.Fab")
			(hide yes)
			(effects
				(font
					(size 1.27 1.27)
					(thickness 0.15)
				)
			)
		)
		(property "Author" "Antmicro"
			(at 0 0 0)
			(layer "F.Fab")
			(hide yes)
			(effects
				(font
					(size 1 1)
					(thickness 0.15)
				)
			)
		)
		(property "Dielectric" ""
			(at 0 0 0)
			(layer "F.Fab")
			(hide yes)
			(effects
				(font
					(size 1 1)
					(thickness 0.15)
				)
			)
		)
		(property "License" "Apache-2.0"
			(at 0 0 0)
			(layer "F.Fab")
			(hide yes)
			(effects
				(font
					(size 1 1)
					(thickness 0.15)
				)
			)
		)
		(property "MPN" "0402X104K6R3CT"
			(at 0 0 0)
			(layer "F.Fab")
			(hide yes)
			(effects
				(font
					(size 1 1)
					(thickness 0.15)
				)
			)
		)
		(property "Manufacturer" "Walsin"
			(at 0 0 0)
			(layer "F.Fab")
			(hide yes)
			(effects
				(font
					(size 1 1)
					(thickness 0.15)
				)
			)
		)
		(property "Val" "100n"
			(at 0 0 0)
			(layer "F.Fab")
			(hide yes)
			(effects
				(font
					(size 1 1)
					(thickness 0.15)
				)
			)
		)
		(property "Voltage" ""
			(at 0 0 0)
			(layer "F.Fab")
			(hide yes)
			(effects
				(font
					(size 1 1)
					(thickness 0.15)
				)
			)
		)
		(sheetname "Interfaces")
		(sheetfile "interfaces.kicad_sch")
		(attr smd)
		(fp_rect
			(start -0.94 -0.47)
			(end 0.94 0.47)
			(stroke
				(width 0.05)
				(type solid)
			)
			(fill no)
			(layer "F.CrtYd")
		)
		(fp_rect
			(start -0.499 -0.249)
			(end 0.499 0.249)
			(stroke
				(width 0.15)
				(type solid)
			)
			(fill no)
			(layer "F.Fab")
		)
		(pad "1" smd roundrect
			(at -0.484 0)
			(size 0.59 0.64)
			(layers "F.Cu" "F.Mask" "F.Paste")
			(roundrect_rratio 0.25)
			(net 5 "GND")
			(pintype "passive")
		)
		(pad "2" smd roundrect
			(at 0.484 0)
			(size 0.59 0.64)
			(layers "F.Cu" "F.Mask" "F.Paste")
			(roundrect_rratio 0.25)
			(net 2 "/Interfaces/1V8_FT")
			(pintype "passive")
		)
	)
	(footprint "antmicro-footprints:Resonator_SMD_Abracon_ABM8G_3.2x2.5mm"
		(layer "F.Cu")
		(at 135.161328 116.621157 -90)
		(property "Reference" "Y1"
			(at 3.012843 0.795328 0)
			(layer "F.SilkS")
			(effects
				(font
					(size 0.7 0.7)
					(thickness 0.15)
				)
				(justify left bottom)
			)
		)
		(property "Value" "Oscillator_SMD_12MHz_KX-7"
			(at -1.75 2.548 270)
			(layer "F.Fab")
			(effects
				(font
					(size 0.7 0.7)
					(thickness 0.15)
				)
				(justify left bottom)
			)
		)
		(property "Description" "Crystal, 12 MHz, SMT, 3.2mm x 2.5mm, 30 ppm, 18 pF, 20 ppm, ABM8G"
			(at 0 0 270)
			(layer "F.Fab")
			(hide yes)
			(effects
				(font
					(size 1.27 1.27)
					(thickness 0.15)
				)
			)
		)
		(property "Author" "Antmicro"
			(at 18.540171 251.782485 0)
			(layer "F.Fab")
			(hide yes)
			(effects
				(font
					(size 1 1)
					(thickness 0.15)
				)
			)
		)
		(property "License" "Apache-2.0"
			(at 18.540171 251.782485 0)
			(layer "F.Fab")
			(hide yes)
			(effects
				(font
					(size 1 1)
					(thickness 0.15)
				)
			)
		)
		(property "MPN" "ABM8G-12.000MHZ-18-D2Y-T"
			(at 18.540171 251.782485 0)
			(layer "F.Fab")
			(hide yes)
			(effects
				(font
					(size 1 1)
					(thickness 0.15)
				)
			)
		)
		(property "Manufacturer" "Abracon"
			(at 18.540171 251.782485 0)
			(layer "F.Fab")
			(hide yes)
			(effects
				(font
					(size 1 1)
					(thickness 0.15)
				)
			)
		)
		(property "Val" "12 MHz"
			(at 18.540171 251.782485 0)
			(layer "F.Fab")
			(hide yes)
			(effects
				(font
					(size 1 1)
					(thickness 0.15)
				)
			)
		)
		(sheetname "Interfaces")
		(sheetfile "interfaces.kicad_sch")
		(attr smd)
		(fp_line
			(start -0.35 1.25)
			(end 0.45 1.25)
			(stroke
				(width 0.15)
				(type solid)
			)
			(layer "F.SilkS")
		)
		(fp_line
			(start -1.6 0.3)
			(end -1.6 -0.2)
			(stroke
				(width 0.15)
				(type solid)
			)
			(layer "F.SilkS")
		)
		(fp_line
			(start 1.6 0.3)
			(end 1.6 -0.2)
			(stroke
				(width 0.15)
				(type solid)
			)
			(layer "F.SilkS")
		)
		(fp_line
			(start -0.35 -1.25)
			(end 0.45 -1.25)
			(stroke
				(width 0.15)
				(type solid)
			)
			(layer "F.SilkS")
		)
		(fp_circle
			(center -1.75 1.5)
			(end -1.7 1.5)
			(stroke
				(width 0.15)
				(type solid)
			)
			(fill no)
			(layer "F.SilkS")
		)
		(fp_rect
			(start -1.907 -1.55)
			(end 2.006 1.649)
			(stroke
				(width 0.05)
				(type solid)
			)
			(fill no)
			(layer "F.CrtYd")
		)
		(pad "1" smd roundrect
			(at -1.101 0.949 270)
			(size 1.3 1.1)
			(layers "F.Cu" "F.Mask" "F.Paste")
			(roundrect_rratio 0)
			(chamfer_ratio 0.2)
			(chamfer bottom_left)
			(net 3 "Net-(U4-OSCI)")
			(pintype "passive")
		)
		(pad "2" smd rect
			(at 1.199 0.949 270)
			(size 1.3 1.1)
			(layers "F.Cu" "F.Mask" "F.Paste")
			(net 5 "GND")
			(pinfunction "SH")
			(pintype "passive")
		)
		(pad "3" smd rect
			(at 1.199 -0.85 270)
			(size 1.3 1.1)
			(layers "F.Cu" "F.Mask" "F.Paste")
			(net 4 "Net-(U4-OSCO)")
			(pintype "passive")
		)
		(pad "4" smd rect
			(at -1.101 -0.85 270)
			(size 1.3 1.1)
			(layers "F.Cu" "F.Mask" "F.Paste")
			(net 5 "GND")
			(pinfunction "SH")
			(pintype "passive")
		)
	)
	(footprint "antmicro-footprints:USB-Micro-B_Receptacle_WE_629105150521"
		(layer "F.Cu")
		(at 136.236328 132.796157)
		(descr "USB Micro-B receptacle")
		(tags "usb micro receptacle")
		(property "Reference" "J1"
			(at 3.209672 -4.526157 0)
			(layer "F.SilkS")
			(effects
				(font
					(size 0.7 0.7)
					(thickness 0.15)
				)
				(justify left)
			)
		)
		(property "Value" "USB-Micro-B_629105150521"
			(at 0 4.3 0)
			(layer "F.Fab")
			(effects
				(font
					(size 0.7 0.7)
					(thickness 0.15)
				)
				(justify left bottom)
			)
		)
		(property "Description" "USB - micro B USB 2.0 Receptacle Connector 5 Position Surface Mount, Right Angle"
			(at 0 0 0)
			(layer "F.Fab")
			(hide yes)
			(effects
				(font
					(size 1.27 1.27)
					(thickness 0.15)
				)
			)
		)
		(property "Author" "Antmicro"
			(at 0 0 0)
			(layer "F.Fab")
			(hide yes)
			(effects
				(font
					(size 1 1)
					(thickness 0.15)
				)
			)
		)
		(property "License" "Apache-2.0"
			(at 0 0 0)
			(layer "F.Fab")
			(hide yes)
			(effects
				(font
					(size 1 1)
					(thickness 0.15)
				)
			)
		)
		(property "MPN" "629105150521"
			(at 0 0 0)
			(layer "F.Fab")
			(hide yes)
			(effects
				(font
					(size 1 1)
					(thickness 0.15)
				)
			)
		)
		(property "Manufacturer" "Würth Elektronik"
			(at 0 0 0)
			(layer "F.Fab")
			(hide yes)
			(effects
				(font
					(size 1 1)
					(thickness 0.15)
				)
			)
		)
		(sheetname "Interfaces")
		(sheetfile "interfaces.kicad_sch")
		(attr smd)
		(fp_line
			(start -4.151 -1.7)
			(end -4.151 -0.299)
			(stroke
				(width 0.15)
				(type solid)
			)
			(layer "F.SilkS")
		)
		(fp_line
			(start -4.151 2.1)
			(end -4.151 2.25)
			(stroke
				(width 0.15)
				(type solid)
			)
			(layer "F.SilkS")
		)
		(fp_line
			(start -4.151 2.25)
			(end -3.851 2.25)
			(stroke
				(width 0.15)
				(type solid)
			)
			(layer "F.SilkS")
		)
		(fp_line
			(start -3.851 2.25)
			(end -3.851 2.701)
			(stroke
				(width 0.15)
				(type solid)
			)
			(layer "F.SilkS")
		)
		(fp_line
			(start -2.85 -3.5)
			(end -1.852 -3.5)
			(stroke
				(width 0.15)
				(type solid)
			)
			(layer "F.SilkS")
		)
		(fp_line
			(start 1.8 -3.45)
			(end 2.798 -3.45)
			(stroke
				(width 0.15)
				(type solid)
			)
			(layer "F.SilkS")
		)
		(fp_line
			(start 3.85 2.25)
			(end 4.15 2.25)
			(stroke
				(width 0.15)
				(type solid)
			)
			(layer "F.SilkS")
		)
		(fp_line
			(start 3.85 2.701)
			(end 3.85 2.25)
			(stroke
				(width 0.15)
				(type solid)
			)
			(layer "F.SilkS")
		)
		(fp_line
			(start 4.15 -0.299)
			(end 4.15 -1.7)
			(stroke
				(width 0.15)
				(type solid)
			)
			(layer "F.SilkS")
		)
		(fp_line
			(start 4.15 2.25)
			(end 4.15 2.1)
			(stroke
				(width 0.15)
				(type solid)
			)
			(layer "F.SilkS")
		)
		(fp_circle
			(center -1.7 -3.7)
			(end -1.65 -3.65)
			(stroke
				(width 0.15)
				(type solid)
			)
			(fill yes)
			(layer "F.SilkS")
		)
		(fp_rect
			(start -4.5 -3.95)
			(end 4.5 3.4)
			(stroke
				(width 0.05)
				(type solid)
			)
			(fill no)
			(layer "F.CrtYd")
		)
		(fp_line
			(start -4 -3.299)
			(end -4 2.1)
			(stroke
				(width 0.15)
				(type solid)
			)
			(layer "F.Fab")
		)
		(fp_line
			(start -4 2.1)
			(end -3.701 2.1)
			(stroke
				(width 0.15)
				(type solid)
			)
			(layer "F.Fab")
		)
		(fp_line
			(start -3.701 2.1)
			(end -3.701 3.301)
			(stroke
				(width 0.15)
				(type solid)
			)
			(layer "F.Fab")
		)
		(fp_line
			(start -3.701 3.301)
			(end 3.7 3.301)
			(stroke
				(width 0.15)
				(type solid)
			)
			(layer "F.Fab")
		)
		(fp_line
			(start 3.7 2.1)
			(end 3.999 2.1)
			(stroke
				(width 0.15)
				(type solid)
			)
			(layer "F.Fab")
		)
		(fp_line
			(start 3.7 3.301)
			(end 3.7 2.1)
			(stroke
				(width 0.15)
				(type solid)
			)
			(layer "F.Fab")
		)
		(fp_line
			(start 3.999 -3.299)
			(end -4 -3.299)
			(stroke
				(width 0.15)
				(type solid)
			)
			(layer "F.Fab")
		)
		(fp_line
			(start 3.999 2.1)
			(end 3.999 -3.299)
			(stroke
				(width 0.15)
				(type solid)
			)
			(layer "F.Fab")
		)
		(pad "" np_thru_hole oval
			(at -2.5 -1.849)
			(size 0.8 0.8)
			(drill 0.8)
			(layers "*.Cu" "*.Mask")
		)
		(pad "" np_thru_hole oval
			(at 2.499 -1.849)
			(size 0.8 0.8)
			(drill 0.8)
			(layers "*.Cu" "*.Mask")
		)
		(pad "1" smd roundrect
			(at -1.301 -2.949)
			(size 0.45 1.3)
			(layers "F.Cu" "F.Mask" "F.Paste")
			(roundrect_rratio 0.25)
			(net 1 "VBUS")
			(pinfunction "VBUS")
			(pintype "passive")
		)
		(pad "2" smd roundrect
			(at -0.652 -2.949)
			(size 0.45 1.3)
			(layers "F.Cu" "F.Mask" "F.Paste")
			(roundrect_rratio 0.25)
			(net 7 "DBG_USB_N")
			(pinfunction "D-")
			(pintype "bidirectional")
		)
		(pad "3" smd roundrect
			(at 0 -2.949)
			(size 0.45 1.3)
			(layers "F.Cu" "F.Mask" "F.Paste")
			(roundrect_rratio 0.25)
			(net 6 "DBG_USB_P")
			(pinfunction "D+")
			(pintype "bidirectional")
		)
		(pad "4" smd roundrect
			(at 0.65 -2.949)
			(size 0.45 1.3)
			(layers "F.Cu" "F.Mask" "F.Paste")
			(roundrect_rratio 0.25)
			(net 78 "unconnected-(J1-ID-Pad4)")
			(pinfunction "ID")
			(pintype "bidirectional+no_connect")
		)
		(pad "5" smd roundrect
			(at 1.3 -2.949)
			(size 0.45 1.3)
			(layers "F.Cu" "F.Mask" "F.Paste")
			(roundrect_rratio 0.25)
			(net 5 "GND")
			(pinfunction "GND")
			(pintype "power_in")
		)
		(pad "SH" thru_hole oval
			(at -3.875 0.901)
			(size 1.15 1.8)
			(drill oval 0.55 1.2)
			(layers "*.Cu" "*.Mask")
			(remove_unused_layers no)
			(net 74 "Net-(J1-SHIELD)")
			(pinfunction "SHIELD")
			(pintype "passive")
		)
		(pad "SH" thru_hole oval
			(at -3.726 -2.899)
			(size 1.45 2)
			(drill oval 0.85 1.4)
			(layers "*.Cu" "*.Mask")
			(remove_unused_layers no)
			(net 74 "Net-(J1-SHIELD)")
			(pinfunction "SHIELD")
			(pintype "passive")
		)
		(pad "SH" thru_hole oval
			(at 3.725 -2.899)
			(size 1.45 2)
			(drill oval 0.85 1.4)
			(layers "*.Cu" "*.Mask")
			(remove_unused_layers no)
			(net 74 "Net-(J1-SHIELD)")
			(pinfunction "SHIELD")
			(pintype "passive")
		)
		(pad "SH" thru_hole oval
			(at 3.874 0.901)
			(size 1.15 1.8)
			(drill oval 0.55 1.2)
			(layers "*.Cu" "*.Mask")
			(remove_unused_layers no)
			(net 74 "Net-(J1-SHIELD)")
			(pinfunction "SHIELD")
			(pintype "passive")
		)
	)
	(footprint "antmicro-footprints:SOT-723"
		(layer "F.Cu")
		(at 135.882328 125.941157 90)
		(property "Reference" "D4"
			(at -0.758843 1.717672 90)
			(layer "F.SilkS")
			(effects
				(font
					(size 0.7 0.7)
					(thickness 0.15)
				)
				(justify left bottom)
			)
		)
		(property "Value" "TPD2E009_SOT-9X3"
			(at 0 1.7 90)
			(layer "F.Fab")
			(effects
				(font
					(size 0.7 0.7)
					(thickness 0.15)
				)
				(justify left bottom)
			)
		)
		(property "Description" "2-Channel ESD Solution for High-Speed (6-Gbps) Differential Interface"
			(at 0 0 90)
			(layer "F.Fab")
			(hide yes)
			(effects
				(font
					(size 1.27 1.27)
					(thickness 0.15)
				)
			)
		)
		(property "Author" "Antmicro"
			(at 261.823485 -9.941171 0)
			(layer "F.Fab")
			(hide yes)
			(effects
				(font
					(size 1 1)
					(thickness 0.15)
				)
			)
		)
		(property "License" "Apache-2.0"
			(at 261.823485 -9.941171 0)
			(layer "F.Fab")
			(hide yes)
			(effects
				(font
					(size 1 1)
					(thickness 0.15)
				)
			)
		)
		(property "MPN" "TPD2E009DRTR"
			(at 261.823485 -9.941171 0)
			(layer "F.Fab")
			(hide yes)
			(effects
				(font
					(size 1 1)
					(thickness 0.15)
				)
			)
		)
		(property "Manufacturer" "Texas Instruments"
			(at 261.823485 -9.941171 0)
			(layer "F.Fab")
			(hide yes)
			(effects
				(font
					(size 1 1)
					(thickness 0.15)
				)
			)
		)
		(sheetname "Interfaces")
		(sheetfile "interfaces.kicad_sch")
		(attr smd)
		(fp_line
			(start 0.43 -0.63)
			(end -0.2175 -0.63)
			(stroke
				(width 0.15)
				(type solid)
			)
			(layer "F.SilkS")
		)
		(fp_line
			(start 0.43 -0.23)
			(end 0.43 -0.63)
			(stroke
				(width 0.15)
				(type solid)
			)
			(layer "F.SilkS")
		)
		(fp_line
			(start -0.43 -0.1375)
			(end -0.43 0.1375)
			(stroke
				(width 0.15)
				(type solid)
			)
			(layer "F.SilkS")
		)
		(fp_line
			(start 0.43 0.23)
			(end 0.43 0.63)
			(stroke
				(width 0.15)
				(type solid)
			)
			(layer "F.SilkS")
		)
		(fp_line
			(start 0.43 0.63)
			(end -0.22 0.63)
			(stroke
				(width 0.15)
				(type solid)
			)
			(layer "F.SilkS")
		)
		(fp_rect
			(start -0.83 -0.83)
			(end 0.83 0.83)
			(stroke
				(width 0.05)
				(type solid)
			)
			(fill no)
			(layer "F.CrtYd")
		)
		(fp_line
			(start -0.09 -0.53)
			(end -0.43 -0.19)
			(stroke
				(width 0.15)
				(type solid)
			)
			(layer "F.Fab")
		)
		(fp_line
			(start 0.424 -0.528)
			(end 0.424 0.524)
			(stroke
				(width 0.15)
				(type solid)
			)
			(layer "F.Fab")
		)
		(fp_line
			(start 0.424 0.524)
			(end -0.424 0.524)
			(stroke
				(width 0.15)
				(type solid)
			)
			(layer "F.Fab")
		)
		(fp_rect
			(start 0.424 0.524)
			(end -0.43 -0.528)
			(stroke
				(width 0.15)
				(type solid)
			)
			(fill no)
			(layer "F.Fab")
		)
		(pad "1" smd rect
			(at -0.501 -0.401)
			(size 0.3 0.4)
			(layers "F.Cu" "F.Mask" "F.Paste")
			(net 7 "DBG_USB_N")
			(pinfunction "1")
			(pintype "passive")
		)
		(pad "2" smd rect
			(at -0.501 0.399)
			(size 0.3 0.4)
			(layers "F.Cu" "F.Mask" "F.Paste")
			(net 6 "DBG_USB_P")
			(pinfunction "2")
			(pintype "passive")
		)
		(pad "3" smd rect
			(at 0.499 -0.001)
			(size 0.3 0.4)
			(layers "F.Cu" "F.Mask" "F.Paste")
			(net 5 "GND")
			(pinfunction "3")
			(pintype "passive")
		)
	)
	(footprint "antmicro-footprints:FB_0603_1608Metric"
		(layer "F.Cu")
		(at 133.292 126.508 180)
		(property "Reference" "FB3"
			(at 0.992 0.708 180)
			(layer "F.SilkS")
			(effects
				(font
					(size 0.7 0.7)
					(thickness 0.15)
				)
				(justify left bottom)
			)
		)
		(property "Value" "FB_600Z_0.5A_0603"
			(at 0 1.5 180)
			(layer "F.Fab")
			(effects
				(font
					(size 0.7 0.7)
					(thickness 0.15)
				)
				(justify left bottom)
			)
		)
		(property "Description" "Ferrite Beads WE-TMSB Suppression 240Ohm 200mA "
			(at 0 0 180)
			(layer "F.Fab")
			(hide yes)
			(effects
				(font
					(size 1.27 1.27)
					(thickness 0.15)
				)
			)
		)
		(property "Author" "Antmicro"
			(at 266.584 253.016 0)
			(layer "F.Fab")
			(hide yes)
			(effects
				(font
					(size 1 1)
					(thickness 0.15)
				)
			)
		)
		(property "License" "Apache-2.0"
			(at 266.584 253.016 0)
			(layer "F.Fab")
			(hide yes)
			(effects
				(font
					(size 1 1)
					(thickness 0.15)
				)
			)
		)
		(property "MPN" "BLM18AG601SN1D"
			(at 266.584 253.016 0)
			(layer "F.Fab")
			(hide yes)
			(effects
				(font
					(size 1 1)
					(thickness 0.15)
				)
			)
		)
		(property "Manufacturer" "Murata"
			(at 266.584 253.016 0)
			(layer "F.Fab")
			(hide yes)
			(effects
				(font
					(size 1 1)
					(thickness 0.15)
				)
			)
		)
		(sheetname "Interfaces")
		(sheetfile "interfaces.kicad_sch")
		(attr smd)
		(fp_line
			(start -0.196 0.406)
			(end 0.193 0.406)
			(stroke
				(width 0.15)
				(type solid)
			)
			(layer "F.SilkS")
		)
		(fp_line
			(start -0.196 -0.408)
			(end 0.193 -0.408)
			(stroke
				(width 0.15)
				(type solid)
			)
			(layer "F.SilkS")
		)
		(fp_rect
			(start -1.3 -0.6)
			(end 1.3 0.6)
			(stroke
				(width 0.05)
				(type solid)
			)
			(fill no)
			(layer "F.CrtYd")
		)
		(fp_line
			(start 0.8 0.406)
			(end -0.803 0.406)
			(stroke
				(width 0.15)
				(type solid)
			)
			(layer "F.Fab")
		)
		(fp_line
			(start 0.8 -0.408)
			(end 0.8 0.406)
			(stroke
				(width 0.15)
				(type solid)
			)
			(layer "F.Fab")
		)
		(fp_line
			(start 0.8 -0.408)
			(end -0.803 -0.408)
			(stroke
				(width 0.15)
				(type solid)
			)
			(layer "F.Fab")
		)
		(fp_line
			(start -0.803 0.406)
			(end -0.803 -0.408)
			(stroke
				(width 0.15)
				(type solid)
			)
			(layer "F.Fab")
		)
		(pad "1" smd roundrect
			(at -0.891 0 180)
			(size 0.762 1.09)
			(layers "F.Cu" "F.Mask" "F.Paste")
			(roundrect_rratio 0.15)
			(net 5 "GND")
			(pintype "passive")
		)
		(pad "2" smd roundrect
			(at 0.888 0 180)
			(size 0.762 1.09)
			(layers "F.Cu" "F.Mask" "F.Paste")
			(roundrect_rratio 0.15)
			(net 74 "Net-(J1-SHIELD)")
			(pintype "passive")
		)
	)
	(footprint "antmicro-footprints:R_0402_1005Metric"
		(layer "F.Cu")
		(at 148.051328 107.746157)
		(descr "Resistor SMD 0402")
		(tags "resistor SMD 0402")
		(property "Reference" "R17"
			(at 0.763672 0.428843 0)
			(layer "F.SilkS")
			(effects
				(font
					(size 0.7 0.7)
					(thickness 0.15)
				)
				(justify left bottom)
			)
		)
		(property "Value" "R_22R_0402"
			(at 0 1.4 0)
			(layer "F.Fab")
			(effects
				(font
					(size 0.7 0.7)
					(thickness 0.15)
				)
				(justify left bottom)
			)
		)
		(property "Description" "22R resistor in 0402 package with 1% tolerance"
			(at 0 0 0)
			(layer "F.Fab")
			(hide yes)
			(effects
				(font
					(size 1.27 1.27)
					(thickness 0.15)
				)
			)
		)
		(property "Author" "Antmicro"
			(at 0 0 0)
			(layer "F.Fab")
			(hide yes)
			(effects
				(font
					(size 1 1)
					(thickness 0.15)
				)
			)
		)
		(property "License" "Apache-2.0"
			(at 0 0 0)
			(layer "F.Fab")
			(hide yes)
			(effects
				(font
					(size 1 1)
					(thickness 0.15)
				)
			)
		)
		(property "MPN" "CR0402-FX-22R0GLF"
			(at 0 0 0)
			(layer "F.Fab")
			(hide yes)
			(effects
				(font
					(size 1 1)
					(thickness 0.15)
				)
			)
		)
		(property "Manufacturer" "Bourns"
			(at 0 0 0)
			(layer "F.Fab")
			(hide yes)
			(effects
				(font
					(size 1 1)
					(thickness 0.15)
				)
			)
		)
		(property "Tolerance" "1%"
			(at 0 0 0)
			(layer "F.Fab")
			(hide yes)
			(effects
				(font
					(size 1 1)
					(thickness 0.15)
				)
			)
		)
		(property "Val" "22R"
			(at 0 0 0)
			(layer "F.Fab")
			(hide yes)
			(effects
				(font
					(size 1 1)
					(thickness 0.15)
				)
			)
		)
		(sheetname "Interfaces")
		(sheetfile "interfaces.kicad_sch")
		(attr smd)
		(fp_rect
			(start -0.93 -0.47)
			(end 0.93 0.47)
			(stroke
				(width 0.05)
				(type solid)
			)
			(fill no)
			(layer "F.CrtYd")
		)
		(fp_rect
			(start -0.5 -0.25)
			(end 0.5 0.25)
			(stroke
				(width 0.15)
				(type solid)
			)
			(fill no)
			(layer "F.Fab")
		)
		(pad "1" smd roundrect
			(at -0.485 0)
			(size 0.59 0.64)
			(layers "F.Cu" "F.Mask" "F.Paste")
			(roundrect_rratio 0.25)
			(net 246 "Net-(U4-BDBUS0)")
			(pintype "passive")
		)
		(pad "2" smd roundrect
			(at 0.485 0)
			(size 0.59 0.64)
			(layers "F.Cu" "F.Mask" "F.Paste")
			(roundrect_rratio 0.25)
			(net 442 "AUX_JTAG_TCK")
			(pintype "passive")
		)
	)
	(footprint "antmicro-footprints:R_0402_1005Metric"
		(layer "F.Cu")
		(at 148.036328 106.621157)
		(descr "Resistor SMD 0402")
		(tags "resistor SMD 0402")
		(property "Reference" "R18"
			(at 0.763672 0.428843 0)
			(layer "F.SilkS")
			(effects
				(font
					(size 0.7 0.7)
					(thickness 0.15)
				)
				(justify left bottom)
			)
		)
		(property "Value" "R_22R_0402"
			(at 0 1.4 0)
			(layer "F.Fab")
			(effects
				(font
					(size 0.7 0.7)
					(thickness 0.15)
				)
				(justify left bottom)
			)
		)
		(property "Description" "22R resistor in 0402 package with 1% tolerance"
			(at 0 0 0)
			(layer "F.Fab")
			(hide yes)
			(effects
				(font
					(size 1.27 1.27)
					(thickness 0.15)
				)
			)
		)
		(property "Author" "Antmicro"
			(at 0 0 0)
			(layer "F.Fab")
			(hide yes)
			(effects
				(font
					(size 1 1)
					(thickness 0.15)
				)
			)
		)
		(property "License" "Apache-2.0"
			(at 0 0 0)
			(layer "F.Fab")
			(hide yes)
			(effects
				(font
					(size 1 1)
					(thickness 0.15)
				)
			)
		)
		(property "MPN" "CR0402-FX-22R0GLF"
			(at 0 0 0)
			(layer "F.Fab")
			(hide yes)
			(effects
				(font
					(size 1 1)
					(thickness 0.15)
				)
			)
		)
		(property "Manufacturer" "Bourns"
			(at 0 0 0)
			(layer "F.Fab")
			(hide yes)
			(effects
				(font
					(size 1 1)
					(thickness 0.15)
				)
			)
		)
		(property "Tolerance" "1%"
			(at 0 0 0)
			(layer "F.Fab")
			(hide yes)
			(effects
				(font
					(size 1 1)
					(thickness 0.15)
				)
			)
		)
		(property "Val" "22R"
			(at 0 0 0)
			(layer "F.Fab")
			(hide yes)
			(effects
				(font
					(size 1 1)
					(thickness 0.15)
				)
			)
		)
		(sheetname "Interfaces")
		(sheetfile "interfaces.kicad_sch")
		(attr smd)
		(fp_rect
			(start -0.93 -0.47)
			(end 0.93 0.47)
			(stroke
				(width 0.05)
				(type solid)
			)
			(fill no)
			(layer "F.CrtYd")
		)
		(fp_rect
			(start -0.5 -0.25)
			(end 0.5 0.25)
			(stroke
				(width 0.15)
				(type solid)
			)
			(fill no)
			(layer "F.Fab")
		)
		(pad "1" smd roundrect
			(at -0.485 0)
			(size 0.59 0.64)
			(layers "F.Cu" "F.Mask" "F.Paste")
			(roundrect_rratio 0.25)
			(net 247 "Net-(U4-BDBUS1)")
			(pintype "passive")
		)
		(pad "2" smd roundrect
			(at 0.485 0)
			(size 0.59 0.64)
			(layers "F.Cu" "F.Mask" "F.Paste")
			(roundrect_rratio 0.25)
			(net 444 "AUX_JTAG_TDI")
			(pintype "passive")
		)
	)
	(footprint "antmicro-footprints:R_0402_1005Metric"
		(layer "F.Cu")
		(at 148.036328 105.496157)
		(descr "Resistor SMD 0402")
		(tags "resistor SMD 0402")
		(property "Reference" "R19"
			(at 0.763672 0.428843 0)
			(layer "F.SilkS")
			(effects
				(font
					(size 0.7 0.7)
					(thickness 0.15)
				)
				(justify left bottom)
			)
		)
		(property "Value" "R_22R_0402"
			(at 0 1.4 0)
			(layer "F.Fab")
			(effects
				(font
					(size 0.7 0.7)
					(thickness 0.15)
				)
				(justify left bottom)
			)
		)
		(property "Description" "22R resistor in 0402 package with 1% tolerance"
			(at 0 0 0)
			(layer "F.Fab")
			(hide yes)
			(effects
				(font
					(size 1.27 1.27)
					(thickness 0.15)
				)
			)
		)
		(property "Author" "Antmicro"
			(at 0 0 0)
			(layer "F.Fab")
			(hide yes)
			(effects
				(font
					(size 1 1)
					(thickness 0.15)
				)
			)
		)
		(property "License" "Apache-2.0"
			(at 0 0 0)
			(layer "F.Fab")
			(hide yes)
			(effects
				(font
					(size 1 1)
					(thickness 0.15)
				)
			)
		)
		(property "MPN" "CR0402-FX-22R0GLF"
			(at 0 0 0)
			(layer "F.Fab")
			(hide yes)
			(effects
				(font
					(size 1 1)
					(thickness 0.15)
				)
			)
		)
		(property "Manufacturer" "Bourns"
			(at 0 0 0)
			(layer "F.Fab")
			(hide yes)
			(effects
				(font
					(size 1 1)
					(thickness 0.15)
				)
			)
		)
		(property "Tolerance" "1%"
			(at 0 0 0)
			(layer "F.Fab")
			(hide yes)
			(effects
				(font
					(size 1 1)
					(thickness 0.15)
				)
			)
		)
		(property "Val" "22R"
			(at 0 0 0)
			(layer "F.Fab")
			(hide yes)
			(effects
				(font
					(size 1 1)
					(thickness 0.15)
				)
			)
		)
		(sheetname "Interfaces")
		(sheetfile "interfaces.kicad_sch")
		(attr smd)
		(fp_rect
			(start -0.93 -0.47)
			(end 0.93 0.47)
			(stroke
				(width 0.05)
				(type solid)
			)
			(fill no)
			(layer "F.CrtYd")
		)
		(fp_rect
			(start -0.5 -0.25)
			(end 0.5 0.25)
			(stroke
				(width 0.15)
				(type solid)
			)
			(fill no)
			(layer "F.Fab")
		)
		(pad "1" smd roundrect
			(at -0.485 0)
			(size 0.59 0.64)
			(layers "F.Cu" "F.Mask" "F.Paste")
			(roundrect_rratio 0.25)
			(net 248 "Net-(U4-BDBUS2)")
			(pintype "passive")
		)
		(pad "2" smd roundrect
			(at 0.485 0)
			(size 0.59 0.64)
			(layers "F.Cu" "F.Mask" "F.Paste")
			(roundrect_rratio 0.25)
			(net 464 "AUX_JTAG_TDO")
			(pintype "passive")
		)
	)
	(footprint "antmicro-footprints:R_0402_1005Metric"
		(layer "F.Cu")
		(at 148.036328 102.121157)
		(descr "Resistor SMD 0402")
		(tags "resistor SMD 0402")
		(property "Reference" "R21"
			(at 0.763672 0.378843 0)
			(layer "F.SilkS")
			(effects
				(font
					(size 0.7 0.7)
					(thickness 0.15)
				)
				(justify left bottom)
			)
		)
		(property "Value" "R_22R_0402"
			(at 0 1.4 0)
			(layer "F.Fab")
			(effects
				(font
					(size 0.7 0.7)
					(thickness 0.15)
				)
				(justify left bottom)
			)
		)
		(property "Description" "22R resistor in 0402 package with 1% tolerance"
			(at 0 0 0)
			(layer "F.Fab")
			(hide yes)
			(effects
				(font
					(size 1.27 1.27)
					(thickness 0.15)
				)
			)
		)
		(property "Author" "Antmicro"
			(at 0 0 0)
			(layer "F.Fab")
			(hide yes)
			(effects
				(font
					(size 1 1)
					(thickness 0.15)
				)
			)
		)
		(property "License" "Apache-2.0"
			(at 0 0 0)
			(layer "F.Fab")
			(hide yes)
			(effects
				(font
					(size 1 1)
					(thickness 0.15)
				)
			)
		)
		(property "MPN" "CR0402-FX-22R0GLF"
			(at 0 0 0)
			(layer "F.Fab")
			(hide yes)
			(effects
				(font
					(size 1 1)
					(thickness 0.15)
				)
			)
		)
		(property "Manufacturer" "Bourns"
			(at 0 0 0)
			(layer "F.Fab")
			(hide yes)
			(effects
				(font
					(size 1 1)
					(thickness 0.15)
				)
			)
		)
		(property "Tolerance" "1%"
			(at 0 0 0)
			(layer "F.Fab")
			(hide yes)
			(effects
				(font
					(size 1 1)
					(thickness 0.15)
				)
			)
		)
		(property "Val" "22R"
			(at 0 0 0)
			(layer "F.Fab")
			(hide yes)
			(effects
				(font
					(size 1 1)
					(thickness 0.15)
				)
			)
		)
		(sheetname "Interfaces")
		(sheetfile "interfaces.kicad_sch")
		(attr smd)
		(fp_rect
			(start -0.93 -0.47)
			(end 0.93 0.47)
			(stroke
				(width 0.05)
				(type solid)
			)
			(fill no)
			(layer "F.CrtYd")
		)
		(fp_rect
			(start -0.5 -0.25)
			(end 0.5 0.25)
			(stroke
				(width 0.15)
				(type solid)
			)
			(fill no)
			(layer "F.Fab")
		)
		(pad "1" smd roundrect
			(at -0.485 0)
			(size 0.59 0.64)
			(layers "F.Cu" "F.Mask" "F.Paste")
			(roundrect_rratio 0.25)
			(net 250 "Net-(U4-BDBUS5)")
			(pintype "passive")
		)
		(pad "2" smd roundrect
			(at 0.485 0)
			(size 0.59 0.64)
			(layers "F.Cu" "F.Mask" "F.Paste")
			(roundrect_rratio 0.25)
			(net 449 "AUX_JTAG_RST")
			(pintype "passive")
		)
	)
	(footprint "antmicro-footprints:R_0402_1005Metric"
		(layer "F.Cu")
		(at 142.536328 100.246157 90)
		(descr "Resistor SMD 0402")
		(tags "resistor SMD 0402")
		(property "Reference" "R22"
			(at 0.746157 0.388672 90)
			(layer "F.SilkS")
			(effects
				(font
					(size 0.7 0.7)
					(thickness 0.15)
				)
				(justify left bottom)
			)
		)
		(property "Value" "R_22R_0402"
			(at 0 1.4 90)
			(layer "F.Fab")
			(effects
				(font
					(size 0.7 0.7)
					(thickness 0.15)
				)
				(justify left bottom)
			)
		)
		(property "Description" "22R resistor in 0402 package with 1% tolerance"
			(at 0 0 90)
			(layer "F.Fab")
			(hide yes)
			(effects
				(font
					(size 1.27 1.27)
					(thickness 0.15)
				)
			)
		)
		(property "Author" "Antmicro"
			(at 242.782485 -42.290171 0)
			(layer "F.Fab")
			(hide yes)
			(effects
				(font
					(size 1 1)
					(thickness 0.15)
				)
			)
		)
		(property "License" "Apache-2.0"
			(at 242.782485 -42.290171 0)
			(layer "F.Fab")
			(hide yes)
			(effects
				(font
					(size 1 1)
					(thickness 0.15)
				)
			)
		)
		(property "MPN" "CR0402-FX-22R0GLF"
			(at 242.782485 -42.290171 0)
			(layer "F.Fab")
			(hide yes)
			(effects
				(font
					(size 1 1)
					(thickness 0.15)
				)
			)
		)
		(property "Manufacturer" "Bourns"
			(at 242.782485 -42.290171 0)
			(layer "F.Fab")
			(hide yes)
			(effects
				(font
					(size 1 1)
					(thickness 0.15)
				)
			)
		)
		(property "Tolerance" "1%"
			(at 242.782485 -42.290171 0)
			(layer "F.Fab")
			(hide yes)
			(effects
				(font
					(size 1 1)
					(thickness 0.15)
				)
			)
		)
		(property "Val" "22R"
			(at 242.782485 -42.290171 0)
			(layer "F.Fab")
			(hide yes)
			(effects
				(font
					(size 1 1)
					(thickness 0.15)
				)
			)
		)
		(sheetname "Interfaces")
		(sheetfile "interfaces.kicad_sch")
		(attr smd)
		(fp_rect
			(start -0.93 -0.47)
			(end 0.93 0.47)
			(stroke
				(width 0.05)
				(type solid)
			)
			(fill no)
			(layer "F.CrtYd")
		)
		(fp_rect
			(start -0.5 -0.25)
			(end 0.5 0.25)
			(stroke
				(width 0.15)
				(type solid)
			)
			(fill no)
			(layer "F.Fab")
		)
		(pad "1" smd roundrect
			(at -0.485 0 90)
			(size 0.59 0.64)
			(layers "F.Cu" "F.Mask" "F.Paste")
			(roundrect_rratio 0.25)
			(net 251 "Net-(U4-CDBUS0)")
			(pintype "passive")
		)
		(pad "2" smd roundrect
			(at 0.485 0 90)
			(size 0.59 0.64)
			(layers "F.Cu" "F.Mask" "F.Paste")
			(roundrect_rratio 0.25)
			(net 451 "UART0_RX")
			(pintype "passive")
		)
	)
	(footprint "antmicro-footprints:R_0402_1005Metric"
		(layer "F.Cu")
		(at 141.411328 100.246157 90)
		(descr "Resistor SMD 0402")
		(tags "resistor SMD 0402")
		(property "Reference" "R23"
			(at 0.746157 0.388672 90)
			(layer "F.SilkS")
			(effects
				(font
					(size 0.7 0.7)
					(thickness 0.15)
				)
				(justify left bottom)
			)
		)
		(property "Value" "R_22R_0402"
			(at 0 1.4 90)
			(layer "F.Fab")
			(effects
				(font
					(size 0.7 0.7)
					(thickness 0.15)
				)
				(justify left bottom)
			)
		)
		(property "Description" "22R resistor in 0402 package with 1% tolerance"
			(at 0 0 90)
			(layer "F.Fab")
			(hide yes)
			(effects
				(font
					(size 1.27 1.27)
					(thickness 0.15)
				)
			)
		)
		(property "Author" "Antmicro"
			(at 241.657485 -41.165171 0)
			(layer "F.Fab")
			(hide yes)
			(effects
				(font
					(size 1 1)
					(thickness 0.15)
				)
			)
		)
		(property "License" "Apache-2.0"
			(at 241.657485 -41.165171 0)
			(layer "F.Fab")
			(hide yes)
			(effects
				(font
					(size 1 1)
					(thickness 0.15)
				)
			)
		)
		(property "MPN" "CR0402-FX-22R0GLF"
			(at 241.657485 -41.165171 0)
			(layer "F.Fab")
			(hide yes)
			(effects
				(font
					(size 1 1)
					(thickness 0.15)
				)
			)
		)
		(property "Manufacturer" "Bourns"
			(at 241.657485 -41.165171 0)
			(layer "F.Fab")
			(hide yes)
			(effects
				(font
					(size 1 1)
					(thickness 0.15)
				)
			)
		)
		(property "Tolerance" "1%"
			(at 241.657485 -41.165171 0)
			(layer "F.Fab")
			(hide yes)
			(effects
				(font
					(size 1 1)
					(thickness 0.15)
				)
			)
		)
		(property "Val" "22R"
			(at 241.657485 -41.165171 0)
			(layer "F.Fab")
			(hide yes)
			(effects
				(font
					(size 1 1)
					(thickness 0.15)
				)
			)
		)
		(sheetname "Interfaces")
		(sheetfile "interfaces.kicad_sch")
		(attr smd)
		(fp_rect
			(start -0.93 -0.47)
			(end 0.93 0.47)
			(stroke
				(width 0.05)
				(type solid)
			)
			(fill no)
			(layer "F.CrtYd")
		)
		(fp_rect
			(start -0.5 -0.25)
			(end 0.5 0.25)
			(stroke
				(width 0.15)
				(type solid)
			)
			(fill no)
			(layer "F.Fab")
		)
		(pad "1" smd roundrect
			(at -0.485 0 90)
			(size 0.59 0.64)
			(layers "F.Cu" "F.Mask" "F.Paste")
			(roundrect_rratio 0.25)
			(net 252 "Net-(U4-CDBUS1)")
			(pintype "passive")
		)
		(pad "2" smd roundrect
			(at 0.485 0 90)
			(size 0.59 0.64)
			(layers "F.Cu" "F.Mask" "F.Paste")
			(roundrect_rratio 0.25)
			(net 453 "UART0_TX")
			(pintype "passive")
		)
	)
	(footprint "antmicro-footprints:R_0402_1005Metric"
		(layer "F.Cu")
		(at 133.911328 102.621157 180)
		(descr "Resistor SMD 0402")
		(tags "resistor SMD 0402")
		(property "Reference" "R24"
			(at -0.688672 -0.378843 180)
			(layer "F.SilkS")
			(effects
				(font
					(size 0.7 0.7)
					(thickness 0.15)
				)
				(justify left bottom)
			)
		)
		(property "Value" "R_22R_0402"
			(at 0 1.4 180)
			(layer "F.Fab")
			(effects
				(font
					(size 0.7 0.7)
					(thickness 0.15)
				)
				(justify left bottom)
			)
		)
		(property "Description" "22R resistor in 0402 package with 1% tolerance"
			(at 0 0 180)
			(layer "F.Fab")
			(hide yes)
			(effects
				(font
					(size 1.27 1.27)
					(thickness 0.15)
				)
			)
		)
		(property "Author" "Antmicro"
			(at 267.822656 205.242314 0)
			(layer "F.Fab")
			(hide yes)
			(effects
				(font
					(size 1 1)
					(thickness 0.15)
				)
			)
		)
		(property "License" "Apache-2.0"
			(at 267.822656 205.242314 0)
			(layer "F.Fab")
			(hide yes)
			(effects
				(font
					(size 1 1)
					(thickness 0.15)
				)
			)
		)
		(property "MPN" "CR0402-FX-22R0GLF"
			(at 267.822656 205.242314 0)
			(layer "F.Fab")
			(hide yes)
			(effects
				(font
					(size 1 1)
					(thickness 0.15)
				)
			)
		)
		(property "Manufacturer" "Bourns"
			(at 267.822656 205.242314 0)
			(layer "F.Fab")
			(hide yes)
			(effects
				(font
					(size 1 1)
					(thickness 0.15)
				)
			)
		)
		(property "Tolerance" "1%"
			(at 267.822656 205.242314 0)
			(layer "F.Fab")
			(hide yes)
			(effects
				(font
					(size 1 1)
					(thickness 0.15)
				)
			)
		)
		(property "Val" "22R"
			(at 267.822656 205.242314 0)
			(layer "F.Fab")
			(hide yes)
			(effects
				(font
					(size 1 1)
					(thickness 0.15)
				)
			)
		)
		(sheetname "Interfaces")
		(sheetfile "interfaces.kicad_sch")
		(attr smd)
		(fp_rect
			(start -0.93 -0.47)
			(end 0.93 0.47)
			(stroke
				(width 0.05)
				(type solid)
			)
			(fill no)
			(layer "F.CrtYd")
		)
		(fp_rect
			(start -0.5 -0.25)
			(end 0.5 0.25)
			(stroke
				(width 0.15)
				(type solid)
			)
			(fill no)
			(layer "F.Fab")
		)
		(pad "1" smd roundrect
			(at -0.485 0 180)
			(size 0.59 0.64)
			(layers "F.Cu" "F.Mask" "F.Paste")
			(roundrect_rratio 0.25)
			(net 253 "Net-(U4-DDBUS0)")
			(pintype "passive")
		)
		(pad "2" smd roundrect
			(at 0.485 0 180)
			(size 0.59 0.64)
			(layers "F.Cu" "F.Mask" "F.Paste")
			(roundrect_rratio 0.25)
			(net 455 "UART1_RX")
			(pintype "passive")
		)
	)
	(footprint "antmicro-footprints:R_0402_1005Metric"
		(layer "F.Cu")
		(at 133.911328 105.871157 180)
		(descr "Resistor SMD 0402")
		(tags "resistor SMD 0402")
		(property "Reference" "R25"
			(at 2.911328 -0.428843 180)
			(layer "F.SilkS")
			(effects
				(font
					(size 0.7 0.7)
					(thickness 0.15)
				)
				(justify left bottom)
			)
		)
		(property "Value" "R_22R_0402"
			(at 0 1.4 180)
			(layer "F.Fab")
			(effects
				(font
					(size 0.7 0.7)
					(thickness 0.15)
				)
				(justify left bottom)
			)
		)
		(property "Description" "22R resistor in 0402 package with 1% tolerance"
			(at 0 0 180)
			(layer "F.Fab")
			(hide yes)
			(effects
				(font
					(size 1.27 1.27)
					(thickness 0.15)
				)
			)
		)
		(property "Author" "Antmicro"
			(at 267.822656 211.742314 0)
			(layer "F.Fab")
			(hide yes)
			(effects
				(font
					(size 1 1)
					(thickness 0.15)
				)
			)
		)
		(property "License" "Apache-2.0"
			(at 267.822656 211.742314 0)
			(layer "F.Fab")
			(hide yes)
			(effects
				(font
					(size 1 1)
					(thickness 0.15)
				)
			)
		)
		(property "MPN" "CR0402-FX-22R0GLF"
			(at 267.822656 211.742314 0)
			(layer "F.Fab")
			(hide yes)
			(effects
				(font
					(size 1 1)
					(thickness 0.15)
				)
			)
		)
		(property "Manufacturer" "Bourns"
			(at 267.822656 211.742314 0)
			(layer "F.Fab")
			(hide yes)
			(effects
				(font
					(size 1 1)
					(thickness 0.15)
				)
			)
		)
		(property "Tolerance" "1%"
			(at 267.822656 211.742314 0)
			(layer "F.Fab")
			(hide yes)
			(effects
				(font
					(size 1 1)
					(thickness 0.15)
				)
			)
		)
		(property "Val" "22R"
			(at 267.822656 211.742314 0)
			(layer "F.Fab")
			(hide yes)
			(effects
				(font
					(size 1 1)
					(thickness 0.15)
				)
			)
		)
		(sheetname "Interfaces")
		(sheetfile "interfaces.kicad_sch")
		(attr smd)
		(fp_rect
			(start -0.93 -0.47)
			(end 0.93 0.47)
			(stroke
				(width 0.05)
				(type solid)
			)
			(fill no)
			(layer "F.CrtYd")
		)
		(fp_rect
			(start -0.5 -0.25)
			(end 0.5 0.25)
			(stroke
				(width 0.15)
				(type solid)
			)
			(fill no)
			(layer "F.Fab")
		)
		(pad "1" smd roundrect
			(at -0.485 0 180)
			(size 0.59 0.64)
			(layers "F.Cu" "F.Mask" "F.Paste")
			(roundrect_rratio 0.25)
			(net 254 "Net-(U4-DDBUS1)")
			(pintype "passive")
		)
		(pad "2" smd roundrect
			(at 0.485 0 180)
			(size 0.59 0.64)
			(layers "F.Cu" "F.Mask" "F.Paste")
			(roundrect_rratio 0.25)
			(net 457 "UART1_TX")
			(pintype "passive")
		)
	)
	(footprint "antmicro-footprints:C_0402_1005Metric"
		(layer "F.Cu")
		(at 115.3492 113.622157 180)
		(descr "Capacitor SMD 0402")
		(tags "capacitor SMD 0402")
		(property "Reference" "C132"
			(at 1.8492 1.522157 180)
			(layer "F.SilkS")
			(effects
				(font
					(size 0.7 0.7)
					(thickness 0.15)
				)
				(justify left bottom)
			)
		)
		(property "Value" "C_100n_6V3_0402"
			(at 0 1.4 180)
			(layer "F.Fab")
			(effects
				(font
					(size 0.7 0.7)
					(thickness 0.15)
				)
				(justify left bottom)
			)
		)
		(property "Description" " "
			(at 0 0 180)
			(layer "F.Fab")
			(hide yes)
			(effects
				(font
					(size 1.27 1.27)
					(thickness 0.15)
				)
			)
		)
		(property "Author" "Antmicro"
			(at 230.6984 227.244314 0)
			(layer "F.Fab")
			(hide yes)
			(effects
				(font
					(size 1 1)
					(thickness 0.15)
				)
			)
		)
		(property "Dielectric" ""
			(at 230.6984 227.244314 0)
			(layer "F.Fab")
			(hide yes)
			(effects
				(font
					(size 1 1)
					(thickness 0.15)
				)
			)
		)
		(property "License" "Apache-2.0"
			(at 230.6984 227.244314 0)
			(layer "F.Fab")
			(hide yes)
			(effects
				(font
					(size 1 1)
					(thickness 0.15)
				)
			)
		)
		(property "MPN" "0402X104K6R3CT"
			(at 230.6984 227.244314 0)
			(layer "F.Fab")
			(hide yes)
			(effects
				(font
					(size 1 1)
					(thickness 0.15)
				)
			)
		)
		(property "Manufacturer" "Walsin"
			(at 230.6984 227.244314 0)
			(layer "F.Fab")
			(hide yes)
			(effects
				(font
					(size 1 1)
					(thickness 0.15)
				)
			)
		)
		(property "Val" "100n"
			(at 230.6984 227.244314 0)
			(layer "F.Fab")
			(hide yes)
			(effects
				(font
					(size 1 1)
					(thickness 0.15)
				)
			)
		)
		(property "Voltage" ""
			(at 230.6984 227.244314 0)
			(layer "F.Fab")
			(hide yes)
			(effects
				(font
					(size 1 1)
					(thickness 0.15)
				)
			)
		)
		(sheetname "Supply")
		(sheetfile "supply.kicad_sch")
		(attr smd)
		(fp_rect
			(start -0.94 -0.47)
			(end 0.94 0.47)
			(stroke
				(width 0.05)
				(type solid)
			)
			(fill no)
			(layer "F.CrtYd")
		)
		(fp_rect
			(start -0.499 -0.249)
			(end 0.499 0.249)
			(stroke
				(width 0.15)
				(type solid)
			)
			(fill no)
			(layer "F.Fab")
		)
		(pad "1" smd roundrect
			(at -0.484 0 180)
			(size 0.59 0.64)
			(layers "F.Cu" "F.Mask" "F.Paste")
			(roundrect_rratio 0.25)
			(net 42 "Net-(IC2-SW)")
			(pintype "passive")
		)
		(pad "2" smd roundrect
			(at 0.484 0 180)
			(size 0.59 0.64)
			(layers "F.Cu" "F.Mask" "F.Paste")
			(roundrect_rratio 0.25)
			(net 43 "Net-(IC2-BOOT)")
			(pintype "passive")
		)
	)
	(footprint "antmicro-footprints:R_0402_1005Metric"
		(layer "F.Cu")
		(at 110.235528 117.872157)
		(descr "Resistor SMD 0402")
		(tags "resistor SMD 0402")
		(property "Reference" "R96"
			(at -2.935528 -0.7 0)
			(layer "F.SilkS")
			(effects
				(font
					(size 0.7 0.7)
					(thickness 0.15)
				)
				(justify left bottom)
			)
		)
		(property "Value" "R_243k_0402"
			(at 0 1.4 0)
			(layer "F.Fab")
			(effects
				(font
					(size 0.7 0.7)
					(thickness 0.15)
				)
				(justify left bottom)
			)
		)
		(property "Description" "243k resistor in 0402 package with 1% tolerance"
			(at 0 0 0)
			(layer "F.Fab")
			(hide yes)
			(effects
				(font
					(size 1.27 1.27)
					(thickness 0.15)
				)
			)
		)
		(property "Author" "Antmicro"
			(at 0 0 0)
			(layer "F.Fab")
			(hide yes)
			(effects
				(font
					(size 1 1)
					(thickness 0.15)
				)
			)
		)
		(property "License" "Apache-2.0"
			(at 0 0 0)
			(layer "F.Fab")
			(hide yes)
			(effects
				(font
					(size 1 1)
					(thickness 0.15)
				)
			)
		)
		(property "MPN" "CR0402-FX-2433GLF"
			(at 0 0 0)
			(layer "F.Fab")
			(hide yes)
			(effects
				(font
					(size 1 1)
					(thickness 0.15)
				)
			)
		)
		(property "Manufacturer" "Bourns"
			(at 0 0 0)
			(layer "F.Fab")
			(hide yes)
			(effects
				(font
					(size 1 1)
					(thickness 0.15)
				)
			)
		)
		(property "Tolerance" "1%"
			(at 0 0 0)
			(layer "F.Fab")
			(hide yes)
			(effects
				(font
					(size 1 1)
					(thickness 0.15)
				)
			)
		)
		(property "Val" "243k"
			(at 0 0 0)
			(layer "F.Fab")
			(hide yes)
			(effects
				(font
					(size 1 1)
					(thickness 0.15)
				)
			)
		)
		(sheetname "Supply")
		(sheetfile "supply.kicad_sch")
		(attr smd)
		(fp_rect
			(start -0.93 -0.47)
			(end 0.93 0.47)
			(stroke
				(width 0.05)
				(type solid)
			)
			(fill no)
			(layer "F.CrtYd")
		)
		(fp_rect
			(start -0.5 -0.25)
			(end 0.5 0.25)
			(stroke
				(width 0.15)
				(type solid)
			)
			(fill no)
			(layer "F.Fab")
		)
		(pad "1" smd roundrect
			(at -0.485 0)
			(size 0.59 0.64)
			(layers "F.Cu" "F.Mask" "F.Paste")
			(roundrect_rratio 0.25)
			(net 5 "GND")
			(pintype "passive")
		)
		(pad "2" smd roundrect
			(at 0.485 0)
			(size 0.59 0.64)
			(layers "F.Cu" "F.Mask" "F.Paste")
			(roundrect_rratio 0.25)
			(net 77 "Net-(IC2-RT{slash}CLK)")
			(pintype "passive")
		)
	)
	(footprint "antmicro-footprints:R_0402_1005Metric"
		(layer "F.Cu")
		(at 118.852872 118.975 180)
		(descr "Resistor SMD 0402")
		(tags "resistor SMD 0402")
		(property "Reference" "R103"
			(at 0.952872 -2.225 180)
			(layer "F.SilkS")
			(effects
				(font
					(size 0.7 0.7)
					(thickness 0.15)
				)
				(justify left bottom)
			)
		)
		(property "Value" "R_49R9_0402"
			(at 0 1.4 180)
			(layer "F.Fab")
			(effects
				(font
					(size 0.7 0.7)
					(thickness 0.15)
				)
				(justify left bottom)
			)
		)
		(property "Description" "49R9 resistor in 0402 package with 1% tolerance"
			(at 0 0 180)
			(layer "F.Fab")
			(hide yes)
			(effects
				(font
					(size 1.27 1.27)
					(thickness 0.15)
				)
			)
		)
		(property "Author" "Antmicro"
			(at 237.705744 237.95 0)
			(layer "F.Fab")
			(hide yes)
			(effects
				(font
					(size 1 1)
					(thickness 0.15)
				)
			)
		)
		(property "License" "Apache-2.0"
			(at 237.705744 237.95 0)
			(layer "F.Fab")
			(hide yes)
			(effects
				(font
					(size 1 1)
					(thickness 0.15)
				)
			)
		)
		(property "MPN" "CR0402-FX-49R9GLF"
			(at 237.705744 237.95 0)
			(layer "F.Fab")
			(hide yes)
			(effects
				(font
					(size 1 1)
					(thickness 0.15)
				)
			)
		)
		(property "Manufacturer" "Bourns"
			(at 237.705744 237.95 0)
			(layer "F.Fab")
			(hide yes)
			(effects
				(font
					(size 1 1)
					(thickness 0.15)
				)
			)
		)
		(property "Tolerance" "1%"
			(at 237.705744 237.95 0)
			(layer "F.Fab")
			(hide yes)
			(effects
				(font
					(size 1 1)
					(thickness 0.15)
				)
			)
		)
		(property "Val" "49R9"
			(at 237.705744 237.95 0)
			(layer "F.Fab")
			(hide yes)
			(effects
				(font
					(size 1 1)
					(thickness 0.15)
				)
			)
		)
		(sheetname "Supply")
		(sheetfile "supply.kicad_sch")
		(attr smd)
		(fp_rect
			(start -0.93 -0.47)
			(end 0.93 0.47)
			(stroke
				(width 0.05)
				(type solid)
			)
			(fill no)
			(layer "F.CrtYd")
		)
		(fp_rect
			(start -0.5 -0.25)
			(end 0.5 0.25)
			(stroke
				(width 0.15)
				(type solid)
			)
			(fill no)
			(layer "F.Fab")
		)
		(pad "1" smd roundrect
			(at -0.485 0 180)
			(size 0.59 0.64)
			(layers "F.Cu" "F.Mask" "F.Paste")
			(roundrect_rratio 0.25)
			(net 55 "Net-(C141-Pad1)")
			(pintype "passive")
		)
		(pad "2" smd roundrect
			(at 0.485 0 180)
			(size 0.59 0.64)
			(layers "F.Cu" "F.Mask" "F.Paste")
			(roundrect_rratio 0.25)
			(net 244 "Net-(R103-Pad2)")
			(pintype "passive")
		)
	)
	(footprint "antmicro-footprints:PowerDI5"
		(layer "F.Cu")
		(at 127.4492 125.7 90)
		(property "Reference" "D11"
			(at -1 3.0508 90)
			(layer "F.SilkS")
			(effects
				(font
					(size 0.7 0.7)
					(thickness 0.15)
				)
				(justify left bottom)
			)
		)
		(property "Value" "PDS760"
			(at 0 3.4 270)
			(layer "F.Fab")
			(effects
				(font
					(size 0.7 0.7)
					(thickness 0.15)
				)
				(justify left bottom)
			)
		)
		(property "Description" "PDS760 Series 60 V 7 A Surface Mount Schottky Barrier Rectifier - PowerDI-5"
			(at 0 0 90)
			(layer "F.Fab")
			(hide yes)
			(effects
				(font
					(size 1.27 1.27)
					(thickness 0.15)
				)
			)
		)
		(property "Author" "Antmicro"
			(at 253.1492 -1.7492 0)
			(layer "F.Fab")
			(hide yes)
			(effects
				(font
					(size 1 1)
					(thickness 0.15)
				)
			)
		)
		(property "License" "Apache-2.0"
			(at 253.1492 -1.7492 0)
			(layer "F.Fab")
			(hide yes)
			(effects
				(font
					(size 1 1)
					(thickness 0.15)
				)
			)
		)
		(property "MPN" "PDS760-13"
			(at 253.1492 -1.7492 0)
			(layer "F.Fab")
			(hide yes)
			(effects
				(font
					(size 1 1)
					(thickness 0.15)
				)
			)
		)
		(property "Manufacturer" "Diodes Incorporated"
			(at 253.1492 -1.7492 0)
			(layer "F.Fab")
			(hide yes)
			(effects
				(font
					(size 1 1)
					(thickness 0.15)
				)
			)
		)
		(sheetname "Supply")
		(sheetfile "supply.kicad_sch")
		(attr smd)
		(fp_line
			(start 2.7 -2)
			(end 2.7 -1.8)
			(stroke
				(width 0.12)
				(type solid)
			)
			(layer "F.SilkS")
		)
		(fp_line
			(start -2.7 -2)
			(end 2.7 -2)
			(stroke
				(width 0.12)
				(type solid)
			)
			(layer "F.SilkS")
		)
		(fp_line
			(start -2.7 -1.8)
			(end -2.7 -2)
			(stroke
				(width 0.12)
				(type solid)
			)
			(layer "F.SilkS")
		)
		(fp_line
			(start 2.7 1.823)
			(end 2.7 2.023)
			(stroke
				(width 0.12)
				(type solid)
			)
			(layer "F.SilkS")
		)
		(fp_line
			(start 2.7 2.023)
			(end -2.7 2.023)
			(stroke
				(width 0.12)
				(type solid)
			)
			(layer "F.SilkS")
		)
		(fp_line
			(start -2.7 2.023)
			(end -2.7 1.823)
			(stroke
				(width 0.12)
				(type solid)
			)
			(layer "F.SilkS")
		)
		(fp_rect
			(start -3.702 -2.3)
			(end 3.7 2.3)
			(stroke
				(width 0.05)
				(type solid)
			)
			(fill no)
			(layer "F.CrtYd")
		)
		(pad "A" smd roundrect
			(at -2.862 -0.94 180)
			(size 1.39 1.4)
			(layers "F.Cu" "F.Mask" "F.Paste")
			(roundrect_rratio 0.25)
			(net 5 "GND")
			(pinfunction "A")
			(pintype "passive")
		)
		(pad "A" smd roundrect
			(at -2.862 0.941)
			(size 1.39 1.4)
			(layers "F.Cu" "F.Mask" "F.Paste")
			(roundrect_rratio 0.25)
			(net 5 "GND")
			(pinfunction "A")
			(pintype "passive")
		)
		(pad "C" smd roundrect
			(at 1.1 0)
			(size 3.36 4.86)
			(layers "F.Cu" "F.Mask" "F.Paste")
			(roundrect_rratio 0.05)
			(net 42 "Net-(IC2-SW)")
			(pinfunction "C")
			(pintype "passive")
		)
	)
	(footprint "antmicro-footprints:L_WE-PDF-1064"
		(layer "F.Cu")
		(at 126.860528 115.747157 90)
		(property "Reference" "L1"
			(at -6.252843 4.139472 0)
			(layer "F.SilkS")
			(effects
				(font
					(size 0.7 0.7)
					(thickness 0.15)
				)
				(justify left bottom)
			)
		)
		(property "Value" "L_7u2_7.9A_WE-PDF"
			(at 0 6.6 270)
			(layer "F.Fab")
			(effects
				(font
					(size 0.7 0.7)
					(thickness 0.15)
				)
				(justify left bottom)
			)
		)
		(property "Author" "Antmicro"
			(at 242.607685 -11.113371 0)
			(layer "F.Fab")
			(hide yes)
			(effects
				(font
					(size 1 1)
					(thickness 0.15)
				)
			)
		)
		(property "IMax" ""
			(at 242.607685 -11.113371 0)
			(layer "F.Fab")
			(hide yes)
			(effects
				(font
					(size 1 1)
					(thickness 0.15)
				)
			)
		)
		(property "ISat" ""
			(at 242.607685 -11.113371 0)
			(layer "F.Fab")
			(hide yes)
			(effects
				(font
					(size 1 1)
					(thickness 0.15)
				)
			)
		)
		(property "License" "Apache-2.0"
			(at 242.607685 -11.113371 0)
			(layer "F.Fab")
			(hide yes)
			(effects
				(font
					(size 1 1)
					(thickness 0.15)
				)
			)
		)
		(property "MPN" "7447798720"
			(at 242.607685 -11.113371 0)
			(layer "F.Fab")
			(hide yes)
			(effects
				(font
					(size 1 1)
					(thickness 0.15)
				)
			)
		)
		(property "Manufacturer" "Würth Elektronik"
			(at 242.607685 -11.113371 0)
			(layer "F.Fab")
			(hide yes)
			(effects
				(font
					(size 1 1)
					(thickness 0.15)
				)
			)
		)
		(property "Size" "10.2x10.2"
			(at 242.607685 -11.113371 0)
			(layer "F.Fab")
			(hide yes)
			(effects
				(font
					(size 1 1)
					(thickness 0.15)
				)
			)
		)
		(property "Val" "7u2/7.9A"
			(at 242.607685 -11.113371 0)
			(layer "F.Fab")
			(hide yes)
			(effects
				(font
					(size 1 1)
					(thickness 0.15)
				)
			)
		)
		(sheetname "Supply")
		(sheetfile "supply.kicad_sch")
		(attr smd)
		(fp_line
			(start 4.099 -5.202)
			(end 5.2 -4.1)
			(stroke
				(width 0.15)
				(type solid)
			)
			(layer "F.SilkS")
		)
		(fp_line
			(start -5.202 -5.202)
			(end 4.099 -5.202)
			(stroke
				(width 0.15)
				(type solid)
			)
			(layer "F.SilkS")
		)
		(fp_line
			(start 5.2 -4.1)
			(end 5.2 -2)
			(stroke
				(width 0.15)
				(type solid)
			)
			(layer "F.SilkS")
		)
		(fp_line
			(start -5.202 -2)
			(end -5.202 -5.202)
			(stroke
				(width 0.15)
				(type solid)
			)
			(layer "F.SilkS")
		)
		(fp_line
			(start 5.2 1.999)
			(end 5.2 4.2)
			(stroke
				(width 0.15)
				(type solid)
			)
			(layer "F.SilkS")
		)
		(fp_line
			(start 5.2 4.2)
			(end 5.2 5.2)
			(stroke
				(width 0.15)
				(type solid)
			)
			(layer "F.SilkS")
		)
		(fp_line
			(start 5.2 5.2)
			(end -5.202 5.2)
			(stroke
				(width 0.15)
				(type solid)
			)
			(layer "F.SilkS")
		)
		(fp_line
			(start -5.202 5.2)
			(end -5.202 1.999)
			(stroke
				(width 0.15)
				(type solid)
			)
			(layer "F.SilkS")
		)
		(fp_rect
			(start -5.601 -5.601)
			(end 5.599 5.599)
			(stroke
				(width 0.05)
				(type solid)
			)
			(fill no)
			(layer "F.CrtYd")
		)
		(pad "1" smd rect
			(at -4.1 0 180)
			(size 3.4 2.4)
			(layers "F.Cu" "F.Mask" "F.Paste")
			(net 42 "Net-(IC2-SW)")
			(pintype "passive")
		)
		(pad "2" smd rect
			(at 4.099 0 180)
			(size 3.4 2.4)
			(layers "F.Cu" "F.Mask" "F.Paste")
			(net 55 "Net-(C141-Pad1)")
			(pintype "passive")
		)
	)
	(footprint "antmicro-footprints:WSON-10-1EP_4x4mm_P0.8mm_EP2.6x3mm"
		(layer "F.Cu")
		(at 114.235528 116.297157)
		(property "Reference" "IC2"
			(at -2.635528 -0.497157 270)
			(layer "F.SilkS")
			(effects
				(font
					(size 0.7 0.7)
					(thickness 0.15)
				)
				(justify left bottom)
			)
		)
		(property "Value" "TPS54561QDPRRQ1"
			(at 0 3.4 180)
			(layer "F.Fab")
			(effects
				(font
					(size 0.7 0.7)
					(thickness 0.15)
				)
				(justify left bottom)
			)
		)
		(property "Description" " 4.5-V to 60-V Input, 5-A, Step-Down DC-DC Converter"
			(at 0 0 0)
			(layer "F.Fab")
			(hide yes)
			(effects
				(font
					(size 1.27 1.27)
					(thickness 0.15)
				)
			)
		)
		(property "Author" "Antmicro"
			(at 0 0 0)
			(layer "F.Fab")
			(hide yes)
			(effects
				(font
					(size 1 1)
					(thickness 0.15)
				)
			)
		)
		(property "License" "Apache-2.0"
			(at 0 0 0)
			(layer "F.Fab")
			(hide yes)
			(effects
				(font
					(size 1 1)
					(thickness 0.15)
				)
			)
		)
		(property "MPN" "TPS54561QDPRRQ1"
			(at 0 0 0)
			(layer "F.Fab")
			(hide yes)
			(effects
				(font
					(size 1 1)
					(thickness 0.15)
				)
			)
		)
		(property "Manufacturer" "Texas Instruments"
			(at 0 0 0)
			(layer "F.Fab")
			(hide yes)
			(effects
				(font
					(size 1 1)
					(thickness 0.15)
				)
			)
		)
		(sheetname "Supply")
		(sheetfile "supply.kicad_sch")
		(attr smd)
		(fp_line
			(start -2.1 -2.123)
			(end -2.1 -1.877)
			(stroke
				(width 0.15)
				(type solid)
			)
			(layer "F.SilkS")
		)
		(fp_line
			(start -2.1 -2.123)
			(end 2.1 -2.123)
			(stroke
				(width 0.15)
				(type solid)
			)
			(layer "F.SilkS")
		)
		(fp_line
			(start -2.1 2.096)
			(end -2.1 1.85)
			(stroke
				(width 0.15)
				(type solid)
			)
			(layer "F.SilkS")
		)
		(fp_line
			(start 2.1 -2.123)
			(end 2.1 -1.877)
			(stroke
				(width 0.15)
				(type solid)
			)
			(layer "F.SilkS")
		)
		(fp_line
			(start 2.1 2.122)
			(end -2.1 2.122)
			(stroke
				(width 0.15)
				(type solid)
			)
			(layer "F.SilkS")
		)
		(fp_line
			(start 2.1 2.122)
			(end 2.1 1.876)
			(stroke
				(width 0.15)
				(type solid)
			)
			(layer "F.SilkS")
		)
		(fp_circle
			(center -2.4 -2)
			(end -2.35 -2)
			(stroke
				(width 0.15)
				(type solid)
			)
			(fill yes)
			(layer "F.SilkS")
		)
		(fp_rect
			(start -2.57 -2.2)
			(end 2.469 2.2)
			(stroke
				(width 0.05)
				(type solid)
			)
			(fill no)
			(layer "F.CrtYd")
		)
		(fp_line
			(start -1.7 -2)
			(end -2 -1.7)
			(stroke
				(width 0.15)
				(type solid)
			)
			(layer "F.Fab")
		)
		(fp_rect
			(start -2.02 -2)
			(end 2.02 2)
			(stroke
				(width 0.15)
				(type solid)
			)
			(fill no)
			(layer "F.Fab")
		)
		(pad "1" smd roundrect
			(at -2.039 -1.603 90)
			(size 0.356 0.85)
			(layers "F.Cu" "F.Mask" "F.Paste")
			(roundrect_rratio 0.25)
			(net 43 "Net-(IC2-BOOT)")
			(pinfunction "BOOT")
			(pintype "passive")
		)
		(pad "2" smd roundrect
			(at -2.039 -0.804 90)
			(size 0.356 0.85)
			(layers "F.Cu" "F.Mask" "F.Paste")
			(roundrect_rratio 0.25)
			(net 224 "VIN")
			(pinfunction "VDD")
			(pintype "passive")
		)
		(pad "3" smd roundrect
			(at -2.039 -0.003 90)
			(size 0.356 0.85)
			(layers "F.Cu" "F.Mask" "F.Paste")
			(roundrect_rratio 0.25)
			(net 514 "/Supply/SYS_EN")
			(pinfunction "EN")
			(pintype "passive")
		)
		(pad "4" smd roundrect
			(at -2.039 0.797 90)
			(size 0.356 0.85)
			(layers "F.Cu" "F.Mask" "F.Paste")
			(roundrect_rratio 0.25)
			(net 39 "Net-(IC2-SS{slash}TR)")
			(pinfunction "SS/TR")
			(pintype "passive")
		)
		(pad "5" smd roundrect
			(at -2.039 1.596 90)
			(size 0.356 0.85)
			(layers "F.Cu" "F.Mask" "F.Paste")
			(roundrect_rratio 0.25)
			(net 77 "Net-(IC2-RT{slash}CLK)")
			(pinfunction "RT/CLK")
			(pintype "passive")
		)
		(pad "6" smd roundrect
			(at 1.961 1.596 90)
			(size 0.356 0.85)
			(layers "F.Cu" "F.Mask" "F.Paste")
			(roundrect_rratio 0.25)
			(net 660 "/Supply/5V0_FB")
			(pinfunction "FB")
			(pintype "passive")
		)
		(pad "7" smd roundrect
			(at 1.961 0.797 90)
			(size 0.356 0.85)
			(layers "F.Cu" "F.Mask" "F.Paste")
			(roundrect_rratio 0.25)
			(net 40 "Net-(IC2-COMP)")
			(pinfunction "COMP")
			(pintype "passive")
		)
		(pad "8" smd roundrect
			(at 1.961 -0.003 90)
			(size 0.356 0.85)
			(layers "F.Cu" "F.Mask" "F.Paste")
			(roundrect_rratio 0.25)
			(net 5 "GND")
			(pinfunction "GND")
			(pintype "power_in")
		)
		(pad "9" smd roundrect
			(at 1.961 -0.804 90)
			(size 0.356 0.85)
			(layers "F.Cu" "F.Mask" "F.Paste")
			(roundrect_rratio 0.25)
			(net 42 "Net-(IC2-SW)")
			(pinfunction "SW")
			(pintype "passive")
		)
		(pad "10" smd roundrect
			(at 1.961 -1.603 90)
			(size 0.356 0.85)
			(layers "F.Cu" "F.Mask" "F.Paste")
			(roundrect_rratio 0.25)
			(net 466 "SYS_ON")
			(pinfunction "PWRGD")
			(pintype "passive")
		)
		(pad "11" smd roundrect
			(at -0.038 -0.003 180)
			(size 2.6 3)
			(layers "F.Cu" "F.Mask" "F.Paste")
			(roundrect_rratio 0.05)
			(net 5 "GND")
			(pinfunction "GND")
			(pintype "passive")
		)
	)
	(footprint "antmicro-footprints:BarrelJack_Pin2mm_MJ-179PH"
		(layer "F.Cu")
		(at 118.4 122.45 -90)
		(property "Reference" "J6"
			(at -4.862 -0.784 90)
			(layer "F.SilkS")
			(effects
				(font
					(size 0.7 0.7)
					(thickness 0.15)
				)
				(justify right top)
			)
		)
		(property "Value" "BarrelJack_3167288"
			(at 0 15.4 90)
			(layer "F.Fab")
			(effects
				(font
					(size 0.7 0.7)
					(thickness 0.15)
				)
				(justify right top)
			)
		)
		(property "Description" "DC Power Connector, Jack, 4 A, 1.95 mm, PCB Mount, Through Hole"
			(at 0 0 90)
			(layer "F.Fab")
			(hide yes)
			(effects
				(font
					(size 1.27 1.27)
					(thickness 0.15)
				)
			)
		)
		(property "Author" "Antmicro"
			(at 0 0 90)
			(layer "F.Fab")
			(hide yes)
			(effects
				(font
					(size 1 1)
					(thickness 0.15)
				)
			)
		)
		(property "License" "Apache-2.0"
			(at 0 0 90)
			(layer "F.Fab")
			(hide yes)
			(effects
				(font
					(size 1 1)
					(thickness 0.15)
				)
			)
		)
		(property "MPN" "MJ-179PH"
			(at 0 0 90)
			(layer "F.Fab")
			(hide yes)
			(effects
				(font
					(size 1 1)
					(thickness 0.15)
				)
			)
		)
		(property "Manufacturer" "Multicomp Pro"
			(at 0 0 90)
			(layer "F.Fab")
			(hide yes)
			(effects
				(font
					(size 1 1)
					(thickness 0.15)
				)
			)
		)
		(sheetname "Supply")
		(sheetfile "supply.kicad_sch")
		(attr through_hole)
		(fp_line
			(start -0.1 4.8)
			(end -0.1 2.4)
			(stroke
				(width 0.15)
				(type solid)
			)
			(layer "F.SilkS")
		)
		(fp_line
			(start 10.1 4.8)
			(end 10.1 -4.8)
			(stroke
				(width 0.15)
				(type solid)
			)
			(layer "F.SilkS")
		)
		(fp_line
			(start 14 4.8)
			(end -0.1 4.8)
			(stroke
				(width 0.15)
				(type solid)
			)
			(layer "F.SilkS")
		)
		(fp_line
			(start 14 4.8)
			(end 14 -4.8)
			(stroke
				(width 0.15)
				(type solid)
			)
			(layer "F.SilkS")
		)
		(fp_line
			(start -0.1 -2.4)
			(end -0.1 -4.8)
			(stroke
				(width 0.15)
				(type solid)
			)
			(layer "F.SilkS")
		)
		(fp_line
			(start -0.1 -4.8)
			(end 0.8255 -4.8)
			(stroke
				(width 0.15)
				(type solid)
			)
			(layer "F.SilkS")
		)
		(fp_line
			(start 14 -4.8)
			(end 5.1 -4.8)
			(stroke
				(width 0.15)
				(type solid)
			)
			(layer "F.SilkS")
		)
		(fp_line
			(start -0.4 5.1)
			(end 14.3 5.1)
			(stroke
				(width 0.05)
				(type solid)
			)
			(layer "F.CrtYd")
		)
		(fp_line
			(start 14.3 5.1)
			(end 14.3 -5.1)
			(stroke
				(width 0.05)
				(type solid)
			)
			(layer "F.CrtYd")
		)
		(fp_line
			(start -1.3 2.5)
			(end -0.4 2.5)
			(stroke
				(width 0.05)
				(type solid)
			)
			(layer "F.CrtYd")
		)
		(fp_line
			(start -0.4 2.5)
			(end -0.4 5.1)
			(stroke
				(width 0.05)
				(type solid)
			)
			(layer "F.CrtYd")
		)
		(fp_line
			(start -1.3 -2.5)
			(end -1.3 2.5)
			(stroke
				(width 0.05)
				(type solid)
			)
			(layer "F.CrtYd")
		)
		(fp_line
			(start -0.4 -2.5)
			(end -1.3 -2.5)
			(stroke
				(width 0.05)
				(type solid)
			)
			(layer "F.CrtYd")
		)
		(fp_line
			(start -0.4 -5.1)
			(end -0.4 -2.5)
			(stroke
				(width 0.05)
				(type solid)
			)
			(layer "F.CrtYd")
		)
		(fp_line
			(start 0.7 -5.1)
			(end -0.4 -5.1)
			(stroke
				(width 0.05)
				(type solid)
			)
			(layer "F.CrtYd")
		)
		(fp_line
			(start 5.2 -5.1)
			(end 5.2 -6.1)
			(stroke
				(width 0.05)
				(type solid)
			)
			(layer "F.CrtYd")
		)
		(fp_line
			(start 14.3 -5.1)
			(end 5.2 -5.1)
			(stroke
				(width 0.05)
				(type solid)
			)
			(layer "F.CrtYd")
		)
		(fp_line
			(start 0.7 -6.1)
			(end 0.7 -5.1)
			(stroke
				(width 0.05)
				(type solid)
			)
			(layer "F.CrtYd")
		)
		(fp_line
			(start 5.2 -6.1)
			(end 0.7 -6.1)
			(stroke
				(width 0.05)
				(type solid)
			)
			(layer "F.CrtYd")
		)
		(fp_line
			(start -0.4 3.6)
			(end 0.5 4.5)
			(stroke
				(width 0.15)
				(type solid)
			)
			(layer "F.Fab")
		)
		(fp_rect
			(start -0.4 4.5)
			(end 13.7 -5.111)
			(stroke
				(width 0.15)
				(type solid)
			)
			(fill no)
			(layer "F.Fab")
		)
		(fp_text user "Author: Antmicro"
			(at -5.1 17.601 90)
			(layer "F.Fab")
			(effects
				(font
					(size 0.7 0.7)
					(thickness 0.15)
				)
				(justify right top)
			)
		)
		(fp_text user "License: Apache-2.0"
			(at -5.1 18.802 90)
			(layer "F.Fab")
			(effects
				(font
					(size 0.7 0.7)
					(thickness 0.15)
				)
				(justify right top)
			)
		)
		(fp_text user "${REFERENCE}"
			(at -5.1 16.4 90)
			(layer "F.Fab")
			(effects
				(font
					(size 0.7 0.7)
					(thickness 0.15)
				)
				(justify right top)
			)
		)
		(pad "1" thru_hole oval
			(at 0 0 270)
			(size 2 4.5)
			(drill oval 1 3.5)
			(layers "*.Cu" "*.Mask")
			(remove_unused_layers no)
			(net 76 "Net-(J6-Pad1)")
			(pinfunction "1")
			(pintype "passive")
		)
		(pad "2" thru_hole oval
			(at 2.948 -4.879 180)
			(size 1.99 4)
			(drill oval 1 3)
			(layers "*.Cu" "*.Mask")
			(remove_unused_layers no)
			(net 5 "GND")
			(pinfunction "2")
			(pintype "passive")
		)
		(pad "3" thru_hole oval
			(at 5.999 0 90)
			(size 2 4)
			(drill oval 1 3)
			(layers "*.Cu" "*.Mask")
			(remove_unused_layers no)
			(net 5 "GND")
			(pinfunction "3")
			(pintype "passive")
		)
	)
	(footprint "antmicro-footprints:C_0402_1005Metric"
		(layer "F.Cu")
		(at 117.387872 117.475 90)
		(descr "Capacitor SMD 0402")
		(tags "capacitor SMD 0402")
		(property "Reference" "C131"
			(at 1.975 0.412128 180)
			(layer "F.SilkS")
			(effects
				(font
					(size 0.7 0.7)
					(thickness 0.15)
				)
				(justify left bottom)
			)
		)
		(property "Value" "C_47p_0402"
			(at 0 1.4 90)
			(layer "F.Fab")
			(effects
				(font
					(size 0.7 0.7)
					(thickness 0.15)
				)
				(justify left bottom)
			)
		)
		(property "Description" " "
			(at 0 0 90)
			(layer "F.Fab")
			(hide yes)
			(effects
				(font
					(size 1.27 1.27)
					(thickness 0.15)
				)
			)
		)
		(property "Author" "Antmicro"
			(at 234.862872 0.087128 0)
			(layer "F.Fab")
			(hide yes)
			(effects
				(font
					(size 1 1)
					(thickness 0.15)
				)
			)
		)
		(property "Dielectric" "C0G"
			(at 234.862872 0.087128 0)
			(layer "F.Fab")
			(hide yes)
			(effects
				(font
					(size 1 1)
					(thickness 0.15)
				)
			)
		)
		(property "License" "Apache-2.0"
			(at 234.862872 0.087128 0)
			(layer "F.Fab")
			(hide yes)
			(effects
				(font
					(size 1 1)
					(thickness 0.15)
				)
			)
		)
		(property "MPN" "GRM1555C1E470JA01D"
			(at 234.862872 0.087128 0)
			(layer "F.Fab")
			(hide yes)
			(effects
				(font
					(size 1 1)
					(thickness 0.15)
				)
			)
		)
		(property "Manufacturer" "Murata"
			(at 234.862872 0.087128 0)
			(layer "F.Fab")
			(hide yes)
			(effects
				(font
					(size 1 1)
					(thickness 0.15)
				)
			)
		)
		(property "Val" "47p"
			(at 234.862872 0.087128 0)
			(layer "F.Fab")
			(hide yes)
			(effects
				(font
					(size 1 1)
					(thickness 0.15)
				)
			)
		)
		(property "Voltage" ""
			(at 234.862872 0.087128 0)
			(layer "F.Fab")
			(hide yes)
			(effects
				(font
					(size 1 1)
					(thickness 0.15)
				)
			)
		)
		(sheetname "Supply")
		(sheetfile "supply.kicad_sch")
		(attr smd)
		(fp_rect
			(start -0.94 -0.47)
			(end 0.94 0.47)
			(stroke
				(width 0.05)
				(type solid)
			)
			(fill no)
			(layer "F.CrtYd")
		)
		(fp_rect
			(start -0.499 -0.249)
			(end 0.499 0.249)
			(stroke
				(width 0.15)
				(type solid)
			)
			(fill no)
			(layer "F.Fab")
		)
		(pad "1" smd roundrect
			(at -0.484 0 90)
			(size 0.59 0.64)
			(layers "F.Cu" "F.Mask" "F.Paste")
			(roundrect_rratio 0.25)
			(net 40 "Net-(IC2-COMP)")
			(pintype "passive")
		)
		(pad "2" smd roundrect
			(at 0.484 0 90)
			(size 0.59 0.64)
			(layers "F.Cu" "F.Mask" "F.Paste")
			(roundrect_rratio 0.25)
			(net 5 "GND")
			(pintype "passive")
		)
	)
	(footprint "antmicro-footprints:TP_SMD_1mm"
		(layer "F.Cu")
		(at 109.65 119.35 90)
		(property "Reference" "TP9"
			(at -0.15 0.35 180)
			(layer "F.SilkS")
			(effects
				(font
					(size 0.7 0.7)
					(thickness 0.15)
				)
				(justify left bottom)
			)
		)
		(property "Value" "TP_1mm_SMD"
			(at 0 1.4 90)
			(layer "F.Fab")
			(effects
				(font
					(size 0.7 0.7)
					(thickness 0.15)
				)
				(justify left bottom)
			)
		)
		(property "Description" "Test Point 1mm"
			(at 0 0 90)
			(layer "F.Fab")
			(hide yes)
			(effects
				(font
					(size 1.27 1.27)
					(thickness 0.15)
				)
			)
		)
		(property "Author" "Antmicro"
			(at 229 9.7 0)
			(layer "F.Fab")
			(hide yes)
			(effects
				(font
					(size 1 1)
					(thickness 0.15)
				)
			)
		)
		(property "License" "Apache-2.0"
			(at 229 9.7 0)
			(layer "F.Fab")
			(hide yes)
			(effects
				(font
					(size 1 1)
					(thickness 0.15)
				)
			)
		)
		(property "MPN" ""
			(at 229 9.7 0)
			(layer "F.Fab")
			(hide yes)
			(effects
				(font
					(size 1 1)
					(thickness 0.15)
				)
			)
		)
		(property "Manufacturer" ""
			(at 229 9.7 0)
			(layer "F.Fab")
			(hide yes)
			(effects
				(font
					(size 1 1)
					(thickness 0.15)
				)
			)
		)
		(sheetname "Supply")
		(sheetfile "supply.kicad_sch")
		(attr exclude_from_pos_files)
		(pad "1" smd circle
			(at 0 0 90)
			(size 1 1)
			(layers "F.Cu" "F.Mask")
			(net 514 "/Supply/SYS_EN")
			(pinfunction "1")
			(pintype "passive")
		)
	)
	(footprint "antmicro-footprints:R_0402_1005Metric"
		(layer "F.Cu")
		(at 116.9492 120 180)
		(descr "Resistor SMD 0402")
		(tags "resistor SMD 0402")
		(property "Reference" "R105"
			(at 3.6142 -0.525 180)
			(layer "F.SilkS")
			(effects
				(font
					(size 0.7 0.7)
					(thickness 0.15)
				)
				(justify left bottom)
			)
		)
		(property "Value" "R_10k2_0402"
			(at 0 1.4 180)
			(layer "F.Fab")
			(effects
				(font
					(size 0.7 0.7)
					(thickness 0.15)
				)
				(justify left bottom)
			)
		)
		(property "Description" "10k2 resistor in 0402 package with 1% tolerance"
			(at 0 0 180)
			(layer "F.Fab")
			(hide yes)
			(effects
				(font
					(size 1.27 1.27)
					(thickness 0.15)
				)
			)
		)
		(property "Author" "Antmicro"
			(at 233.8984 240 0)
			(layer "F.Fab")
			(hide yes)
			(effects
				(font
					(size 1 1)
					(thickness 0.15)
				)
			)
		)
		(property "License" "Apache-2.0"
			(at 233.8984 240 0)
			(layer "F.Fab")
			(hide yes)
			(effects
				(font
					(size 1 1)
					(thickness 0.15)
				)
			)
		)
		(property "MPN" "CR0402-FX-1022GLF"
			(at 233.8984 240 0)
			(layer "F.Fab")
			(hide yes)
			(effects
				(font
					(size 1 1)
					(thickness 0.15)
				)
			)
		)
		(property "Manufacturer" "Bourns"
			(at 233.8984 240 0)
			(layer "F.Fab")
			(hide yes)
			(effects
				(font
					(size 1 1)
					(thickness 0.15)
				)
			)
		)
		(property "Tolerance" "1%"
			(at 233.8984 240 0)
			(layer "F.Fab")
			(hide yes)
			(effects
				(font
					(size 1 1)
					(thickness 0.15)
				)
			)
		)
		(property "Val" "10k2"
			(at 233.8984 240 0)
			(layer "F.Fab")
			(hide yes)
			(effects
				(font
					(size 1 1)
					(thickness 0.15)
				)
			)
		)
		(sheetname "Supply")
		(sheetfile "supply.kicad_sch")
		(attr smd)
		(fp_rect
			(start -0.93 -0.47)
			(end 0.93 0.47)
			(stroke
				(width 0.05)
				(type solid)
			)
			(fill no)
			(layer "F.CrtYd")
		)
		(fp_rect
			(start -0.5 -0.25)
			(end 0.5 0.25)
			(stroke
				(width 0.15)
				(type solid)
			)
			(fill no)
			(layer "F.Fab")
		)
		(pad "1" smd roundrect
			(at -0.485 0 180)
			(size 0.59 0.64)
			(layers "F.Cu" "F.Mask" "F.Paste")
			(roundrect_rratio 0.25)
			(net 660 "/Supply/5V0_FB")
			(pintype "passive")
		)
		(pad "2" smd roundrect
			(at 0.485 0 180)
			(size 0.59 0.64)
			(layers "F.Cu" "F.Mask" "F.Paste")
			(roundrect_rratio 0.25)
			(net 5 "GND")
			(pintype "passive")
		)
	)
	(footprint "antmicro-footprints:R_0402_1005Metric"
		(layer "F.Cu")
		(at 190.889171 122.574485 180)
		(descr "Resistor SMD 0402")
		(tags "resistor SMD 0402")
		(property "Reference" "R94"
			(at 0.989171 -1.325515 180)
			(layer "F.SilkS")
			(effects
				(font
					(size 0.7 0.7)
					(thickness 0.15)
				)
				(justify left bottom)
			)
		)
		(property "Value" "R_330R_0402"
			(at 0 1.4 180)
			(layer "F.Fab")
			(effects
				(font
					(size 0.7 0.7)
					(thickness 0.15)
				)
				(justify left bottom)
			)
		)
		(property "Description" "330R resistor in 0402 package with 1% tolerance"
			(at 0 0 180)
			(layer "F.Fab")
			(hide yes)
			(effects
				(font
					(size 1.27 1.27)
					(thickness 0.15)
				)
			)
		)
		(property "Author" "Antmicro"
			(at 381.778342 245.14897 0)
			(layer "F.Fab")
			(hide yes)
			(effects
				(font
					(size 1 1)
					(thickness 0.15)
				)
			)
		)
		(property "License" "Apache-2.0"
			(at 381.778342 245.14897 0)
			(layer "F.Fab")
			(hide yes)
			(effects
				(font
					(size 1 1)
					(thickness 0.15)
				)
			)
		)
		(property "MPN" "CR0402-FX-3300GLF"
			(at 381.778342 245.14897 0)
			(layer "F.Fab")
			(hide yes)
			(effects
				(font
					(size 1 1)
					(thickness 0.15)
				)
			)
		)
		(property "Manufacturer" "Bourns"
			(at 381.778342 245.14897 0)
			(layer "F.Fab")
			(hide yes)
			(effects
				(font
					(size 1 1)
					(thickness 0.15)
				)
			)
		)
		(property "Tolerance" "1%"
			(at 381.778342 245.14897 0)
			(layer "F.Fab")
			(hide yes)
			(effects
				(font
					(size 1 1)
					(thickness 0.15)
				)
			)
		)
		(property "Val" "330R"
			(at 381.778342 245.14897 0)
			(layer "F.Fab")
			(hide yes)
			(effects
				(font
					(size 1 1)
					(thickness 0.15)
				)
			)
		)
		(sheetname "Supply")
		(sheetfile "supply.kicad_sch")
		(attr smd)
		(fp_rect
			(start -0.93 -0.47)
			(end 0.93 0.47)
			(stroke
				(width 0.05)
				(type solid)
			)
			(fill no)
			(layer "F.CrtYd")
		)
		(fp_rect
			(start -0.5 -0.25)
			(end 0.5 0.25)
			(stroke
				(width 0.15)
				(type solid)
			)
			(fill no)
			(layer "F.Fab")
		)
		(pad "1" smd roundrect
			(at -0.485 0 180)
			(size 0.59 0.64)
			(layers "F.Cu" "F.Mask" "F.Paste")
			(roundrect_rratio 0.25)
			(net 229 "Net-(PWR1-Pad2)")
			(pintype "passive")
		)
		(pad "2" smd roundrect
			(at 0.485 0 180)
			(size 0.59 0.64)
			(layers "F.Cu" "F.Mask" "F.Paste")
			(roundrect_rratio 0.25)
			(net 5 "GND")
			(pintype "passive")
		)
	)
	(footprint "antmicro-footprints:TP_SMD_1mm"
		(layer "F.Cu")
		(at 135 101.124)
		(property "Reference" "TP14"
			(at -0.1 -0.324 90)
			(layer "F.SilkS")
			(effects
				(font
					(size 0.7 0.7)
					(thickness 0.15)
				)
				(justify left bottom)
			)
		)
		(property "Value" "TP_1mm_SMD"
			(at 0 1.4 0)
			(layer "F.Fab")
			(effects
				(font
					(size 0.7 0.7)
					(thickness 0.15)
				)
				(justify left bottom)
			)
		)
		(property "Description" "Test Point 1mm"
			(at 0 0 0)
			(layer "F.Fab")
			(hide yes)
			(effects
				(font
					(size 1.27 1.27)
					(thickness 0.15)
				)
			)
		)
		(property "Author" "Antmicro"
			(at 0 0 0)
			(layer "F.Fab")
			(hide yes)
			(effects
				(font
					(size 1 1)
					(thickness 0.15)
				)
			)
		)
		(property "License" "Apache-2.0"
			(at 0 0 0)
			(layer "F.Fab")
			(hide yes)
			(effects
				(font
					(size 1 1)
					(thickness 0.15)
				)
			)
		)
		(property "MPN" ""
			(at 0 0 0)
			(layer "F.Fab")
			(hide yes)
			(effects
				(font
					(size 1 1)
					(thickness 0.15)
				)
			)
		)
		(property "Manufacturer" ""
			(at 0 0 0)
			(layer "F.Fab")
			(hide yes)
			(effects
				(font
					(size 1 1)
					(thickness 0.15)
				)
			)
		)
		(sheetname "Supply")
		(sheetfile "supply.kicad_sch")
		(attr exclude_from_pos_files)
		(pad "1" smd circle
			(at 0 0)
			(size 1 1)
			(layers "F.Cu" "F.Mask")
			(net 459 "3V3_SYS")
			(pinfunction "1")
			(pintype "passive")
		)
	)
	(footprint "antmicro-footprints:C_0402_1005Metric"
		(layer "F.Cu")
		(at 110.235528 116.747157 180)
		(descr "Capacitor SMD 0402")
		(tags "capacitor SMD 0402")
		(property "Reference" "C130"
			(at 2.735528 -3.252843 225)
			(layer "F.SilkS")
			(effects
				(font
					(size 0.7 0.7)
					(thickness 0.15)
				)
				(justify left bottom)
			)
		)
		(property "Value" "C_10n_0402"
			(at 0 1.4 180)
			(layer "F.Fab")
			(effects
				(font
					(size 0.7 0.7)
					(thickness 0.15)
				)
				(justify left bottom)
			)
		)
		(property "Description" " "
			(at 0 0 180)
			(layer "F.Fab")
			(hide yes)
			(effects
				(font
					(size 1.27 1.27)
					(thickness 0.15)
				)
			)
		)
		(property "Author" "Antmicro"
			(at 220.471056 233.494314 0)
			(layer "F.Fab")
			(hide yes)
			(effects
				(font
					(size 1 1)
					(thickness 0.15)
				)
			)
		)
		(property "Dielectric" "X7R"
			(at 220.471056 233.494314 0)
			(layer "F.Fab")
			(hide yes)
			(effects
				(font
					(size 1 1)
					(thickness 0.15)
				)
			)
		)
		(property "License" "Apache-2.0"
			(at 220.471056 233.494314 0)
			(layer "F.Fab")
			(hide yes)
			(effects
				(font
					(size 1 1)
					(thickness 0.15)
				)
			)
		)
		(property "MPN" "GRM155R71H103KA88D"
			(at 220.471056 233.494314 0)
			(layer "F.Fab")
			(hide yes)
			(effects
				(font
					(size 1 1)
					(thickness 0.15)
				)
			)
		)
		(property "Manufacturer" "Murata"
			(at 220.471056 233.494314 0)
			(layer "F.Fab")
			(hide yes)
			(effects
				(font
					(size 1 1)
					(thickness 0.15)
				)
			)
		)
		(property "Val" "10n"
			(at 220.471056 233.494314 0)
			(layer "F.Fab")
			(hide yes)
			(effects
				(font
					(size 1 1)
					(thickness 0.15)
				)
			)
		)
		(property "Voltage" "50V"
			(at 220.471056 233.494314 0)
			(layer "F.Fab")
			(hide yes)
			(effects
				(font
					(size 1 1)
					(thickness 0.15)
				)
			)
		)
		(sheetname "Supply")
		(sheetfile "supply.kicad_sch")
		(attr smd)
		(fp_rect
			(start -0.94 -0.47)
			(end 0.94 0.47)
			(stroke
				(width 0.05)
				(type solid)
			)
			(fill no)
			(layer "F.CrtYd")
		)
		(fp_rect
			(start -0.499 -0.249)
			(end 0.499 0.249)
			(stroke
				(width 0.15)
				(type solid)
			)
			(fill no)
			(layer "F.Fab")
		)
		(pad "1" smd roundrect
			(at -0.484 0 180)
			(size 0.59 0.64)
			(layers "F.Cu" "F.Mask" "F.Paste")
			(roundrect_rratio 0.25)
			(net 39 "Net-(IC2-SS{slash}TR)")
			(pintype "passive")
		)
		(pad "2" smd roundrect
			(at 0.484 0 180)
			(size 0.59 0.64)
			(layers "F.Cu" "F.Mask" "F.Paste")
			(roundrect_rratio 0.25)
			(net 5 "GND")
			(pintype "passive")
		)
	)
	(footprint "antmicro-footprints:C_0402_1005Metric"
		(layer "F.Cu")
		(at 118.8492 116.975 180)
		(descr "Capacitor SMD 0402")
		(tags "capacitor SMD 0402")
		(property "Reference" "C129"
			(at 0.9492 -3.225 180)
			(layer "F.SilkS")
			(effects
				(font
					(size 0.7 0.7)
					(thickness 0.15)
				)
				(justify left bottom)
			)
		)
		(property "Value" "C_4n7_0402"
			(at 0 1.4 180)
			(layer "F.Fab")
			(effects
				(font
					(size 0.7 0.7)
					(thickness 0.15)
				)
				(justify left bottom)
			)
		)
		(property "Description" " "
			(at 0 0 180)
			(layer "F.Fab")
			(hide yes)
			(effects
				(font
					(size 1.27 1.27)
					(thickness 0.15)
				)
			)
		)
		(property "Author" "Antmicro"
			(at 237.6984 233.95 0)
			(layer "F.Fab")
			(hide yes)
			(effects
				(font
					(size 1 1)
					(thickness 0.15)
				)
			)
		)
		(property "Dielectric" ""
			(at 237.6984 233.95 0)
			(layer "F.Fab")
			(hide yes)
			(effects
				(font
					(size 1 1)
					(thickness 0.15)
				)
			)
		)
		(property "License" "Apache-2.0"
			(at 237.6984 233.95 0)
			(layer "F.Fab")
			(hide yes)
			(effects
				(font
					(size 1 1)
					(thickness 0.15)
				)
			)
		)
		(property "MPN" "CGA2B3X7S2A472K050BB"
			(at 237.6984 233.95 0)
			(layer "F.Fab")
			(hide yes)
			(effects
				(font
					(size 1 1)
					(thickness 0.15)
				)
			)
		)
		(property "Manufacturer" "TDK"
			(at 237.6984 233.95 0)
			(layer "F.Fab")
			(hide yes)
			(effects
				(font
					(size 1 1)
					(thickness 0.15)
				)
			)
		)
		(property "Val" "4n7"
			(at 237.6984 233.95 0)
			(layer "F.Fab")
			(hide yes)
			(effects
				(font
					(size 1 1)
					(thickness 0.15)
				)
			)
		)
		(property "Voltage" ""
			(at 237.6984 233.95 0)
			(layer "F.Fab")
			(hide yes)
			(effects
				(font
					(size 1 1)
					(thickness 0.15)
				)
			)
		)
		(sheetname "Supply")
		(sheetfile "supply.kicad_sch")
		(attr smd)
		(fp_rect
			(start -0.94 -0.47)
			(end 0.94 0.47)
			(stroke
				(width 0.05)
				(type solid)
			)
			(fill no)
			(layer "F.CrtYd")
		)
		(fp_rect
			(start -0.499 -0.249)
			(end 0.499 0.249)
			(stroke
				(width 0.15)
				(type solid)
			)
			(fill no)
			(layer "F.Fab")
		)
		(pad "1" smd roundrect
			(at -0.484 0 180)
			(size 0.59 0.64)
			(layers "F.Cu" "F.Mask" "F.Paste")
			(roundrect_rratio 0.25)
			(net 41 "Net-(C129-Pad1)")
			(pintype "passive")
		)
		(pad "2" smd roundrect
			(at 0.484 0 180)
			(size 0.59 0.64)
			(layers "F.Cu" "F.Mask" "F.Paste")
			(roundrect_rratio 0.25)
			(net 5 "GND")
			(pintype "passive")
		)
	)
	(footprint "antmicro-footprints:R_0402_1005Metric"
		(layer "F.Cu")
		(at 118.8492 117.975)
		(descr "Resistor SMD 0402")
		(tags "resistor SMD 0402")
		(property "Reference" "R95"
			(at -0.9492 -1.475 0)
			(layer "F.SilkS")
			(effects
				(font
					(size 0.7 0.7)
					(thickness 0.15)
				)
				(justify left bottom)
			)
		)
		(property "Value" "R_16k9_0402"
			(at 0 1.4 0)
			(layer "F.Fab")
			(effects
				(font
					(size 0.7 0.7)
					(thickness 0.15)
				)
				(justify left bottom)
			)
		)
		(property "Description" "16k9 resistor in 0402 package with 1% tolerance"
			(at 0 0 0)
			(layer "F.Fab")
			(hide yes)
			(effects
				(font
					(size 1.27 1.27)
					(thickness 0.15)
				)
			)
		)
		(property "Author" "Antmicro"
			(at 0 0 0)
			(layer "F.Fab")
			(hide yes)
			(effects
				(font
					(size 1 1)
					(thickness 0.15)
				)
			)
		)
		(property "License" "Apache-2.0"
			(at 0 0 0)
			(layer "F.Fab")
			(hide yes)
			(effects
				(font
					(size 1 1)
					(thickness 0.15)
				)
			)
		)
		(property "MPN" "CR0402-FX-1692GLF"
			(at 0 0 0)
			(layer "F.Fab")
			(hide yes)
			(effects
				(font
					(size 1 1)
					(thickness 0.15)
				)
			)
		)
		(property "Manufacturer" "Bourns"
			(at 0 0 0)
			(layer "F.Fab")
			(hide yes)
			(effects
				(font
					(size 1 1)
					(thickness 0.15)
				)
			)
		)
		(property "Tolerance" "1%"
			(at 0 0 0)
			(layer "F.Fab")
			(hide yes)
			(effects
				(font
					(size 1 1)
					(thickness 0.15)
				)
			)
		)
		(property "Val" "16k9"
			(at 0 0 0)
			(layer "F.Fab")
			(hide yes)
			(effects
				(font
					(size 1 1)
					(thickness 0.15)
				)
			)
		)
		(sheetname "Supply")
		(sheetfile "supply.kicad_sch")
		(attr smd)
		(fp_rect
			(start -0.93 -0.47)
			(end 0.93 0.47)
			(stroke
				(width 0.05)
				(type solid)
			)
			(fill no)
			(layer "F.CrtYd")
		)
		(fp_rect
			(start -0.5 -0.25)
			(end 0.5 0.25)
			(stroke
				(width 0.15)
				(type solid)
			)
			(fill no)
			(layer "F.Fab")
		)
		(pad "1" smd roundrect
			(at -0.485 0)
			(size 0.59 0.64)
			(layers "F.Cu" "F.Mask" "F.Paste")
			(roundrect_rratio 0.25)
			(net 40 "Net-(IC2-COMP)")
			(pintype "passive")
		)
		(pad "2" smd roundrect
			(at 0.485 0)
			(size 0.59 0.64)
			(layers "F.Cu" "F.Mask" "F.Paste")
			(roundrect_rratio 0.25)
			(net 41 "Net-(C129-Pad1)")
			(pintype "passive")
		)
	)
	(footprint "antmicro-footprints:LED_0603_1608Metric_G"
		(layer "F.Cu")
		(at 190.639171 121.074485)
		(descr "LED SMD 0603 Green")
		(tags "LED SMD 0603 Green")
		(property "Reference" "PWR1"
			(at -0.639171 -2.074485 0)
			(layer "F.SilkS")
			(effects
				(font
					(size 0.7 0.7)
					(thickness 0.15)
				)
				(justify left bottom)
			)
		)
		(property "Value" "LED_G_0603_KP-1608CGCK"
			(at 0 1.6 0)
			(layer "F.Fab")
			(effects
				(font
					(size 0.7 0.7)
					(thickness 0.15)
				)
				(justify left bottom)
			)
		)
		(property "Author" "Antmicro"
			(at 0 0 0)
			(layer "F.Fab")
			(hide yes)
			(effects
				(font
					(size 1 1)
					(thickness 0.15)
				)
			)
		)
		(property "License" "Apache-2.0"
			(at 0 0 0)
			(layer "F.Fab")
			(hide yes)
			(effects
				(font
					(size 1 1)
					(thickness 0.15)
				)
			)
		)
		(property "MPN" "KP-1608CGCK"
			(at 0 0 0)
			(layer "F.Fab")
			(hide yes)
			(effects
				(font
					(size 1 1)
					(thickness 0.15)
				)
			)
		)
		(property "Manufacturer" "Kingbright"
			(at 0 0 0)
			(layer "F.Fab")
			(hide yes)
			(effects
				(font
					(size 1 1)
					(thickness 0.15)
				)
			)
		)
		(sheetname "Supply")
		(sheetfile "supply.kicad_sch")
		(attr smd)
		(fp_line
			(start -0.27 -0.35)
			(end 0.27 -0.35)
			(stroke
				(width 0.15)
				(type solid)
			)
			(layer "F.SilkS")
		)
		(fp_line
			(start -0.27 0.351)
			(end 0.27 0.351)
			(stroke
				(width 0.15)
				(type solid)
			)
			(layer "F.SilkS")
		)
		(fp_line
			(start -0.106328 -0.200008)
			(end -0.106328 0.199992)
			(stroke
				(width 0.1)
				(type solid)
			)
			(layer "F.SilkS")
		)
		(fp_line
			(start -0.106328 -0.200008)
			(end 0.093672 -8e-06)
			(stroke
				(width 0.1)
				(type solid)
			)
			(layer "F.SilkS")
		)
		(fp_line
			(start -0.106328 -8e-06)
			(end -0.29 0)
			(stroke
				(width 0.1)
				(type solid)
			)
			(layer "F.SilkS")
		)
		(fp_line
			(start 0.093672 -0.200008)
			(end 0.093672 0.199992)
			(stroke
				(width 0.1)
				(type solid)
			)
			(layer "F.SilkS")
		)
		(fp_line
			(start 0.093672 -8e-06)
			(end -0.106328 0.199992)
			(stroke
				(width 0.1)
				(type solid)
			)
			(layer "F.SilkS")
		)
		(fp_line
			(start 0.093672 -8e-06)
			(end 0.293672 -8e-06)
			(stroke
				(width 0.1)
				(type solid)
			)
			(layer "F.SilkS")
		)
		(fp_line
			(start 1.25 0.32)
			(end 1.25 -0.32)
			(stroke
				(width 0.15)
				(type solid)
			)
			(layer "F.SilkS")
		)
		(fp_rect
			(start 1.26 0.65)
			(end -1.26 -0.65)
			(stroke
				(width 0.05)
				(type solid)
			)
			(fill no)
			(layer "F.CrtYd")
		)
		(fp_line
			(start -0.599 0)
			(end -0.201 0)
			(stroke
				(width 0.15)
				(type solid)
			)
			(layer "F.Fab")
		)
		(fp_line
			(start -0.201 -0.2)
			(end -0.201 0)
			(stroke
				(width 0.15)
				(type solid)
			)
			(layer "F.Fab")
		)
		(fp_line
			(start -0.201 0)
			(end -0.201 0.202)
			(stroke
				(width 0.15)
				(type solid)
			)
			(layer "F.Fab")
		)
		(fp_line
			(start -0.201 0.202)
			(end 0.101 0)
			(stroke
				(width 0.15)
				(type solid)
			)
			(layer "F.Fab")
		)
		(fp_line
			(start 0.101 0)
			(end -0.201 -0.2)
			(stroke
				(width 0.15)
				(type solid)
			)
			(layer "F.Fab")
		)
		(fp_line
			(start 0.199 -0.2)
			(end 0.199 -0.1)
			(stroke
				(width 0.15)
				(type solid)
			)
			(layer "F.Fab")
		)
		(fp_line
			(start 0.199 0)
			(end 0.597 0)
			(stroke
				(width 0.15)
				(type solid)
			)
			(layer "F.Fab")
		)
		(fp_line
			(start 0.199 0.202)
			(end 0.199 -0.1)
			(stroke
				(width 0.15)
				(type solid)
			)
			(layer "F.Fab")
		)
		(fp_rect
			(start -0.848 -0.4)
			(end 0.85 0.402)
			(stroke
				(width 0.15)
				(type solid)
			)
			(fill no)
			(layer "F.Fab")
		)
		(pad "1" smd rect
			(at -0.75 0 180)
			(size 0.8 0.8)
			(layers "F.Cu" "F.Mask" "F.Paste")
			(net 459 "3V3_SYS")
			(pinfunction "1")
			(pintype "passive")
		)
		(pad "2" smd rect
			(at 0.75 0 180)
			(size 0.8 0.8)
			(layers "F.Cu" "F.Mask" "F.Paste")
			(net 229 "Net-(PWR1-Pad2)")
			(pinfunction "2")
			(pintype "passive")
		)
	)
	(footprint "antmicro-footprints:R_0402_1005Metric"
		(layer "F.Cu")
		(at 148.036328 104.371157)
		(descr "Resistor SMD 0402")
		(tags "resistor SMD 0402")
		(property "Reference" "R20"
			(at 0.763672 0.428843 0)
			(layer "F.SilkS")
			(effects
				(font
					(size 0.7 0.7)
					(thickness 0.15)
				)
				(justify left bottom)
			)
		)
		(property "Value" "R_22R_0402"
			(at 0 1.4 0)
			(layer "F.Fab")
			(effects
				(font
					(size 0.7 0.7)
					(thickness 0.15)
				)
				(justify left bottom)
			)
		)
		(property "Description" "22R resistor in 0402 package with 1% tolerance"
			(at 0 0 0)
			(layer "F.Fab")
			(hide yes)
			(effects
				(font
					(size 1.27 1.27)
					(thickness 0.15)
				)
			)
		)
		(property "Author" "Antmicro"
			(at 0 0 0)
			(layer "F.Fab")
			(hide yes)
			(effects
				(font
					(size 1 1)
					(thickness 0.15)
				)
			)
		)
		(property "License" "Apache-2.0"
			(at 0 0 0)
			(layer "F.Fab")
			(hide yes)
			(effects
				(font
					(size 1 1)
					(thickness 0.15)
				)
			)
		)
		(property "MPN" "CR0402-FX-22R0GLF"
			(at 0 0 0)
			(layer "F.Fab")
			(hide yes)
			(effects
				(font
					(size 1 1)
					(thickness 0.15)
				)
			)
		)
		(property "Manufacturer" "Bourns"
			(at 0 0 0)
			(layer "F.Fab")
			(hide yes)
			(effects
				(font
					(size 1 1)
					(thickness 0.15)
				)
			)
		)
		(property "Tolerance" "1%"
			(at 0 0 0)
			(layer "F.Fab")
			(hide yes)
			(effects
				(font
					(size 1 1)
					(thickness 0.15)
				)
			)
		)
		(property "Val" "22R"
			(at 0 0 0)
			(layer "F.Fab")
			(hide yes)
			(effects
				(font
					(size 1 1)
					(thickness 0.15)
				)
			)
		)
		(sheetname "Interfaces")
		(sheetfile "interfaces.kicad_sch")
		(attr smd)
		(fp_rect
			(start -0.93 -0.47)
			(end 0.93 0.47)
			(stroke
				(width 0.05)
				(type solid)
			)
			(fill no)
			(layer "F.CrtYd")
		)
		(fp_rect
			(start -0.5 -0.25)
			(end 0.5 0.25)
			(stroke
				(width 0.15)
				(type solid)
			)
			(fill no)
			(layer "F.Fab")
		)
		(pad "1" smd roundrect
			(at -0.485 0)
			(size 0.59 0.64)
			(layers "F.Cu" "F.Mask" "F.Paste")
			(roundrect_rratio 0.25)
			(net 249 "Net-(U4-BDBUS3)")
			(pintype "passive")
		)
		(pad "2" smd roundrect
			(at 0.485 0)
			(size 0.59 0.64)
			(layers "F.Cu" "F.Mask" "F.Paste")
			(roundrect_rratio 0.25)
			(net 447 "AUX_JTAG_TMS")
			(pintype "passive")
		)
	)
	(footprint "antmicro-footprints:R_0402_1005Metric"
		(layer "F.Cu")
		(at 148.056328 109.831157)
		(descr "Resistor SMD 0402")
		(tags "resistor SMD 0402")
		(property "Reference" "R16"
			(at 0.763672 0.428843 0)
			(layer "F.SilkS")
			(effects
				(font
					(size 0.7 0.7)
					(thickness 0.15)
				)
				(justify left bottom)
			)
		)
		(property "Value" "R_22R_0402"
			(at 0 1.4 0)
			(layer "F.Fab")
			(effects
				(font
					(size 0.7 0.7)
					(thickness 0.15)
				)
				(justify left bottom)
			)
		)
		(property "Description" "22R resistor in 0402 package with 1% tolerance"
			(at 0 0 0)
			(layer "F.Fab")
			(hide yes)
			(effects
				(font
					(size 1.27 1.27)
					(thickness 0.15)
				)
			)
		)
		(property "Author" "Antmicro"
			(at 0 0 0)
			(layer "F.Fab")
			(hide yes)
			(effects
				(font
					(size 1 1)
					(thickness 0.15)
				)
			)
		)
		(property "License" "Apache-2.0"
			(at 0 0 0)
			(layer "F.Fab")
			(hide yes)
			(effects
				(font
					(size 1 1)
					(thickness 0.15)
				)
			)
		)
		(property "MPN" "CR0402-FX-22R0GLF"
			(at 0 0 0)
			(layer "F.Fab")
			(hide yes)
			(effects
				(font
					(size 1 1)
					(thickness 0.15)
				)
			)
		)
		(property "Manufacturer" "Bourns"
			(at 0 0 0)
			(layer "F.Fab")
			(hide yes)
			(effects
				(font
					(size 1 1)
					(thickness 0.15)
				)
			)
		)
		(property "Tolerance" "1%"
			(at 0 0 0)
			(layer "F.Fab")
			(hide yes)
			(effects
				(font
					(size 1 1)
					(thickness 0.15)
				)
			)
		)
		(property "Val" "22R"
			(at 0 0 0)
			(layer "F.Fab")
			(hide yes)
			(effects
				(font
					(size 1 1)
					(thickness 0.15)
				)
			)
		)
		(sheetname "Interfaces")
		(sheetfile "interfaces.kicad_sch")
		(attr smd)
		(fp_rect
			(start -0.93 -0.47)
			(end 0.93 0.47)
			(stroke
				(width 0.05)
				(type solid)
			)
			(fill no)
			(layer "F.CrtYd")
		)
		(fp_rect
			(start -0.5 -0.25)
			(end 0.5 0.25)
			(stroke
				(width 0.15)
				(type solid)
			)
			(fill no)
			(layer "F.Fab")
		)
		(pad "1" smd roundrect
			(at -0.485 0)
			(size 0.59 0.64)
			(layers "F.Cu" "F.Mask" "F.Paste")
			(roundrect_rratio 0.25)
			(net 245 "Net-(U4-ADBUS3)")
			(pintype "passive")
		)
		(pad "2" smd roundrect
			(at 0.485 0)
			(size 0.59 0.64)
			(layers "F.Cu" "F.Mask" "F.Paste")
			(roundrect_rratio 0.25)
			(net 9 "TMS_JTAG")
			(pintype "passive")
		)
	)
	(footprint "antmicro-footprints:R_0402_1005Metric"
		(layer "F.Cu")
		(at 148.056328 110.906157)
		(descr "Resistor SMD 0402")
		(tags "resistor SMD 0402")
		(property "Reference" "R15"
			(at 0.763672 0.428843 0)
			(layer "F.SilkS")
			(effects
				(font
					(size 0.7 0.7)
					(thickness 0.15)
				)
				(justify left bottom)
			)
		)
		(property "Value" "R_22R_0402"
			(at 0 1.4 0)
			(layer "F.Fab")
			(effects
				(font
					(size 0.7 0.7)
					(thickness 0.15)
				)
				(justify left bottom)
			)
		)
		(property "Description" "22R resistor in 0402 package with 1% tolerance"
			(at 0 0 0)
			(layer "F.Fab")
			(hide yes)
			(effects
				(font
					(size 1.27 1.27)
					(thickness 0.15)
				)
			)
		)
		(property "Author" "Antmicro"
			(at 0 0 0)
			(layer "F.Fab")
			(hide yes)
			(effects
				(font
					(size 1 1)
					(thickness 0.15)
				)
			)
		)
		(property "License" "Apache-2.0"
			(at 0 0 0)
			(layer "F.Fab")
			(hide yes)
			(effects
				(font
					(size 1 1)
					(thickness 0.15)
				)
			)
		)
		(property "MPN" "CR0402-FX-22R0GLF"
			(at 0 0 0)
			(layer "F.Fab")
			(hide yes)
			(effects
				(font
					(size 1 1)
					(thickness 0.15)
				)
			)
		)
		(property "Manufacturer" "Bourns"
			(at 0 0 0)
			(layer "F.Fab")
			(hide yes)
			(effects
				(font
					(size 1 1)
					(thickness 0.15)
				)
			)
		)
		(property "Tolerance" "1%"
			(at 0 0 0)
			(layer "F.Fab")
			(hide yes)
			(effects
				(font
					(size 1 1)
					(thickness 0.15)
				)
			)
		)
		(property "Val" "22R"
			(at 0 0 0)
			(layer "F.Fab")
			(hide yes)
			(effects
				(font
					(size 1 1)
					(thickness 0.15)
				)
			)
		)
		(sheetname "Interfaces")
		(sheetfile "interfaces.kicad_sch")
		(attr smd)
		(fp_rect
			(start -0.93 -0.47)
			(end 0.93 0.47)
			(stroke
				(width 0.05)
				(type solid)
			)
			(fill no)
			(layer "F.CrtYd")
		)
		(fp_rect
			(start -0.5 -0.25)
			(end 0.5 0.25)
			(stroke
				(width 0.15)
				(type solid)
			)
			(fill no)
			(layer "F.Fab")
		)
		(pad "1" smd roundrect
			(at -0.485 0)
			(size 0.59 0.64)
			(layers "F.Cu" "F.Mask" "F.Paste")
			(roundrect_rratio 0.25)
			(net 243 "Net-(U4-ADBUS2)")
			(pintype "passive")
		)
		(pad "2" smd roundrect
			(at 0.485 0)
			(size 0.59 0.64)
			(layers "F.Cu" "F.Mask" "F.Paste")
			(roundrect_rratio 0.25)
			(net 11 "TDO_JTAG")
			(pintype "passive")
		)
	)
	(footprint "antmicro-footprints:R_0402_1005Metric"
		(layer "F.Cu")
		(at 148.056328 111.981157)
		(descr "Resistor SMD 0402")
		(tags "resistor SMD 0402")
		(property "Reference" "R14"
			(at 0.763672 0.428843 0)
			(layer "F.SilkS")
			(effects
				(font
					(size 0.7 0.7)
					(thickness 0.15)
				)
				(justify left bottom)
			)
		)
		(property "Value" "R_22R_0402"
			(at 0 1.4 0)
			(layer "F.Fab")
			(effects
				(font
					(size 0.7 0.7)
					(thickness 0.15)
				)
				(justify left bottom)
			)
		)
		(property "Description" "22R resistor in 0402 package with 1% tolerance"
			(at 0 0 0)
			(layer "F.Fab")
			(hide yes)
			(effects
				(font
					(size 1.27 1.27)
					(thickness 0.15)
				)
			)
		)
		(property "Author" "Antmicro"
			(at 0 0 0)
			(layer "F.Fab")
			(hide yes)
			(effects
				(font
					(size 1 1)
					(thickness 0.15)
				)
			)
		)
		(property "License" "Apache-2.0"
			(at 0 0 0)
			(layer "F.Fab")
			(hide yes)
			(effects
				(font
					(size 1 1)
					(thickness 0.15)
				)
			)
		)
		(property "MPN" "CR0402-FX-22R0GLF"
			(at 0 0 0)
			(layer "F.Fab")
			(hide yes)
			(effects
				(font
					(size 1 1)
					(thickness 0.15)
				)
			)
		)
		(property "Manufacturer" "Bourns"
			(at 0 0 0)
			(layer "F.Fab")
			(hide yes)
			(effects
				(font
					(size 1 1)
					(thickness 0.15)
				)
			)
		)
		(property "Tolerance" "1%"
			(at 0 0 0)
			(layer "F.Fab")
			(hide yes)
			(effects
				(font
					(size 1 1)
					(thickness 0.15)
				)
			)
		)
		(property "Val" "22R"
			(at 0 0 0)
			(layer "F.Fab")
			(hide yes)
			(effects
				(font
					(size 1 1)
					(thickness 0.15)
				)
			)
		)
		(sheetname "Interfaces")
		(sheetfile "interfaces.kicad_sch")
		(attr smd)
		(fp_rect
			(start -0.93 -0.47)
			(end 0.93 0.47)
			(stroke
				(width 0.05)
				(type solid)
			)
			(fill no)
			(layer "F.CrtYd")
		)
		(fp_rect
			(start -0.5 -0.25)
			(end 0.5 0.25)
			(stroke
				(width 0.15)
				(type solid)
			)
			(fill no)
			(layer "F.Fab")
		)
		(pad "1" smd roundrect
			(at -0.485 0)
			(size 0.59 0.64)
			(layers "F.Cu" "F.Mask" "F.Paste")
			(roundrect_rratio 0.25)
			(net 242 "Net-(U4-ADBUS1)")
			(pintype "passive")
		)
		(pad "2" smd roundrect
			(at 0.485 0)
			(size 0.59 0.64)
			(layers "F.Cu" "F.Mask" "F.Paste")
			(roundrect_rratio 0.25)
			(net 10 "TDI_JTAG")
			(pintype "passive")
		)
	)
	(footprint "antmicro-footprints:R_0402_1005Metric"
		(layer "F.Cu")
		(at 148.036328 113.121157)
		(descr "Resistor SMD 0402")
		(tags "resistor SMD 0402")
		(property "Reference" "R13"
			(at 0.763672 0.428843 0)
			(layer "F.SilkS")
			(effects
				(font
					(size 0.7 0.7)
					(thickness 0.15)
				)
				(justify left bottom)
			)
		)
		(property "Value" "R_22R_0402"
			(at 0 1.4 0)
			(layer "F.Fab")
			(effects
				(font
					(size 0.7 0.7)
					(thickness 0.15)
				)
				(justify left bottom)
			)
		)
		(property "Description" "22R resistor in 0402 package with 1% tolerance"
			(at 0 0 0)
			(layer "F.Fab")
			(hide yes)
			(effects
				(font
					(size 1.27 1.27)
					(thickness 0.15)
				)
			)
		)
		(property "Author" "Antmicro"
			(at 0 0 0)
			(layer "F.Fab")
			(hide yes)
			(effects
				(font
					(size 1 1)
					(thickness 0.15)
				)
			)
		)
		(property "License" "Apache-2.0"
			(at 0 0 0)
			(layer "F.Fab")
			(hide yes)
			(effects
				(font
					(size 1 1)
					(thickness 0.15)
				)
			)
		)
		(property "MPN" "CR0402-FX-22R0GLF"
			(at 0 0 0)
			(layer "F.Fab")
			(hide yes)
			(effects
				(font
					(size 1 1)
					(thickness 0.15)
				)
			)
		)
		(property "Manufacturer" "Bourns"
			(at 0 0 0)
			(layer "F.Fab")
			(hide yes)
			(effects
				(font
					(size 1 1)
					(thickness 0.15)
				)
			)
		)
		(property "Tolerance" "1%"
			(at 0 0 0)
			(layer "F.Fab")
			(hide yes)
			(effects
				(font
					(size 1 1)
					(thickness 0.15)
				)
			)
		)
		(property "Val" "22R"
			(at 0 0 0)
			(layer "F.Fab")
			(hide yes)
			(effects
				(font
					(size 1 1)
					(thickness 0.15)
				)
			)
		)
		(sheetname "Interfaces")
		(sheetfile "interfaces.kicad_sch")
		(attr smd)
		(fp_rect
			(start -0.93 -0.47)
			(end 0.93 0.47)
			(stroke
				(width 0.05)
				(type solid)
			)
			(fill no)
			(layer "F.CrtYd")
		)
		(fp_rect
			(start -0.5 -0.25)
			(end 0.5 0.25)
			(stroke
				(width 0.15)
				(type solid)
			)
			(fill no)
			(layer "F.Fab")
		)
		(pad "1" smd roundrect
			(at -0.485 0)
			(size 0.59 0.64)
			(layers "F.Cu" "F.Mask" "F.Paste")
			(roundrect_rratio 0.25)
			(net 241 "Net-(U4-ADBUS0)")
			(pintype "passive")
		)
		(pad "2" smd roundrect
			(at 0.485 0)
			(size 0.59 0.64)
			(layers "F.Cu" "F.Mask" "F.Paste")
			(roundrect_rratio 0.25)
			(net 8 "TCK_JTAG")
			(pintype "passive")
		)
	)
	(footprint "antmicro-footprints:C_0402_1005Metric"
		(layer "F.Cu")
		(at 135.1 108.099 180)
		(descr "Capacitor SMD 0402")
		(tags "capacitor SMD 0402")
		(property "Reference" "C9"
			(at 0.8 -1.201 180)
			(layer "F.SilkS")
			(effects
				(font
					(size 0.7 0.7)
					(thickness 0.15)
				)
				(justify left bottom)
			)
		)
		(property "Value" "C_100n_6V3_0402"
			(at 0 1.4 180)
			(layer "F.Fab")
			(effects
				(font
					(size 0.7 0.7)
					(thickness 0.15)
				)
				(justify left bottom)
			)
		)
		(property "Description" " "
			(at 0 0 180)
			(layer "F.Fab")
			(hide yes)
			(effects
				(font
					(size 1.27 1.27)
					(thickness 0.15)
				)
			)
		)
		(property "Author" "Antmicro"
			(at 270.2 216.198 0)
			(layer "F.Fab")
			(hide yes)
			(effects
				(font
					(size 1 1)
					(thickness 0.15)
				)
			)
		)
		(property "Dielectric" ""
			(at 270.2 216.198 0)
			(layer "F.Fab")
			(hide yes)
			(effects
				(font
					(size 1 1)
					(thickness 0.15)
				)
			)
		)
		(property "License" "Apache-2.0"
			(at 270.2 216.198 0)
			(layer "F.Fab")
			(hide yes)
			(effects
				(font
					(size 1 1)
					(thickness 0.15)
				)
			)
		)
		(property "MPN" "0402X104K6R3CT"
			(at 270.2 216.198 0)
			(layer "F.Fab")
			(hide yes)
			(effects
				(font
					(size 1 1)
					(thickness 0.15)
				)
			)
		)
		(property "Manufacturer" "Walsin"
			(at 270.2 216.198 0)
			(layer "F.Fab")
			(hide yes)
			(effects
				(font
					(size 1 1)
					(thickness 0.15)
				)
			)
		)
		(property "Val" "100n"
			(at 270.2 216.198 0)
			(layer "F.Fab")
			(hide yes)
			(effects
				(font
					(size 1 1)
					(thickness 0.15)
				)
			)
		)
		(property "Voltage" ""
			(at 270.2 216.198 0)
			(layer "F.Fab")
			(hide yes)
			(effects
				(font
					(size 1 1)
					(thickness 0.15)
				)
			)
		)
		(sheetname "Interfaces")
		(sheetfile "interfaces.kicad_sch")
		(attr smd)
		(fp_rect
			(start -0.94 -0.47)
			(end 0.94 0.47)
			(stroke
				(width 0.05)
				(type solid)
			)
			(fill no)
			(layer "F.CrtYd")
		)
		(fp_rect
			(start -0.499 -0.249)
			(end 0.499 0.249)
			(stroke
				(width 0.15)
				(type solid)
			)
			(fill no)
			(layer "F.Fab")
		)
		(pad "1" smd roundrect
			(at -0.484 0 180)
			(size 0.59 0.64)
			(layers "F.Cu" "F.Mask" "F.Paste")
			(roundrect_rratio 0.25)
			(net 459 "3V3_SYS")
			(pintype "passive")
		)
		(pad "2" smd roundrect
			(at 0.484 0 180)
			(size 0.59 0.64)
			(layers "F.Cu" "F.Mask" "F.Paste")
			(roundrect_rratio 0.25)
			(net 5 "GND")
			(pintype "passive")
		)
	)
	(footprint "antmicro-footprints:C_0402_1005Metric"
		(layer "F.Cu")
		(at 132.661328 115.996157 90)
		(descr "Capacitor SMD 0402")
		(tags "capacitor SMD 0402")
		(property "Reference" "C16"
			(at 0.796157 0.438672 90)
			(layer "F.SilkS")
			(effects
				(font
					(size 0.7 0.7)
					(thickness 0.15)
				)
				(justify left bottom)
			)
		)
		(property "Value" "C_18p_0402"
			(at 0 1.4 90)
			(layer "F.Fab")
			(effects
				(font
					(size 0.7 0.7)
					(thickness 0.15)
				)
				(justify left bottom)
			)
		)
		(property "Description" " "
			(at 0 0 90)
			(layer "F.Fab")
			(hide yes)
			(effects
				(font
					(size 1.27 1.27)
					(thickness 0.15)
				)
			)
		)
		(property "Author" "Antmicro"
			(at 248.657485 -16.665171 0)
			(layer "F.Fab")
			(hide yes)
			(effects
				(font
					(size 1 1)
					(thickness 0.15)
				)
			)
		)
		(property "Dielectric" ""
			(at 248.657485 -16.665171 0)
			(layer "F.Fab")
			(hide yes)
			(effects
				(font
					(size 1 1)
					(thickness 0.15)
				)
			)
		)
		(property "License" "Apache-2.0"
			(at 248.657485 -16.665171 0)
			(layer "F.Fab")
			(hide yes)
			(effects
				(font
					(size 1 1)
					(thickness 0.15)
				)
			)
		)
		(property "MPN" "MC0402N180J500CT"
			(at 248.657485 -16.665171 0)
			(layer "F.Fab")
			(hide yes)
			(effects
				(font
					(size 1 1)
					(thickness 0.15)
				)
			)
		)
		(property "Manufacturer" "Multicomp"
			(at 248.657485 -16.665171 0)
			(layer "F.Fab")
			(hide yes)
			(effects
				(font
					(size 1 1)
					(thickness 0.15)
				)
			)
		)
		(property "Val" "18p"
			(at 248.657485 -16.665171 0)
			(layer "F.Fab")
			(hide yes)
			(effects
				(font
					(size 1 1)
					(thickness 0.15)
				)
			)
		)
		(property "Voltage" ""
			(at 248.657485 -16.665171 0)
			(layer "F.Fab")
			(hide yes)
			(effects
				(font
					(size 1 1)
					(thickness 0.15)
				)
			)
		)
		(sheetname "Interfaces")
		(sheetfile "interfaces.kicad_sch")
		(attr smd)
		(fp_rect
			(start -0.94 -0.47)
			(end 0.94 0.47)
			(stroke
				(width 0.05)
				(type solid)
			)
			(fill no)
			(layer "F.CrtYd")
		)
		(fp_rect
			(start -0.499 -0.249)
			(end 0.499 0.249)
			(stroke
				(width 0.15)
				(type solid)
			)
			(fill no)
			(layer "F.Fab")
		)
		(pad "1" smd roundrect
			(at -0.484 0 90)
			(size 0.59 0.64)
			(layers "F.Cu" "F.Mask" "F.Paste")
			(roundrect_rratio 0.25)
			(net 5 "GND")
			(pintype "passive")
		)
		(pad "2" smd roundrect
			(at 0.484 0 90)
			(size 0.59 0.64)
			(layers "F.Cu" "F.Mask" "F.Paste")
			(roundrect_rratio 0.25)
			(net 3 "Net-(U4-OSCI)")
			(pintype "passive")
		)
	)
	(footprint "antmicro-footprints:C_0402_1005Metric"
		(layer "F.Cu")
		(at 148.661328 108.781157)
		(descr "Capacitor SMD 0402")
		(tags "capacitor SMD 0402")
		(property "Reference" "C19"
			(at 0.764672 0.428843 0)
			(layer "F.SilkS")
			(effects
				(font
					(size 0.7 0.7)
					(thickness 0.15)
				)
				(justify left bottom)
			)
		)
		(property "Value" "C_100n_6V3_0402"
			(at 0 1.4 0)
			(layer "F.Fab")
			(effects
				(font
					(size 0.7 0.7)
					(thickness 0.15)
				)
				(justify left bottom)
			)
		)
		(property "Description" " "
			(at 0 0 0)
			(layer "F.Fab")
			(hide yes)
			(effects
				(font
					(size 1.27 1.27)
					(thickness 0.15)
				)
			)
		)
		(property "Author" "Antmicro"
			(at 0 0 0)
			(layer "F.Fab")
			(hide yes)
			(effects
				(font
					(size 1 1)
					(thickness 0.15)
				)
			)
		)
		(property "Dielectric" ""
			(at 0 0 0)
			(layer "F.Fab")
			(hide yes)
			(effects
				(font
					(size 1 1)
					(thickness 0.15)
				)
			)
		)
		(property "License" "Apache-2.0"
			(at 0 0 0)
			(layer "F.Fab")
			(hide yes)
			(effects
				(font
					(size 1 1)
					(thickness 0.15)
				)
			)
		)
		(property "MPN" "0402X104K6R3CT"
			(at 0 0 0)
			(layer "F.Fab")
			(hide yes)
			(effects
				(font
					(size 1 1)
					(thickness 0.15)
				)
			)
		)
		(property "Manufacturer" "Walsin"
			(at 0 0 0)
			(layer "F.Fab")
			(hide yes)
			(effects
				(font
					(size 1 1)
					(thickness 0.15)
				)
			)
		)
		(property "Val" "100n"
			(at 0 0 0)
			(layer "F.Fab")
			(hide yes)
			(effects
				(font
					(size 1 1)
					(thickness 0.15)
				)
			)
		)
		(property "Voltage" ""
			(at 0 0 0)
			(layer "F.Fab")
			(hide yes)
			(effects
				(font
					(size 1 1)
					(thickness 0.15)
				)
			)
		)
		(sheetname "Interfaces")
		(sheetfile "interfaces.kicad_sch")
		(attr smd)
		(fp_rect
			(start -0.94 -0.47)
			(end 0.94 0.47)
			(stroke
				(width 0.05)
				(type solid)
			)
			(fill no)
			(layer "F.CrtYd")
		)
		(fp_rect
			(start -0.499 -0.249)
			(end 0.499 0.249)
			(stroke
				(width 0.15)
				(type solid)
			)
			(fill no)
			(layer "F.Fab")
		)
		(pad "1" smd roundrect
			(at -0.484 0)
			(size 0.59 0.64)
			(layers "F.Cu" "F.Mask" "F.Paste")
			(roundrect_rratio 0.25)
			(net 459 "3V3_SYS")
			(pintype "passive")
		)
		(pad "2" smd roundrect
			(at 0.484 0)
			(size 0.59 0.64)
			(layers "F.Cu" "F.Mask" "F.Paste")
			(roundrect_rratio 0.25)
			(net 5 "GND")
			(pintype "passive")
		)
	)
	(footprint "antmicro-footprints:C_0402_1005Metric"
		(layer "F.Cu")
		(at 143.165 102.174 -90)
		(descr "Capacitor SMD 0402")
		(tags "capacitor SMD 0402")
		(property "Reference" "C10"
			(at 1.126 0.465 270)
			(layer "F.SilkS")
			(effects
				(font
					(size 0.7 0.7)
					(thickness 0.15)
				)
				(justify left bottom)
			)
		)
		(property "Value" "C_4u7_0402"
			(at 0 1.4 270)
			(layer "F.Fab")
			(effects
				(font
					(size 0.7 0.7)
					(thickness 0.15)
				)
				(justify left bottom)
			)
		)
		(property "Description" " "
			(at 0 0 270)
			(layer "F.Fab")
			(hide yes)
			(effects
				(font
					(size 1.27 1.27)
					(thickness 0.15)
				)
			)
		)
		(property "Author" "Antmicro"
			(at 40.991 245.339 0)
			(layer "F.Fab")
			(hide yes)
			(effects
				(font
					(size 1 1)
					(thickness 0.15)
				)
			)
		)
		(property "Dielectric" ""
			(at 40.991 245.339 0)
			(layer "F.Fab")
			(hide yes)
			(effects
				(font
					(size 1 1)
					(thickness 0.15)
				)
			)
		)
		(property "License" "Apache-2.0"
			(at 40.991 245.339 0)
			(layer "F.Fab")
			(hide yes)
			(effects
				(font
					(size 1 1)
					(thickness 0.15)
				)
			)
		)
		(property "MPN" "GRM155R61A475MEAAD"
			(at 40.991 245.339 0)
			(layer "F.Fab")
			(hide yes)
			(effects
				(font
					(size 1 1)
					(thickness 0.15)
				)
			)
		)
		(property "Manufacturer" "Murata"
			(at 40.991 245.339 0)
			(layer "F.Fab")
			(hide yes)
			(effects
				(font
					(size 1 1)
					(thickness 0.15)
				)
			)
		)
		(property "Val" "4u7"
			(at 40.991 245.339 0)
			(layer "F.Fab")
			(hide yes)
			(effects
				(font
					(size 1 1)
					(thickness 0.15)
				)
			)
		)
		(property "Voltage" ""
			(at 40.991 245.339 0)
			(layer "F.Fab")
			(hide yes)
			(effects
				(font
					(size 1 1)
					(thickness 0.15)
				)
			)
		)
		(sheetname "Interfaces")
		(sheetfile "interfaces.kicad_sch")
		(attr smd)
		(fp_rect
			(start -0.94 -0.47)
			(end 0.94 0.47)
			(stroke
				(width 0.05)
				(type solid)
			)
			(fill no)
			(layer "F.CrtYd")
		)
		(fp_rect
			(start -0.499 -0.249)
			(end 0.499 0.249)
			(stroke
				(width 0.15)
				(type solid)
			)
			(fill no)
			(layer "F.Fab")
		)
		(pad "1" smd roundrect
			(at -0.484 0 270)
			(size 0.59 0.64)
			(layers "F.Cu" "F.Mask" "F.Paste")
			(roundrect_rratio 0.25)
			(net 5 "GND")
			(pintype "passive")
		)
		(pad "2" smd roundrect
			(at 0.484 0 270)
			(size 0.59 0.64)
			(layers "F.Cu" "F.Mask" "F.Paste")
			(roundrect_rratio 0.25)
			(net 2 "/Interfaces/1V8_FT")
			(pintype "passive")
		)
	)
	(footprint "antmicro-footprints:FB_0603_1608Metric"
		(layer "F.Cu")
		(at 138.786328 117.496157 90)
		(property "Reference" "FB2"
			(at -1.103843 1.513672 90)
			(layer "F.SilkS")
			(effects
				(font
					(size 0.7 0.7)
					(thickness 0.15)
				)
				(justify left bottom)
			)
		)
		(property "Value" "FB_600Z_0.5A_0603"
			(at 0 1.5 90)
			(layer "F.Fab")
			(effects
				(font
					(size 0.7 0.7)
					(thickness 0.15)
				)
				(justify left bottom)
			)
		)
		(property "Description" "Ferrite Beads WE-TMSB Suppression 240Ohm 200mA "
			(at 0 0 90)
			(layer "F.Fab")
			(hide yes)
			(effects
				(font
					(size 1.27 1.27)
					(thickness 0.15)
				)
			)
		)
		(property "Author" "Antmicro"
			(at 256.282485 -21.290171 0)
			(layer "F.Fab")
			(hide yes)
			(effects
				(font
					(size 1 1)
					(thickness 0.15)
				)
			)
		)
		(property "License" "Apache-2.0"
			(at 256.282485 -21.290171 0)
			(layer "F.Fab")
			(hide yes)
			(effects
				(font
					(size 1 1)
					(thickness 0.15)
				)
			)
		)
		(property "MPN" "BLM18AG601SN1D"
			(at 256.282485 -21.290171 0)
			(layer "F.Fab")
			(hide yes)
			(effects
				(font
					(size 1 1)
					(thickness 0.15)
				)
			)
		)
		(property "Manufacturer" "Murata"
			(at 256.282485 -21.290171 0)
			(layer "F.Fab")
			(hide yes)
			(effects
				(font
					(size 1 1)
					(thickness 0.15)
				)
			)
		)
		(sheetname "Interfaces")
		(sheetfile "interfaces.kicad_sch")
		(attr smd)
		(fp_line
			(start -0.196 -0.408)
			(end 0.193 -0.408)
			(stroke
				(width 0.15)
				(type solid)
			)
			(layer "F.SilkS")
		)
		(fp_line
			(start -0.196 0.406)
			(end 0.193 0.406)
			(stroke
				(width 0.15)
				(type solid)
			)
			(layer "F.SilkS")
		)
		(fp_rect
			(start -1.3 -0.6)
			(end 1.3 0.6)
			(stroke
				(width 0.05)
				(type solid)
			)
			(fill no)
			(layer "F.CrtYd")
		)
		(fp_line
			(start 0.8 -0.408)
			(end -0.803 -0.408)
			(stroke
				(width 0.15)
				(type solid)
			)
			(layer "F.Fab")
		)
		(fp_line
			(start 0.8 -0.408)
			(end 0.8 0.406)
			(stroke
				(width 0.15)
				(type solid)
			)
			(layer "F.Fab")
		)
		(fp_line
			(start 0.8 0.406)
			(end -0.803 0.406)
			(stroke
				(width 0.15)
				(type solid)
			)
			(layer "F.Fab")
		)
		(fp_line
			(start -0.803 0.406)
			(end -0.803 -0.408)
			(stroke
				(width 0.15)
				(type solid)
			)
			(layer "F.Fab")
		)
		(pad "1" smd roundrect
			(at -0.891 0 90)
			(size 0.762 1.09)
			(layers "F.Cu" "F.Mask" "F.Paste")
			(roundrect_rratio 0.15)
			(net 459 "3V3_SYS")
			(pintype "passive")
		)
		(pad "2" smd roundrect
			(at 0.888 0 90)
			(size 0.762 1.09)
			(layers "F.Cu" "F.Mask" "F.Paste")
			(roundrect_rratio 0.15)
			(net 653 "/Interfaces/VPHY")
			(pintype "passive")
		)
	)
	(footprint "antmicro-footprints:R_0402_1005Metric"
		(layer "F.Cu")
		(at 139.776328 114.626157 -90)
		(descr "Resistor SMD 0402")
		(tags "resistor SMD 0402")
		(property "Reference" "R7"
			(at 0.773843 -1.223672 270)
			(layer "F.SilkS")
			(effects
				(font
					(size 0.7 0.7)
					(thickness 0.15)
				)
				(justify left bottom)
			)
		)
		(property "Value" "R_12k_0402"
			(at 0 1.4 270)
			(layer "F.Fab")
			(effects
				(font
					(size 0.7 0.7)
					(thickness 0.15)
				)
				(justify left bottom)
			)
		)
		(property "Description" "12k resistor in 0402 package with 1% tolerance"
			(at 0 0 270)
			(layer "F.Fab")
			(hide yes)
			(effects
				(font
					(size 1.27 1.27)
					(thickness 0.15)
				)
			)
		)
		(property "Author" "Antmicro"
			(at 25.150171 254.402485 0)
			(layer "F.Fab")
			(hide yes)
			(effects
				(font
					(size 1 1)
					(thickness 0.15)
				)
			)
		)
		(property "License" "Apache-2.0"
			(at 25.150171 254.402485 0)
			(layer "F.Fab")
			(hide yes)
			(effects
				(font
					(size 1 1)
					(thickness 0.15)
				)
			)
		)
		(property "MPN" "CR0402-FX-1202GLF"
			(at 25.150171 254.402485 0)
			(layer "F.Fab")
			(hide yes)
			(effects
				(font
					(size 1 1)
					(thickness 0.15)
				)
			)
		)
		(property "Manufacturer" "Bourns"
			(at 25.150171 254.402485 0)
			(layer "F.Fab")
			(hide yes)
			(effects
				(font
					(size 1 1)
					(thickness 0.15)
				)
			)
		)
		(property "Tolerance" "1%"
			(at 25.150171 254.402485 0)
			(layer "F.Fab")
			(hide yes)
			(effects
				(font
					(size 1 1)
					(thickness 0.15)
				)
			)
		)
		(property "Val" "12k"
			(at 25.150171 254.402485 0)
			(layer "F.Fab")
			(hide yes)
			(effects
				(font
					(size 1 1)
					(thickness 0.15)
				)
			)
		)
		(sheetname "Interfaces")
		(sheetfile "interfaces.kicad_sch")
		(attr smd)
		(fp_rect
			(start -0.93 -0.47)
			(end 0.93 0.47)
			(stroke
				(width 0.05)
				(type solid)
			)
			(fill no)
			(layer "F.CrtYd")
		)
		(fp_rect
			(start -0.5 -0.25)
			(end 0.5 0.25)
			(stroke
				(width 0.15)
				(type solid)
			)
			(fill no)
			(layer "F.Fab")
		)
		(pad "1" smd roundrect
			(at -0.485 0 270)
			(size 0.59 0.64)
			(layers "F.Cu" "F.Mask" "F.Paste")
			(roundrect_rratio 0.25)
			(net 239 "Net-(U4-REF)")
			(pintype "passive")
		)
		(pad "2" smd roundrect
			(at 0.485 0 270)
			(size 0.59 0.64)
			(layers "F.Cu" "F.Mask" "F.Paste")
			(roundrect_rratio 0.25)
			(net 5 "GND")
			(pintype "passive")
		)
	)
	(footprint "antmicro-footprints:C_0402_1005Metric"
		(layer "F.Cu")
		(at 142.066328 115.236157 180)
		(descr "Capacitor SMD 0402")
		(tags "capacitor SMD 0402")
		(property "Reference" "C8"
			(at -0.733672 -0.363843 180)
			(layer "F.SilkS")
			(effects
				(font
					(size 0.7 0.7)
					(thickness 0.15)
				)
				(justify left bottom)
			)
		)
		(property "Value" "C_100n_6V3_0402"
			(at 0 1.4 180)
			(layer "F.Fab")
			(effects
				(font
					(size 0.7 0.7)
					(thickness 0.15)
				)
				(justify left bottom)
			)
		)
		(property "Description" " "
			(at 0 0 180)
			(layer "F.Fab")
			(hide yes)
			(effects
				(font
					(size 1.27 1.27)
					(thickness 0.15)
				)
			)
		)
		(property "Author" "Antmicro"
			(at 284.132656 230.472314 0)
			(layer "F.Fab")
			(hide yes)
			(effects
				(font
					(size 1 1)
					(thickness 0.15)
				)
			)
		)
		(property "Dielectric" ""
			(at 284.132656 230.472314 0)
			(layer "F.Fab")
			(hide yes)
			(effects
				(font
					(size 1 1)
					(thickness 0.15)
				)
			)
		)
		(property "License" "Apache-2.0"
			(at 284.132656 230.472314 0)
			(layer "F.Fab")
			(hide yes)
			(effects
				(font
					(size 1 1)
					(thickness 0.15)
				)
			)
		)
		(property "MPN" "0402X104K6R3CT"
			(at 284.132656 230.472314 0)
			(layer "F.Fab")
			(hide yes)
			(effects
				(font
					(size 1 1)
					(thickness 0.15)
				)
			)
		)
		(property "Manufacturer" "Walsin"
			(at 284.132656 230.472314 0)
			(layer "F.Fab")
			(hide yes)
			(effects
				(font
					(size 1 1)
					(thickness 0.15)
				)
			)
		)
		(property "Val" "100n"
			(at 284.132656 230.472314 0)
			(layer "F.Fab")
			(hide yes)
			(effects
				(font
					(size 1 1)
					(thickness 0.15)
				)
			)
		)
		(property "Voltage" ""
			(at 284.132656 230.472314 0)
			(layer "F.Fab")
			(hide yes)
			(effects
				(font
					(size 1 1)
					(thickness 0.15)
				)
			)
		)
		(sheetname "Interfaces")
		(sheetfile "interfaces.kicad_sch")
		(attr smd)
		(fp_rect
			(start -0.94 -0.47)
			(end 0.94 0.47)
			(stroke
				(width 0.05)
				(type solid)
			)
			(fill no)
			(layer "F.CrtYd")
		)
		(fp_rect
			(start -0.499 -0.249)
			(end 0.499 0.249)
			(stroke
				(width 0.15)
				(type solid)
			)
			(fill no)
			(layer "F.Fab")
		)
		(pad "1" smd roundrect
			(at -0.484 0 180)
			(size 0.59 0.64)
			(layers "F.Cu" "F.Mask" "F.Paste")
			(roundrect_rratio 0.25)
			(net 5 "GND")
			(pintype "passive")
		)
		(pad "2" smd roundrect
			(at 0.484 0 180)
			(size 0.59 0.64)
			(layers "F.Cu" "F.Mask" "F.Paste")
			(roundrect_rratio 0.25)
			(net 652 "/Interfaces/VPLL")
			(pintype "passive")
		)
	)
	(footprint "antmicro-footprints:C_0402_1005Metric"
		(layer "F.Cu")
		(at 142.066328 114.156157 180)
		(descr "Capacitor SMD 0402")
		(tags "capacitor SMD 0402")
		(property "Reference" "C14"
			(at 1.066328 0.456157 180)
			(layer "F.SilkS")
			(effects
				(font
					(size 0.7 0.7)
					(thickness 0.15)
				)
				(justify left bottom)
			)
		)
		(property "Value" "C_4u7_0402"
			(at 0 1.4 180)
			(layer "F.Fab")
			(effects
				(font
					(size 0.7 0.7)
					(thickness 0.15)
				)
				(justify left bottom)
			)
		)
		(property "Description" " "
			(at 0 0 180)
			(layer "F.Fab")
			(hide yes)
			(effects
				(font
					(size 1.27 1.27)
					(thickness 0.15)
				)
			)
		)
		(property "Author" "Antmicro"
			(at 284.132656 228.312314 0)
			(layer "F.Fab")
			(hide yes)
			(effects
				(font
					(size 1 1)
					(thickness 0.15)
				)
			)
		)
		(property "Dielectric" ""
			(at 284.132656 228.312314 0)
			(layer "F.Fab")
			(hide yes)
			(effects
				(font
					(size 1 1)
					(thickness 0.15)
				)
			)
		)
		(property "License" "Apache-2.0"
			(at 284.132656 228.312314 0)
			(layer "F.Fab")
			(hide yes)
			(effects
				(font
					(size 1 1)
					(thickness 0.15)
				)
			)
		)
		(property "MPN" "GRM155R61A475MEAAD"
			(at 284.132656 228.312314 0)
			(layer "F.Fab")
			(hide yes)
			(effects
				(font
					(size 1 1)
					(thickness 0.15)
				)
			)
		)
		(property "Manufacturer" "Murata"
			(at 284.132656 228.312314 0)
			(layer "F.Fab")
			(hide yes)
			(effects
				(font
					(size 1 1)
					(thickness 0.15)
				)
			)
		)
		(property "Val" "4u7"
			(at 284.132656 228.312314 0)
			(layer "F.Fab")
			(hide yes)
			(effects
				(font
					(size 1 1)
					(thickness 0.15)
				)
			)
		)
		(property "Voltage" ""
			(at 284.132656 228.312314 0)
			(layer "F.Fab")
			(hide yes)
			(effects
				(font
					(size 1 1)
					(thickness 0.15)
				)
			)
		)
		(sheetname "Interfaces")
		(sheetfile "interfaces.kicad_sch")
		(attr smd)
		(fp_rect
			(start -0.94 -0.47)
			(end 0.94 0.47)
			(stroke
				(width 0.05)
				(type solid)
			)
			(fill no)
			(layer "F.CrtYd")
		)
		(fp_rect
			(start -0.499 -0.249)
			(end 0.499 0.249)
			(stroke
				(width 0.15)
				(type solid)
			)
			(fill no)
			(layer "F.Fab")
		)
		(pad "1" smd roundrect
			(at -0.484 0 180)
			(size 0.59 0.64)
			(layers "F.Cu" "F.Mask" "F.Paste")
			(roundrect_rratio 0.25)
			(net 5 "GND")
			(pintype "passive")
		)
		(pad "2" smd roundrect
			(at 0.484 0 180)
			(size 0.59 0.64)
			(layers "F.Cu" "F.Mask" "F.Paste")
			(roundrect_rratio 0.25)
			(net 652 "/Interfaces/VPLL")
			(pintype "passive")
		)
	)
	(footprint "antmicro-footprints:R_0402_1005Metric"
		(layer "F.Cu")
		(at 176.169 130.082 -90)
		(descr "Resistor SMD 0402")
		(tags "resistor SMD 0402")
		(property "Reference" "R34"
			(at -0.782 -0.431 270)
			(layer "F.SilkS")
			(effects
				(font
					(size 0.7 0.7)
					(thickness 0.15)
				)
				(justify left bottom)
			)
		)
		(property "Value" "R_20k_0402"
			(at 0 1.4 270)
			(layer "F.Fab")
			(effects
				(font
					(size 0.7 0.7)
					(thickness 0.15)
				)
				(justify left bottom)
			)
		)
		(property "Description" "20k resistor in 0402 package with 1% tolerance"
			(at 0 0 270)
			(layer "F.Fab")
			(hide yes)
			(effects
				(font
					(size 1.27 1.27)
					(thickness 0.15)
				)
			)
		)
		(property "Author" "Antmicro"
			(at 46.087 306.251 0)
			(layer "F.Fab")
			(hide yes)
			(effects
				(font
					(size 1 1)
					(thickness 0.15)
				)
			)
		)
		(property "License" "Apache-2.0"
			(at 46.087 306.251 0)
			(layer "F.Fab")
			(hide yes)
			(effects
				(font
					(size 1 1)
					(thickness 0.15)
				)
			)
		)
		(property "MPN" "CR0402-FX-2002GLF"
			(at 46.087 306.251 0)
			(layer "F.Fab")
			(hide yes)
			(effects
				(font
					(size 1 1)
					(thickness 0.15)
				)
			)
		)
		(property "Manufacturer" "Bourns"
			(at 46.087 306.251 0)
			(layer "F.Fab")
			(hide yes)
			(effects
				(font
					(size 1 1)
					(thickness 0.15)
				)
			)
		)
		(property "Tolerance" "1%"
			(at 46.087 306.251 0)
			(layer "F.Fab")
			(hide yes)
			(effects
				(font
					(size 1 1)
					(thickness 0.15)
				)
			)
		)
		(property "Val" "20k"
			(at 46.087 306.251 0)
			(layer "F.Fab")
			(hide yes)
			(effects
				(font
					(size 1 1)
					(thickness 0.15)
				)
			)
		)
		(sheetname "Interfaces")
		(sheetfile "interfaces.kicad_sch")
		(attr smd)
		(fp_rect
			(start -0.93 -0.47)
			(end 0.93 0.47)
			(stroke
				(width 0.05)
				(type solid)
			)
			(fill no)
			(layer "F.CrtYd")
		)
		(fp_rect
			(start -0.5 -0.25)
			(end 0.5 0.25)
			(stroke
				(width 0.15)
				(type solid)
			)
			(fill no)
			(layer "F.Fab")
		)
		(pad "1" smd roundrect
			(at -0.485 0 270)
			(size 0.59 0.64)
			(layers "F.Cu" "F.Mask" "F.Paste")
			(roundrect_rratio 0.25)
			(net 459 "3V3_SYS")
			(pintype "passive")
		)
		(pad "2" smd roundrect
			(at 0.485 0 270)
			(size 0.59 0.64)
			(layers "F.Cu" "F.Mask" "F.Paste")
			(roundrect_rratio 0.25)
			(net 194 "SD_CLK")
			(pintype "passive")
		)
	)
	(footprint "antmicro-footprints:R_0402_1005Metric"
		(layer "F.Cu")
		(at 173.756 130.082 -90)
		(descr "Resistor SMD 0402")
		(tags "resistor SMD 0402")
		(property "Reference" "R35"
			(at -0.782 -0.403 270)
			(layer "F.SilkS")
			(effects
				(font
					(size 0.7 0.7)
					(thickness 0.15)
				)
				(justify left bottom)
			)
		)
		(property "Value" "R_20k_0402"
			(at 0 1.4 270)
			(layer "F.Fab")
			(effects
				(font
					(size 0.7 0.7)
					(thickness 0.15)
				)
				(justify left bottom)
			)
		)
		(property "Description" "20k resistor in 0402 package with 1% tolerance"
			(at 0 0 270)
			(layer "F.Fab")
			(hide yes)
			(effects
				(font
					(size 1.27 1.27)
					(thickness 0.15)
				)
			)
		)
		(property "Author" "Antmicro"
			(at 43.674 303.838 0)
			(layer "F.Fab")
			(hide yes)
			(effects
				(font
					(size 1 1)
					(thickness 0.15)
				)
			)
		)
		(property "License" "Apache-2.0"
			(at 43.674 303.838 0)
			(layer "F.Fab")
			(hide yes)
			(effects
				(font
					(size 1 1)
					(thickness 0.15)
				)
			)
		)
		(property "MPN" "CR0402-FX-2002GLF"
			(at 43.674 303.838 0)
			(layer "F.Fab")
			(hide yes)
			(effects
				(font
					(size 1 1)
					(thickness 0.15)
				)
			)
		)
		(property "Manufacturer" "Bourns"
			(at 43.674 303.838 0)
			(layer "F.Fab")
			(hide yes)
			(effects
				(font
					(size 1 1)
					(thickness 0.15)
				)
			)
		)
		(property "Tolerance" "1%"
			(at 43.674 303.838 0)
			(layer "F.Fab")
			(hide yes)
			(effects
				(font
					(size 1 1)
					(thickness 0.15)
				)
			)
		)
		(property "Val" "20k"
			(at 43.674 303.838 0)
			(layer "F.Fab")
			(hide yes)
			(effects
				(font
					(size 1 1)
					(thickness 0.15)
				)
			)
		)
		(sheetname "Interfaces")
		(sheetfile "interfaces.kicad_sch")
		(attr smd)
		(fp_rect
			(start -0.93 -0.47)
			(end 0.93 0.47)
			(stroke
				(width 0.05)
				(type solid)
			)
			(fill no)
			(layer "F.CrtYd")
		)
		(fp_rect
			(start -0.5 -0.25)
			(end 0.5 0.25)
			(stroke
				(width 0.15)
				(type solid)
			)
			(fill no)
			(layer "F.Fab")
		)
		(pad "1" smd roundrect
			(at -0.485 0 270)
			(size 0.59 0.64)
			(layers "F.Cu" "F.Mask" "F.Paste")
			(roundrect_rratio 0.25)
			(net 459 "3V3_SYS")
			(pintype "passive")
		)
		(pad "2" smd roundrect
			(at 0.485 0 270)
			(size 0.59 0.64)
			(layers "F.Cu" "F.Mask" "F.Paste")
			(roundrect_rratio 0.25)
			(net 195 "SD_CMD")
			(pintype "passive")
		)
	)
	(footprint "antmicro-footprints:R_0402_1005Metric"
		(layer "F.Cu")
		(at 179.344 130.082 -90)
		(descr "Resistor SMD 0402")
		(tags "resistor SMD 0402")
		(property "Reference" "R32"
			(at -0.782 -0.431 270)
			(layer "F.SilkS")
			(effects
				(font
					(size 0.7 0.7)
					(thickness 0.15)
				)
				(justify left bottom)
			)
		)
		(property "Value" "R_20k_0402"
			(at 0 1.4 270)
			(layer "F.Fab")
			(effects
				(font
					(size 0.7 0.7)
					(thickness 0.15)
				)
				(justify left bottom)
			)
		)
		(property "Description" "20k resistor in 0402 package with 1% tolerance"
			(at 0 0 270)
			(layer "F.Fab")
			(hide yes)
			(effects
				(font
					(size 1.27 1.27)
					(thickness 0.15)
				)
			)
		)
		(property "Author" "Antmicro"
			(at 49.262 309.426 0)
			(layer "F.Fab")
			(hide yes)
			(effects
				(font
					(size 1 1)
					(thickness 0.15)
				)
			)
		)
		(property "License" "Apache-2.0"
			(at 49.262 309.426 0)
			(layer "F.Fab")
			(hide yes)
			(effects
				(font
					(size 1 1)
					(thickness 0.15)
				)
			)
		)
		(property "MPN" "CR0402-FX-2002GLF"
			(at 49.262 309.426 0)
			(layer "F.Fab")
			(hide yes)
			(effects
				(font
					(size 1 1)
					(thickness 0.15)
				)
			)
		)
		(property "Manufacturer" "Bourns"
			(at 49.262 309.426 0)
			(layer "F.Fab")
			(hide yes)
			(effects
				(font
					(size 1 1)
					(thickness 0.15)
				)
			)
		)
		(property "Tolerance" "1%"
			(at 49.262 309.426 0)
			(layer "F.Fab")
			(hide yes)
			(effects
				(font
					(size 1 1)
					(thickness 0.15)
				)
			)
		)
		(property "Val" "20k"
			(at 49.262 309.426 0)
			(layer "F.Fab")
			(hide yes)
			(effects
				(font
					(size 1 1)
					(thickness 0.15)
				)
			)
		)
		(sheetname "Interfaces")
		(sheetfile "interfaces.kicad_sch")
		(attr smd)
		(fp_rect
			(start -0.93 -0.47)
			(end 0.93 0.47)
			(stroke
				(width 0.05)
				(type solid)
			)
			(fill no)
			(layer "F.CrtYd")
		)
		(fp_rect
			(start -0.5 -0.25)
			(end 0.5 0.25)
			(stroke
				(width 0.15)
				(type solid)
			)
			(fill no)
			(layer "F.Fab")
		)
		(pad "1" smd roundrect
			(at -0.485 0 270)
			(size 0.59 0.64)
			(layers "F.Cu" "F.Mask" "F.Paste")
			(roundrect_rratio 0.25)
			(net 459 "3V3_SYS")
			(pintype "passive")
		)
		(pad "2" smd roundrect
			(at 0.485 0 270)
			(size 0.59 0.64)
			(layers "F.Cu" "F.Mask" "F.Paste")
			(roundrect_rratio 0.25)
			(net 192 "SD_DAT1")
			(pintype "passive")
		)
	)
	(footprint "antmicro-footprints:FB_0603_1608Metric"
		(layer "F.Cu")
		(at 142.469328 116.527157 180)
		(property "Reference" "FB1"
			(at 0.969328 -1.472843 180)
			(layer "F.SilkS")
			(effects
				(font
					(size 0.7 0.7)
					(thickness 0.15)
				)
				(justify left bottom)
			)
		)
		(property "Value" "FB_600Z_0.5A_0603"
			(at 0 1.5 180)
			(layer "F.Fab")
			(effects
				(font
					(size 0.7 0.7)
					(thickness 0.15)
				)
				(justify left bottom)
			)
		)
		(property "Description" "Ferrite Beads WE-TMSB Suppression 240Ohm 200mA "
			(at 0 0 180)
			(layer "F.Fab")
			(hide yes)
			(effects
				(font
					(size 1.27 1.27)
					(thickness 0.15)
				)
			)
		)
		(property "Author" "Antmicro"
			(at 284.938656 233.054314 0)
			(layer "F.Fab")
			(hide yes)
			(effects
				(font
					(size 1 1)
					(thickness 0.15)
				)
			)
		)
		(property "License" "Apache-2.0"
			(at 284.938656 233.054314 0)
			(layer "F.Fab")
			(hide yes)
			(effects
				(font
					(size 1 1)
					(thickness 0.15)
				)
			)
		)
		(property "MPN" "BLM18AG601SN1D"
			(at 284.938656 233.054314 0)
			(layer "F.Fab")
			(hide yes)
			(effects
				(font
					(size 1 1)
					(thickness 0.15)
				)
			)
		)
		(property "Manufacturer" "Murata"
			(at 284.938656 233.054314 0)
			(layer "F.Fab")
			(hide yes)
			(effects
				(font
					(size 1 1)
					(thickness 0.15)
				)
			)
		)
		(sheetname "Interfaces")
		(sheetfile "interfaces.kicad_sch")
		(attr smd)
		(fp_line
			(start -0.196 0.406)
			(end 0.193 0.406)
			(stroke
				(width 0.15)
				(type solid)
			)
			(layer "F.SilkS")
		)
		(fp_line
			(start -0.196 -0.408)
			(end 0.193 -0.408)
			(stroke
				(width 0.15)
				(type solid)
			)
			(layer "F.SilkS")
		)
		(fp_rect
			(start -1.3 -0.6)
			(end 1.3 0.6)
			(stroke
				(width 0.05)
				(type solid)
			)
			(fill no)
			(layer "F.CrtYd")
		)
		(fp_line
			(start 0.8 0.406)
			(end -0.803 0.406)
			(stroke
				(width 0.15)
				(type solid)
			)
			(layer "F.Fab")
		)
		(fp_line
			(start 0.8 -0.408)
			(end 0.8 0.406)
			(stroke
				(width 0.15)
				(type solid)
			)
			(layer "F.Fab")
		)
		(fp_line
			(start 0.8 -0.408)
			(end -0.803 -0.408)
			(stroke
				(width 0.15)
				(type solid)
			)
			(layer "F.Fab")
		)
		(fp_line
			(start -0.803 0.406)
			(end -0.803 -0.408)
			(stroke
				(width 0.15)
				(type solid)
			)
			(layer "F.Fab")
		)
		(pad "1" smd roundrect
			(at -0.891 0 180)
			(size 0.762 1.09)
			(layers "F.Cu" "F.Mask" "F.Paste")
			(roundrect_rratio 0.15)
			(net 459 "3V3_SYS")
			(pintype "passive")
		)
		(pad "2" smd roundrect
			(at 0.888 0 180)
			(size 0.762 1.09)
			(layers "F.Cu" "F.Mask" "F.Paste")
			(roundrect_rratio 0.15)
			(net 652 "/Interfaces/VPLL")
			(pintype "passive")
		)
	)
	(footprint "antmicro-footprints:C_0402_1005Metric"
		(layer "F.Cu")
		(at 137.536328 117.371157 -90)
		(descr "Capacitor SMD 0402")
		(tags "capacitor SMD 0402")
		(property "Reference" "C20"
			(at 2.928843 -0.363672 270)
			(layer "F.SilkS")
			(effects
				(font
					(size 0.7 0.7)
					(thickness 0.15)
				)
				(justify left bottom)
			)
		)
		(property "Value" "C_18p_0402"
			(at 0 1.4 270)
			(layer "F.Fab")
			(effects
				(font
					(size 0.7 0.7)
					(thickness 0.15)
				)
				(justify left bottom)
			)
		)
		(property "Description" " "
			(at 0 0 270)
			(layer "F.Fab")
			(hide yes)
			(effects
				(font
					(size 1.27 1.27)
					(thickness 0.15)
				)
			)
		)
		(property "Author" "Antmicro"
			(at 20.165171 254.907485 0)
			(layer "F.Fab")
			(hide yes)
			(effects
				(font
					(size 1 1)
					(thickness 0.15)
				)
			)
		)
		(property "Dielectric" ""
			(at 20.165171 254.907485 0)
			(layer "F.Fab")
			(hide yes)
			(effects
				(font
					(size 1 1)
					(thickness 0.15)
				)
			)
		)
		(property "License" "Apache-2.0"
			(at 20.165171 254.907485 0)
			(layer "F.Fab")
			(hide yes)
			(effects
				(font
					(size 1 1)
					(thickness 0.15)
				)
			)
		)
		(property "MPN" "MC0402N180J500CT"
			(at 20.165171 254.907485 0)
			(layer "F.Fab")
			(hide yes)
			(effects
				(font
					(size 1 1)
					(thickness 0.15)
				)
			)
		)
		(property "Manufacturer" "Multicomp"
			(at 20.165171 254.907485 0)
			(layer "F.Fab")
			(hide yes)
			(effects
				(font
					(size 1 1)
					(thickness 0.15)
				)
			)
		)
		(property "Val" "18p"
			(at 20.165171 254.907485 0)
			(layer "F.Fab")
			(hide yes)
			(effects
				(font
					(size 1 1)
					(thickness 0.15)
				)
			)
		)
		(property "Voltage" ""
			(at 20.165171 254.907485 0)
			(layer "F.Fab")
			(hide yes)
			(effects
				(font
					(size 1 1)
					(thickness 0.15)
				)
			)
		)
		(sheetname "Interfaces")
		(sheetfile "interfaces.kicad_sch")
		(attr smd)
		(fp_rect
			(start -0.94 -0.47)
			(end 0.94 0.47)
			(stroke
				(width 0.05)
				(type solid)
			)
			(fill no)
			(layer "F.CrtYd")
		)
		(fp_rect
			(start -0.499 -0.249)
			(end 0.499 0.249)
			(stroke
				(width 0.15)
				(type solid)
			)
			(fill no)
			(layer "F.Fab")
		)
		(pad "1" smd roundrect
			(at -0.484 0 270)
			(size 0.59 0.64)
			(layers "F.Cu" "F.Mask" "F.Paste")
			(roundrect_rratio 0.25)
			(net 5 "GND")
			(pintype "passive")
		)
		(pad "2" smd roundrect
			(at 0.484 0 270)
			(size 0.59 0.64)
			(layers "F.Cu" "F.Mask" "F.Paste")
			(roundrect_rratio 0.25)
			(net 4 "Net-(U4-OSCO)")
			(pintype "passive")
		)
	)
	(footprint "antmicro-footprints:R_0402_1005Metric"
		(layer "F.Cu")
		(at 116.9142 118.975 180)
		(descr "Resistor SMD 0402")
		(tags "resistor SMD 0402")
		(property "Reference" "R104"
			(at 3.6142 -0.525 180)
			(layer "F.SilkS")
			(effects
				(font
					(size 0.7 0.7)
					(thickness 0.15)
				)
				(justify left bottom)
			)
		)
		(property "Value" "R_53k6_0402"
			(at 0 1.4 180)
			(layer "F.Fab")
			(effects
				(font
					(size 0.7 0.7)
					(thickness 0.15)
				)
				(justify left bottom)
			)
		)
		(property "Description" "53k6 resistor in 0402 package with 1% tolerance"
			(at 0 0 180)
			(layer "F.Fab")
			(hide yes)
			(effects
				(font
					(size 1.27 1.27)
					(thickness 0.15)
				)
			)
		)
		(property "Author" "Antmicro"
			(at 233.8284 237.95 0)
			(layer "F.Fab")
			(hide yes)
			(effects
				(font
					(size 1 1)
					(thickness 0.15)
				)
			)
		)
		(property "License" "Apache-2.0"
			(at 233.8284 237.95 0)
			(layer "F.Fab")
			(hide yes)
			(effects
				(font
					(size 1 1)
					(thickness 0.15)
				)
			)
		)
		(property "MPN" "CR0402-FX-5362GLF"
			(at 233.8284 237.95 0)
			(layer "F.Fab")
			(hide yes)
			(effects
				(font
					(size 1 1)
					(thickness 0.15)
				)
			)
		)
		(property "Manufacturer" "Bourns"
			(at 233.8284 237.95 0)
			(layer "F.Fab")
			(hide yes)
			(effects
				(font
					(size 1 1)
					(thickness 0.15)
				)
			)
		)
		(property "Tolerance" "1%"
			(at 233.8284 237.95 0)
			(layer "F.Fab")
			(hide yes)
			(effects
				(font
					(size 1 1)
					(thickness 0.15)
				)
			)
		)
		(property "Val" "53k6"
			(at 233.8284 237.95 0)
			(layer "F.Fab")
			(hide yes)
			(effects
				(font
					(size 1 1)
					(thickness 0.15)
				)
			)
		)
		(sheetname "Supply")
		(sheetfile "supply.kicad_sch")
		(attr smd)
		(fp_rect
			(start -0.93 -0.47)
			(end 0.93 0.47)
			(stroke
				(width 0.05)
				(type solid)
			)
			(fill no)
			(layer "F.CrtYd")
		)
		(fp_rect
			(start -0.5 -0.25)
			(end 0.5 0.25)
			(stroke
				(width 0.15)
				(type solid)
			)
			(fill no)
			(layer "F.Fab")
		)
		(pad "1" smd roundrect
			(at -0.485 0 180)
			(size 0.59 0.64)
			(layers "F.Cu" "F.Mask" "F.Paste")
			(roundrect_rratio 0.25)
			(net 244 "Net-(R103-Pad2)")
			(pintype "passive")
		)
		(pad "2" smd roundrect
			(at 0.485 0 180)
			(size 0.59 0.64)
			(layers "F.Cu" "F.Mask" "F.Paste")
			(roundrect_rratio 0.25)
			(net 660 "/Supply/5V0_FB")
			(pintype "passive")
		)
	)
	(footprint "antmicro-footprints:LED_0603_1608Metric_G"
		(layer "F.Cu")
		(at 205.286328 86.620008 180)
		(descr "LED SMD 0603 Green")
		(tags "LED SMD 0603 Green")
		(property "Reference" "D9"
			(at 0.786328 -1.379992 180)
			(layer "F.SilkS")
			(effects
				(font
					(size 0.7 0.7)
					(thickness 0.15)
				)
				(justify left bottom)
			)
		)
		(property "Value" "LED_G_0603_KP-1608CGCK"
			(at 0 1.6 180)
			(layer "F.Fab")
			(effects
				(font
					(size 0.7 0.7)
					(thickness 0.15)
				)
				(justify left bottom)
			)
		)
		(property "Author" "Antmicro"
			(at 410.572656 173.240016 0)
			(layer "F.Fab")
			(hide yes)
			(effects
				(font
					(size 1 1)
					(thickness 0.15)
				)
			)
		)
		(property "License" "Apache-2.0"
			(at 410.572656 173.240016 0)
			(layer "F.Fab")
			(hide yes)
			(effects
				(font
					(size 1 1)
					(thickness 0.15)
				)
			)
		)
		(property "MPN" "KP-1608CGCK"
			(at 410.572656 173.240016 0)
			(layer "F.Fab")
			(hide yes)
			(effects
				(font
					(size 1 1)
					(thickness 0.15)
				)
			)
		)
		(property "Manufacturer" "Kingbright"
			(at 410.572656 173.240016 0)
			(layer "F.Fab")
			(hide yes)
			(effects
				(font
					(size 1 1)
					(thickness 0.15)
				)
			)
		)
		(sheetname "Config SPI flash")
		(sheetfile "config-spi.kicad_sch")
		(attr smd)
		(fp_line
			(start 1.25 0.32)
			(end 1.25 -0.32)
			(stroke
				(width 0.15)
				(type solid)
			)
			(layer "F.SilkS")
		)
		(fp_line
			(start 0.093672 -8e-06)
			(end 0.293672 -8e-06)
			(stroke
				(width 0.1)
				(type solid)
			)
			(layer "F.SilkS")
		)
		(fp_line
			(start 0.093672 -8e-06)
			(end -0.106328 0.199992)
			(stroke
				(width 0.1)
				(type solid)
			)
			(layer "F.SilkS")
		)
		(fp_line
			(start 0.093672 -0.200008)
			(end 0.093672 0.199992)
			(stroke
				(width 0.1)
				(type solid)
			)
			(layer "F.SilkS")
		)
		(fp_line
			(start -0.106328 -8e-06)
			(end -0.29 0)
			(stroke
				(width 0.1)
				(type solid)
			)
			(layer "F.SilkS")
		)
		(fp_line
			(start -0.106328 -0.200008)
			(end 0.093672 -8e-06)
			(stroke
				(width 0.1)
				(type solid)
			)
			(layer "F.SilkS")
		)
		(fp_line
			(start -0.106328 -0.200008)
			(end -0.106328 0.199992)
			(stroke
				(width 0.1)
				(type solid)
			)
			(layer "F.SilkS")
		)
		(fp_line
			(start -0.27 0.351)
			(end 0.27 0.351)
			(stroke
				(width 0.15)
				(type solid)
			)
			(layer "F.SilkS")
		)
		(fp_line
			(start -0.27 -0.35)
			(end 0.27 -0.35)
			(stroke
				(width 0.15)
				(type solid)
			)
			(layer "F.SilkS")
		)
		(fp_rect
			(start 1.26 0.65)
			(end -1.26 -0.65)
			(stroke
				(width 0.05)
				(type solid)
			)
			(fill no)
			(layer "F.CrtYd")
		)
		(fp_line
			(start 0.199 0.202)
			(end 0.199 -0.1)
			(stroke
				(width 0.15)
				(type solid)
			)
			(layer "F.Fab")
		)
		(fp_line
			(start 0.199 0)
			(end 0.597 0)
			(stroke
				(width 0.15)
				(type solid)
			)
			(layer "F.Fab")
		)
		(fp_line
			(start 0.199 -0.2)
			(end 0.199 -0.1)
			(stroke
				(width 0.15)
				(type solid)
			)
			(layer "F.Fab")
		)
		(fp_line
			(start 0.101 0)
			(end -0.201 -0.2)
			(stroke
				(width 0.15)
				(type solid)
			)
			(layer "F.Fab")
		)
		(fp_line
			(start -0.201 0.202)
			(end 0.101 0)
			(stroke
				(width 0.15)
				(type solid)
			)
			(layer "F.Fab")
		)
		(fp_line
			(start -0.201 0)
			(end -0.201 0.202)
			(stroke
				(width 0.15)
				(type solid)
			)
			(layer "F.Fab")
		)
		(fp_line
			(start -0.201 -0.2)
			(end -0.201 0)
			(stroke
				(width 0.15)
				(type solid)
			)
			(layer "F.Fab")
		)
		(fp_line
			(start -0.599 0)
			(end -0.201 0)
			(stroke
				(width 0.15)
				(type solid)
			)
			(layer "F.Fab")
		)
		(fp_rect
			(start -0.848 -0.4)
			(end 0.85 0.402)
			(stroke
				(width 0.15)
				(type solid)
			)
			(fill no)
			(layer "F.Fab")
		)
		(pad "1" smd rect
			(at -0.75 0)
			(size 0.8 0.8)
			(layers "F.Cu" "F.Mask" "F.Paste")
			(net 459 "3V3_SYS")
			(pinfunction "1")
			(pintype "passive")
		)
		(pad "2" smd rect
			(at 0.75 0)
			(size 0.8 0.8)
			(layers "F.Cu" "F.Mask" "F.Paste")
			(net 67 "Net-(D9-Pad2)")
			(pinfunction "2")
			(pintype "passive")
		)
	)
	(footprint "antmicro-footprints:SC70-3"
		(layer "F.Cu")
		(at 199.686328 87.05)
		(property "Reference" "Q7"
			(at -0.79 2.05 0)
			(layer "F.SilkS")
			(effects
				(font
					(size 0.7 0.7)
					(thickness 0.15)
				)
				(justify left bottom)
			)
		)
		(property "Value" "BSS138PW"
			(at 0 2.3 0)
			(layer "F.Fab")
			(effects
				(font
					(size 0.7 0.7)
					(thickness 0.15)
				)
				(justify left bottom)
			)
		)
		(property "Description" "60 V, 320 mA N-channel enhancement mode Trench MOSFET, SC-70-3 aka SOT-323 package"
			(at 0 0 0)
			(layer "F.Fab")
			(hide yes)
			(effects
				(font
					(size 1.27 1.27)
					(thickness 0.15)
				)
			)
		)
		(property "Author" "Antmicro"
			(at 0 0 0)
			(layer "F.Fab")
			(hide yes)
			(effects
				(font
					(size 1 1)
					(thickness 0.15)
				)
			)
		)
		(property "License" "Apache-2.0"
			(at 0 0 0)
			(layer "F.Fab")
			(hide yes)
			(effects
				(font
					(size 1 1)
					(thickness 0.15)
				)
			)
		)
		(property "MPN" "BSS138PW"
			(at 0 0 0)
			(layer "F.Fab")
			(hide yes)
			(effects
				(font
					(size 1 1)
					(thickness 0.15)
				)
			)
		)
		(property "Manufacturer" "Nexperia"
			(at 0 0 0)
			(layer "F.Fab")
			(hide yes)
			(effects
				(font
					(size 1 1)
					(thickness 0.15)
				)
			)
		)
		(sheetname "Config SPI flash")
		(sheetfile "config-spi.kicad_sch")
		(attr smd)
		(fp_line
			(start -0.3 -1)
			(end 0.627 -0.999)
			(stroke
				(width 0.15)
				(type solid)
			)
			(layer "F.SilkS")
		)
		(fp_line
			(start -0.3 1)
			(end 0.627 1.001)
			(stroke
				(width 0.15)
				(type solid)
			)
			(layer "F.SilkS")
		)
		(fp_line
			(start 0.627 -0.6)
			(end 0.627 -0.999)
			(stroke
				(width 0.15)
				(type solid)
			)
			(layer "F.SilkS")
		)
		(fp_line
			(start 0.627 0.6)
			(end 0.627 1.001)
			(stroke
				(width 0.15)
				(type solid)
			)
			(layer "F.SilkS")
		)
		(fp_line
			(start -1.4 1)
			(end -1.4 -1)
			(stroke
				(width 0.05)
				(type solid)
			)
			(layer "F.CrtYd")
		)
		(fp_line
			(start -0.9 -1.3)
			(end -0.9 -1)
			(stroke
				(width 0.05)
				(type solid)
			)
			(layer "F.CrtYd")
		)
		(fp_line
			(start -0.9 -1.3)
			(end 0.9 -1.3)
			(stroke
				(width 0.05)
				(type solid)
			)
			(layer "F.CrtYd")
		)
		(fp_line
			(start -0.9 -1)
			(end -1.4 -1)
			(stroke
				(width 0.05)
				(type solid)
			)
			(layer "F.CrtYd")
		)
		(fp_line
			(start -0.9 1)
			(end -1.4 1)
			(stroke
				(width 0.05)
				(type solid)
			)
			(layer "F.CrtYd")
		)
		(fp_line
			(start -0.9 1.3)
			(end -0.9 1)
			(stroke
				(width 0.05)
				(type solid)
			)
			(layer "F.CrtYd")
		)
		(fp_line
			(start 0.9 -1.3)
			(end 0.9 -0.4)
			(stroke
				(width 0.05)
				(type solid)
			)
			(layer "F.CrtYd")
		)
		(fp_line
			(start 0.9 -0.4)
			(end 1.4 -0.4)
			(stroke
				(width 0.05)
				(type solid)
			)
			(layer "F.CrtYd")
		)
		(fp_line
			(start 0.9 0.4)
			(end 0.9 1.3)
			(stroke
				(width 0.05)
				(type solid)
			)
			(layer "F.CrtYd")
		)
		(fp_line
			(start 0.9 1.3)
			(end -0.9 1.3)
			(stroke
				(width 0.05)
				(type solid)
			)
			(layer "F.CrtYd")
		)
		(fp_line
			(start 1.4 -0.4)
			(end 1.4 0.4)
			(stroke
				(width 0.05)
				(type solid)
			)
			(layer "F.CrtYd")
		)
		(fp_line
			(start 1.4 0.4)
			(end 0.9 0.4)
			(stroke
				(width 0.05)
				(type solid)
			)
			(layer "F.CrtYd")
		)
		(fp_rect
			(start -0.623 -0.999)
			(end 0.627 1.001)
			(stroke
				(width 0.15)
				(type solid)
			)
			(fill no)
			(layer "F.Fab")
		)
		(pad "1" smd rect
			(at -0.95 -0.65 90)
			(size 0.6 0.8)
			(layers "F.Cu" "F.Mask" "F.Paste")
			(net 210 "INIT_B")
			(pinfunction "G")
			(pintype "bidirectional")
		)
		(pad "2" smd rect
			(at -0.95 0.65 90)
			(size 0.6 0.8)
			(layers "F.Cu" "F.Mask" "F.Paste")
			(net 5 "GND")
			(pinfunction "S")
			(pintype "bidirectional")
		)
		(pad "3" smd rect
			(at 0.95 0 90)
			(size 0.6 0.8)
			(layers "F.Cu" "F.Mask" "F.Paste")
			(net 233 "Net-(Q7-D)")
			(pinfunction "D")
			(pintype "bidirectional")
		)
	)
	(footprint "antmicro-footprints:R_0402_1005Metric"
		(layer "F.Cu")
		(at 173.375 111.667 90)
		(descr "Resistor SMD 0402")
		(tags "resistor SMD 0402")
		(property "Reference" "R60"
			(at 0.767 0.425 90)
			(layer "F.SilkS")
			(effects
				(font
					(size 0.7 0.7)
					(thickness 0.15)
				)
				(justify left bottom)
			)
		)
		(property "Value" "R_100R_0402"
			(at 0 1.4 90)
			(layer "F.Fab")
			(effects
				(font
					(size 0.7 0.7)
					(thickness 0.15)
				)
				(justify left bottom)
			)
		)
		(property "Description" "100R resistor in 0402 package with 1% tolerance"
			(at 0 0 90)
			(layer "F.Fab")
			(hide yes)
			(effects
				(font
					(size 1.27 1.27)
					(thickness 0.15)
				)
			)
		)
		(property "Author" "Antmicro"
			(at 285.042 -61.708 0)
			(layer "F.Fab")
			(hide yes)
			(effects
				(font
					(size 1 1)
					(thickness 0.15)
				)
			)
		)
		(property "License" "Apache-2.0"
			(at 285.042 -61.708 0)
			(layer "F.Fab")
			(hide yes)
			(effects
				(font
					(size 1 1)
					(thickness 0.15)
				)
			)
		)
		(property "MPN" "CR0402-FX-1000GLF"
			(at 285.042 -61.708 0)
			(layer "F.Fab")
			(hide yes)
			(effects
				(font
					(size 1 1)
					(thickness 0.15)
				)
			)
		)
		(property "Manufacturer" "Bourns"
			(at 285.042 -61.708 0)
			(layer "F.Fab")
			(hide yes)
			(effects
				(font
					(size 1 1)
					(thickness 0.15)
				)
			)
		)
		(property "Tolerance" "1%"
			(at 285.042 -61.708 0)
			(layer "F.Fab")
			(hide yes)
			(effects
				(font
					(size 1 1)
					(thickness 0.15)
				)
			)
		)
		(property "Val" "100R"
			(at 285.042 -61.708 0)
			(layer "F.Fab")
			(hide yes)
			(effects
				(font
					(size 1 1)
					(thickness 0.15)
				)
			)
		)
		(sheetname "Config SPI flash")
		(sheetfile "config-spi.kicad_sch")
		(attr smd)
		(fp_rect
			(start -0.93 -0.47)
			(end 0.93 0.47)
			(stroke
				(width 0.05)
				(type solid)
			)
			(fill no)
			(layer "F.CrtYd")
		)
		(fp_rect
			(start -0.5 -0.25)
			(end 0.5 0.25)
			(stroke
				(width 0.15)
				(type solid)
			)
			(fill no)
			(layer "F.Fab")
		)
		(pad "1" smd roundrect
			(at -0.485 0 90)
			(size 0.59 0.64)
			(layers "F.Cu" "F.Mask" "F.Paste")
			(roundrect_rratio 0.25)
			(net 459 "3V3_SYS")
			(pintype "passive")
		)
		(pad "2" smd roundrect
			(at 0.485 0 90)
			(size 0.59 0.64)
			(layers "F.Cu" "F.Mask" "F.Paste")
			(roundrect_rratio 0.25)
			(net 95 "PUDC_B")
			(pintype "passive")
		)
	)
	(footprint "antmicro-footprints:R_0402_1005Metric"
		(layer "F.Cu")
		(at 204.186328 79.320008 -90)
		(descr "Resistor SMD 0402")
		(tags "resistor SMD 0402")
		(property "Reference" "R64"
			(at 3.079992 -0.413672 270)
			(layer "F.SilkS")
			(effects
				(font
					(size 0.7 0.7)
					(thickness 0.15)
				)
				(justify left bottom)
			)
		)
		(property "Value" "R_0R_0402"
			(at 0 1.4 270)
			(layer "F.Fab")
			(effects
				(font
					(size 0.7 0.7)
					(thickness 0.15)
				)
				(justify left bottom)
			)
		)
		(property "Description" "0R resistor in 0402 package with unspecified tolerance"
			(at 0 0 270)
			(layer "F.Fab")
			(hide yes)
			(effects
				(font
					(size 1.27 1.27)
					(thickness 0.15)
				)
			)
		)
		(property "Author" "Antmicro"
			(at 124.86632 283.506336 0)
			(layer "F.Fab")
			(hide yes)
			(effects
				(font
					(size 1 1)
					(thickness 0.15)
				)
			)
		)
		(property "Current" "1A"
			(at 124.86632 283.506336 0)
			(layer "F.Fab")
			(hide yes)
			(effects
				(font
					(size 1 1)
					(thickness 0.15)
				)
			)
		)
		(property "License" "Apache-2.0"
			(at 124.86632 283.506336 0)
			(layer "F.Fab")
			(hide yes)
			(effects
				(font
					(size 1 1)
					(thickness 0.15)
				)
			)
		)
		(property "MPN" "ERJ2GE0R00X"
			(at 124.86632 283.506336 0)
			(layer "F.Fab")
			(hide yes)
			(effects
				(font
					(size 1 1)
					(thickness 0.15)
				)
			)
		)
		(property "Manufacturer" "Panasonic"
			(at 124.86632 283.506336 0)
			(layer "F.Fab")
			(hide yes)
			(effects
				(font
					(size 1 1)
					(thickness 0.15)
				)
			)
		)
		(property "Tolerance" ""
			(at 124.86632 283.506336 0)
			(layer "F.Fab")
			(hide yes)
			(effects
				(font
					(size 1 1)
					(thickness 0.15)
				)
			)
		)
		(property "Val" "0R"
			(at 124.86632 283.506336 0)
			(layer "F.Fab")
			(hide yes)
			(effects
				(font
					(size 1 1)
					(thickness 0.15)
				)
			)
		)
		(sheetname "Config SPI flash")
		(sheetfile "config-spi.kicad_sch")
		(attr exclude_from_pos_files exclude_from_bom dnp)
		(fp_rect
			(start -0.93 -0.47)
			(end 0.93 0.47)
			(stroke
				(width 0.05)
				(type solid)
			)
			(fill no)
			(layer "F.CrtYd")
		)
		(fp_rect
			(start -0.5 -0.25)
			(end 0.5 0.25)
			(stroke
				(width 0.15)
				(type solid)
			)
			(fill no)
			(layer "F.Fab")
		)
		(pad "1" smd roundrect
			(at -0.485 0 270)
			(size 0.59 0.64)
			(layers "F.Cu" "F.Mask" "F.Paste")
			(roundrect_rratio 0.25)
			(net 20 "MODE1")
			(pintype "passive")
		)
		(pad "2" smd roundrect
			(at 0.485 0 270)
			(size 0.59 0.64)
			(layers "F.Cu" "F.Mask" "F.Paste")
			(roundrect_rratio 0.25)
			(net 459 "3V3_SYS")
			(pintype "passive")
		)
	)
	(footprint "antmicro-footprints:R_0402_1005Metric"
		(layer "F.Cu")
		(at 203.086328 79.320008 -90)
		(descr "Resistor SMD 0402")
		(tags "resistor SMD 0402")
		(property "Reference" "R65"
			(at 3.079992 -0.413672 270)
			(layer "F.SilkS")
			(effects
				(font
					(size 0.7 0.7)
					(thickness 0.15)
				)
				(justify left bottom)
			)
		)
		(property "Value" "R_0R_0402"
			(at 0 1.4 270)
			(layer "F.Fab")
			(effects
				(font
					(size 0.7 0.7)
					(thickness 0.15)
				)
				(justify left bottom)
			)
		)
		(property "Description" "0R resistor in 0402 package with unspecified tolerance"
			(at 0 0 270)
			(layer "F.Fab")
			(hide yes)
			(effects
				(font
					(size 1.27 1.27)
					(thickness 0.15)
				)
			)
		)
		(property "Author" "Antmicro"
			(at 123.76632 282.406336 0)
			(layer "F.Fab")
			(hide yes)
			(effects
				(font
					(size 1 1)
					(thickness 0.15)
				)
			)
		)
		(property "Current" "1A"
			(at 123.76632 282.406336 0)
			(layer "F.Fab")
			(hide yes)
			(effects
				(font
					(size 1 1)
					(thickness 0.15)
				)
			)
		)
		(property "License" "Apache-2.0"
			(at 123.76632 282.406336 0)
			(layer "F.Fab")
			(hide yes)
			(effects
				(font
					(size 1 1)
					(thickness 0.15)
				)
			)
		)
		(property "MPN" "ERJ2GE0R00X"
			(at 123.76632 282.406336 0)
			(layer "F.Fab")
			(hide yes)
			(effects
				(font
					(size 1 1)
					(thickness 0.15)
				)
			)
		)
		(property "Manufacturer" "Panasonic"
			(at 123.76632 282.406336 0)
			(layer "F.Fab")
			(hide yes)
			(effects
				(font
					(size 1 1)
					(thickness 0.15)
				)
			)
		)
		(property "Tolerance" ""
			(at 123.76632 282.406336 0)
			(layer "F.Fab")
			(hide yes)
			(effects
				(font
					(size 1 1)
					(thickness 0.15)
				)
			)
		)
		(property "Val" "0R"
			(at 123.76632 282.406336 0)
			(layer "F.Fab")
			(hide yes)
			(effects
				(font
					(size 1 1)
					(thickness 0.15)
				)
			)
		)
		(sheetname "Config SPI flash")
		(sheetfile "config-spi.kicad_sch")
		(attr smd)
		(fp_rect
			(start -0.93 -0.47)
			(end 0.93 0.47)
			(stroke
				(width 0.05)
				(type solid)
			)
			(fill no)
			(layer "F.CrtYd")
		)
		(fp_rect
			(start -0.5 -0.25)
			(end 0.5 0.25)
			(stroke
				(width 0.15)
				(type solid)
			)
			(fill no)
			(layer "F.Fab")
		)
		(pad "1" smd roundrect
			(at -0.485 0 270)
			(size 0.59 0.64)
			(layers "F.Cu" "F.Mask" "F.Paste")
			(roundrect_rratio 0.25)
			(net 20 "MODE1")
			(pintype "passive")
		)
		(pad "2" smd roundrect
			(at 0.485 0 270)
			(size 0.59 0.64)
			(layers "F.Cu" "F.Mask" "F.Paste")
			(roundrect_rratio 0.25)
			(net 5 "GND")
			(pintype "passive")
		)
	)
	(footprint "antmicro-footprints:R_0402_1005Metric"
		(layer "F.Cu")
		(at 168.822 115.731 180)
		(descr "Resistor SMD 0402")
		(tags "resistor SMD 0402")
		(property "Reference" "R47"
			(at 1.322 -3.969 180)
			(layer "F.SilkS")
			(effects
				(font
					(size 0.7 0.7)
					(thickness 0.15)
				)
				(justify left bottom)
			)
		)
		(property "Value" "R_0R_0402"
			(at 0 1.4 180)
			(layer "F.Fab")
			(effects
				(font
					(size 0.7 0.7)
					(thickness 0.15)
				)
				(justify left bottom)
			)
		)
		(property "Description" "0R resistor in 0402 package with unspecified tolerance"
			(at 0 0 180)
			(layer "F.Fab")
			(hide yes)
			(effects
				(font
					(size 1.27 1.27)
					(thickness 0.15)
				)
			)
		)
		(property "Author" "Antmicro"
			(at 337.644 231.462 0)
			(layer "F.Fab")
			(hide yes)
			(effects
				(font
					(size 1 1)
					(thickness 0.15)
				)
			)
		)
		(property "Current" "1A"
			(at 337.644 231.462 0)
			(layer "F.Fab")
			(hide yes)
			(effects
				(font
					(size 1 1)
					(thickness 0.15)
				)
			)
		)
		(property "License" "Apache-2.0"
			(at 337.644 231.462 0)
			(layer "F.Fab")
			(hide yes)
			(effects
				(font
					(size 1 1)
					(thickness 0.15)
				)
			)
		)
		(property "MPN" "ERJ2GE0R00X"
			(at 337.644 231.462 0)
			(layer "F.Fab")
			(hide yes)
			(effects
				(font
					(size 1 1)
					(thickness 0.15)
				)
			)
		)
		(property "Manufacturer" "Panasonic"
			(at 337.644 231.462 0)
			(layer "F.Fab")
			(hide yes)
			(effects
				(font
					(size 1 1)
					(thickness 0.15)
				)
			)
		)
		(property "Tolerance" ""
			(at 337.644 231.462 0)
			(layer "F.Fab")
			(hide yes)
			(effects
				(font
					(size 1 1)
					(thickness 0.15)
				)
			)
		)
		(property "Val" "0R"
			(at 337.644 231.462 0)
			(layer "F.Fab")
			(hide yes)
			(effects
				(font
					(size 1 1)
					(thickness 0.15)
				)
			)
		)
		(sheetname "Config SPI flash")
		(sheetfile "config-spi.kicad_sch")
		(attr smd)
		(fp_rect
			(start -0.93 -0.47)
			(end 0.93 0.47)
			(stroke
				(width 0.05)
				(type solid)
			)
			(fill no)
			(layer "F.CrtYd")
		)
		(fp_rect
			(start -0.5 -0.25)
			(end 0.5 0.25)
			(stroke
				(width 0.15)
				(type solid)
			)
			(fill no)
			(layer "F.Fab")
		)
		(pad "1" smd roundrect
			(at -0.485 0 180)
			(size 0.59 0.64)
			(layers "F.Cu" "F.Mask" "F.Paste")
			(roundrect_rratio 0.25)
			(net 255 "Net-(U5-*CS)")
			(pintype "passive")
		)
		(pad "2" smd roundrect
			(at 0.485 0 180)
			(size 0.59 0.64)
			(layers "F.Cu" "F.Mask" "F.Paste")
			(roundrect_rratio 0.25)
			(net 212 "FCS_B")
			(pintype "passive")
		)
	)
	(footprint "antmicro-footprints:R_0402_1005Metric"
		(layer "F.Cu")
		(at 168.822 118.271 180)
		(descr "Resistor SMD 0402")
		(tags "resistor SMD 0402")
		(property "Reference" "R50"
			(at 1.322 -3.529 180)
			(layer "F.SilkS")
			(effects
				(font
					(size 0.7 0.7)
					(thickness 0.15)
				)
				(justify left bottom)
			)
		)
		(property "Value" "R_0R_0402"
			(at 0 1.4 180)
			(layer "F.Fab")
			(effects
				(font
					(size 0.7 0.7)
					(thickness 0.15)
				)
				(justify left bottom)
			)
		)
		(property "Description" "0R resistor in 0402 package with unspecified tolerance"
			(at 0 0 180)
			(layer "F.Fab")
			(hide yes)
			(effects
				(font
					(size 1.27 1.27)
					(thickness 0.15)
				)
			)
		)
		(property "Author" "Antmicro"
			(at 337.644 236.542 0)
			(layer "F.Fab")
			(hide yes)
			(effects
				(font
					(size 1 1)
					(thickness 0.15)
				)
			)
		)
		(property "Current" "1A"
			(at 337.644 236.542 0)
			(layer "F.Fab")
			(hide yes)
			(effects
				(font
					(size 1 1)
					(thickness 0.15)
				)
			)
		)
		(property "License" "Apache-2.0"
			(at 337.644 236.542 0)
			(layer "F.Fab")
			(hide yes)
			(effects
				(font
					(size 1 1)
					(thickness 0.15)
				)
			)
		)
		(property "MPN" "ERJ2GE0R00X"
			(at 337.644 236.542 0)
			(layer "F.Fab")
			(hide yes)
			(effects
				(font
					(size 1 1)
					(thickness 0.15)
				)
			)
		)
		(property "Manufacturer" "Panasonic"
			(at 337.644 236.542 0)
			(layer "F.Fab")
			(hide yes)
			(effects
				(font
					(size 1 1)
					(thickness 0.15)
				)
			)
		)
		(property "Tolerance" ""
			(at 337.644 236.542 0)
			(layer "F.Fab")
			(hide yes)
			(effects
				(font
					(size 1 1)
					(thickness 0.15)
				)
			)
		)
		(property "Val" "0R"
			(at 337.644 236.542 0)
			(layer "F.Fab")
			(hide yes)
			(effects
				(font
					(size 1 1)
					(thickness 0.15)
				)
			)
		)
		(sheetname "Config SPI flash")
		(sheetfile "config-spi.kicad_sch")
		(attr smd)
		(fp_rect
			(start -0.93 -0.47)
			(end 0.93 0.47)
			(stroke
				(width 0.05)
				(type solid)
			)
			(fill no)
			(layer "F.CrtYd")
		)
		(fp_rect
			(start -0.5 -0.25)
			(end 0.5 0.25)
			(stroke
				(width 0.15)
				(type solid)
			)
			(fill no)
			(layer "F.Fab")
		)
		(pad "1" smd roundrect
			(at -0.485 0 180)
			(size 0.59 0.64)
			(layers "F.Cu" "F.Mask" "F.Paste")
			(roundrect_rratio 0.25)
			(net 258 "Net-(U5-*WP{slash}IO2)")
			(pintype "passive")
		)
		(pad "2" smd roundrect
			(at 0.485 0 180)
			(size 0.59 0.64)
			(layers "F.Cu" "F.Mask" "F.Paste")
			(roundrect_rratio 0.25)
			(net 17 "QSPI_DQ2")
			(pintype "passive")
		)
	)
	(footprint "antmicro-footprints:R_0402_1005Metric"
		(layer "F.Cu")
		(at 202.386328 86.620008 180)
		(descr "Resistor SMD 0402")
		(tags "resistor SMD 0402")
		(property "Reference" "R58"
			(at 0.886328 -1.279992 180)
			(layer "F.SilkS")
			(effects
				(font
					(size 0.7 0.7)
					(thickness 0.15)
				)
				(justify left bottom)
			)
		)
		(property "Value" "R_330R_0402"
			(at 0 1.4 180)
			(layer "F.Fab")
			(effects
				(font
					(size 0.7 0.7)
					(thickness 0.15)
				)
				(justify left bottom)
			)
		)
		(property "Description" "330R resistor in 0402 package with 1% tolerance"
			(at 0 0 180)
			(layer "F.Fab")
			(hide yes)
			(effects
				(font
					(size 1.27 1.27)
					(thickness 0.15)
				)
			)
		)
		(property "Author" "Antmicro"
			(at 404.772656 173.240016 0)
			(layer "F.Fab")
			(hide yes)
			(effects
				(font
					(size 1 1)
					(thickness 0.15)
				)
			)
		)
		(property "License" "Apache-2.0"
			(at 404.772656 173.240016 0)
			(layer "F.Fab")
			(hide yes)
			(effects
				(font
					(size 1 1)
					(thickness 0.15)
				)
			)
		)
		(property "MPN" "CR0402-FX-3300GLF"
			(at 404.772656 173.240016 0)
			(layer "F.Fab")
			(hide yes)
			(effects
				(font
					(size 1 1)
					(thickness 0.15)
				)
			)
		)
		(property "Manufacturer" "Bourns"
			(at 404.772656 173.240016 0)
			(layer "F.Fab")
			(hide yes)
			(effects
				(font
					(size 1 1)
					(thickness 0.15)
				)
			)
		)
		(property "Tolerance" "1%"
			(at 404.772656 173.240016 0)
			(layer "F.Fab")
			(hide yes)
			(effects
				(font
					(size 1 1)
					(thickness 0.15)
				)
			)
		)
		(property "Val" "330R"
			(at 404.772656 173.240016 0)
			(layer "F.Fab")
			(hide yes)
			(effects
				(font
					(size 1 1)
					(thickness 0.15)
				)
			)
		)
		(sheetname "Config SPI flash")
		(sheetfile "config-spi.kicad_sch")
		(attr smd)
		(fp_rect
			(start -0.93 -0.47)
			(end 0.93 0.47)
			(stroke
				(width 0.05)
				(type solid)
			)
			(fill no)
			(layer "F.CrtYd")
		)
		(fp_rect
			(start -0.5 -0.25)
			(end 0.5 0.25)
			(stroke
				(width 0.15)
				(type solid)
			)
			(fill no)
			(layer "F.Fab")
		)
		(pad "1" smd roundrect
			(at -0.485 0 180)
			(size 0.59 0.64)
			(layers "F.Cu" "F.Mask" "F.Paste")
			(roundrect_rratio 0.25)
			(net 67 "Net-(D9-Pad2)")
			(pintype "passive")
		)
		(pad "2" smd roundrect
			(at 0.485 0 180)
			(size 0.59 0.64)
			(layers "F.Cu" "F.Mask" "F.Paste")
			(roundrect_rratio 0.25)
			(net 233 "Net-(Q7-D)")
			(pintype "passive")
		)
	)
	(footprint "antmicro-footprints:R_0402_1005Metric"
		(layer "F.Cu")
		(at 213.686328 93.220008 180)
		(descr "Resistor SMD 0402")
		(tags "resistor SMD 0402")
		(property "Reference" "R67"
			(at 1.086328 0.520008 180)
			(layer "F.SilkS")
			(effects
				(font
					(size 0.7 0.7)
					(thickness 0.15)
				)
				(justify left bottom)
			)
		)
		(property "Value" "R_4k7_0402"
			(at 0 1.4 180)
			(layer "F.Fab")
			(effects
				(font
					(size 0.7 0.7)
					(thickness 0.15)
				)
				(justify left bottom)
			)
		)
		(property "Description" "4k7 resistor in 0402 package with 1% tolerance"
			(at 0 0 180)
			(layer "F.Fab")
			(hide yes)
			(effects
				(font
					(size 1.27 1.27)
					(thickness 0.15)
				)
			)
		)
		(property "Author" "Antmicro"
			(at 427.372656 186.440016 0)
			(layer "F.Fab")
			(hide yes)
			(effects
				(font
					(size 1 1)
					(thickness 0.15)
				)
			)
		)
		(property "License" "Apache-2.0"
			(at 427.372656 186.440016 0)
			(layer "F.Fab")
			(hide yes)
			(effects
				(font
					(size 1 1)
					(thickness 0.15)
				)
			)
		)
		(property "MPN" "CR0402-FX-4701GLF"
			(at 427.372656 186.440016 0)
			(layer "F.Fab")
			(hide yes)
			(effects
				(font
					(size 1 1)
					(thickness 0.15)
				)
			)
		)
		(property "Manufacturer" "Bourns"
			(at 427.372656 186.440016 0)
			(layer "F.Fab")
			(hide yes)
			(effects
				(font
					(size 1 1)
					(thickness 0.15)
				)
			)
		)
		(property "Tolerance" "1%"
			(at 427.372656 186.440016 0)
			(layer "F.Fab")
			(hide yes)
			(effects
				(font
					(size 1 1)
					(thickness 0.15)
				)
			)
		)
		(property "Val" "4k7"
			(at 427.372656 186.440016 0)
			(layer "F.Fab")
			(hide yes)
			(effects
				(font
					(size 1 1)
					(thickness 0.15)
				)
			)
		)
		(sheetname "Config SPI flash")
		(sheetfile "config-spi.kicad_sch")
		(attr smd)
		(fp_rect
			(start -0.93 -0.47)
			(end 0.93 0.47)
			(stroke
				(width 0.05)
				(type solid)
			)
			(fill no)
			(layer "F.CrtYd")
		)
		(fp_rect
			(start -0.5 -0.25)
			(end 0.5 0.25)
			(stroke
				(width 0.15)
				(type solid)
			)
			(fill no)
			(layer "F.Fab")
		)
		(pad "1" smd roundrect
			(at -0.485 0 180)
			(size 0.59 0.64)
			(layers "F.Cu" "F.Mask" "F.Paste")
			(roundrect_rratio 0.25)
			(net 459 "3V3_SYS")
			(pintype "passive")
		)
		(pad "2" smd roundrect
			(at 0.485 0 180)
			(size 0.59 0.64)
			(layers "F.Cu" "F.Mask" "F.Paste")
			(roundrect_rratio 0.25)
			(net 208 "PROGRAM_B")
			(pintype "passive")
		)
	)
	(footprint "antmicro-footprints:R_0402_1005Metric"
		(layer "F.Cu")
		(at 172.359 111.667 -90)
		(descr "Resistor SMD 0402")
		(tags "resistor SMD 0402")
		(property "Reference" "R61"
			(at -0.768 -0.3 270)
			(layer "F.SilkS")
			(effects
				(font
					(size 0.7 0.7)
					(thickness 0.15)
				)
				(justify left bottom)
			)
		)
		(property "Value" "R_100R_0402"
			(at 0 1.4 270)
			(layer "F.Fab")
			(effects
				(font
					(size 0.7 0.7)
					(thickness 0.15)
				)
				(justify left bottom)
			)
		)
		(property "Description" "100R resistor in 0402 package with 1% tolerance"
			(at 0 0 270)
			(layer "F.Fab")
			(hide yes)
			(effects
				(font
					(size 1.27 1.27)
					(thickness 0.15)
				)
			)
		)
		(property "Author" "Antmicro"
			(at 60.692 284.026 0)
			(layer "F.Fab")
			(hide yes)
			(effects
				(font
					(size 1 1)
					(thickness 0.15)
				)
			)
		)
		(property "License" "Apache-2.0"
			(at 60.692 284.026 0)
			(layer "F.Fab")
			(hide yes)
			(effects
				(font
					(size 1 1)
					(thickness 0.15)
				)
			)
		)
		(property "MPN" "CR0402-FX-1000GLF"
			(at 60.692 284.026 0)
			(layer "F.Fab")
			(hide yes)
			(effects
				(font
					(size 1 1)
					(thickness 0.15)
				)
			)
		)
		(property "Manufacturer" "Bourns"
			(at 60.692 284.026 0)
			(layer "F.Fab")
			(hide yes)
			(effects
				(font
					(size 1 1)
					(thickness 0.15)
				)
			)
		)
		(property "Tolerance" "1%"
			(at 60.692 284.026 0)
			(layer "F.Fab")
			(hide yes)
			(effects
				(font
					(size 1 1)
					(thickness 0.15)
				)
			)
		)
		(property "Val" "100R"
			(at 60.692 284.026 0)
			(layer "F.Fab")
			(hide yes)
			(effects
				(font
					(size 1 1)
					(thickness 0.15)
				)
			)
		)
		(sheetname "Config SPI flash")
		(sheetfile "config-spi.kicad_sch")
		(attr exclude_from_pos_files exclude_from_bom dnp)
		(fp_rect
			(start -0.93 -0.47)
			(end 0.93 0.47)
			(stroke
				(width 0.05)
				(type solid)
			)
			(fill no)
			(layer "F.CrtYd")
		)
		(fp_rect
			(start -0.5 -0.25)
			(end 0.5 0.25)
			(stroke
				(width 0.15)
				(type solid)
			)
			(fill no)
			(layer "F.Fab")
		)
		(pad "1" smd roundrect
			(at -0.485 0 270)
			(size 0.59 0.64)
			(layers "F.Cu" "F.Mask" "F.Paste")
			(roundrect_rratio 0.25)
			(net 95 "PUDC_B")
			(pintype "passive")
		)
		(pad "2" smd roundrect
			(at 0.485 0 270)
			(size 0.59 0.64)
			(layers "F.Cu" "F.Mask" "F.Paste")
			(roundrect_rratio 0.25)
			(net 5 "GND")
			(pintype "passive")
		)
	)
	(footprint "antmicro-footprints:R_0402_1005Metric"
		(layer "F.Cu")
		(at 197.486328 84.720008 90)
		(descr "Resistor SMD 0402")
		(tags "resistor SMD 0402")
		(property "Reference" "R68"
			(at -0.879992 -0.486328 90)
			(layer "F.SilkS")
			(effects
				(font
					(size 0.7 0.7)
					(thickness 0.15)
				)
				(justify left bottom)
			)
		)
		(property "Value" "R_330R_0402"
			(at 0 1.4 90)
			(layer "F.Fab")
			(effects
				(font
					(size 0.7 0.7)
					(thickness 0.15)
				)
				(justify left bottom)
			)
		)
		(property "Description" "330R resistor in 0402 package with 1% tolerance"
			(at 0 0 90)
			(layer "F.Fab")
			(hide yes)
			(effects
				(font
					(size 1.27 1.27)
					(thickness 0.15)
				)
			)
		)
		(property "Author" "Antmicro"
			(at 282.206336 -112.76632 0)
			(layer "F.Fab")
			(hide yes)
			(effects
				(font
					(size 1 1)
					(thickness 0.15)
				)
			)
		)
		(property "License" "Apache-2.0"
			(at 282.206336 -112.76632 0)
			(layer "F.Fab")
			(hide yes)
			(effects
				(font
					(size 1 1)
					(thickness 0.15)
				)
			)
		)
		(property "MPN" "CR0402-FX-3300GLF"
			(at 282.206336 -112.76632 0)
			(layer "F.Fab")
			(hide yes)
			(effects
				(font
					(size 1 1)
					(thickness 0.15)
				)
			)
		)
		(property "Manufacturer" "Bourns"
			(at 282.206336 -112.76632 0)
			(layer "F.Fab")
			(hide yes)
			(effects
				(font
					(size 1 1)
					(thickness 0.15)
				)
			)
		)
		(property "Tolerance" "1%"
			(at 282.206336 -112.76632 0)
			(layer "F.Fab")
			(hide yes)
			(effects
				(font
					(size 1 1)
					(thickness 0.15)
				)
			)
		)
		(property "Val" "330R"
			(at 282.206336 -112.76632 0)
			(layer "F.Fab")
			(hide yes)
			(effects
				(font
					(size 1 1)
					(thickness 0.15)
				)
			)
		)
		(sheetname "Config SPI flash")
		(sheetfile "config-spi.kicad_sch")
		(attr smd)
		(fp_rect
			(start -0.93 -0.47)
			(end 0.93 0.47)
			(stroke
				(width 0.05)
				(type solid)
			)
			(fill no)
			(layer "F.CrtYd")
		)
		(fp_rect
			(start -0.5 -0.25)
			(end 0.5 0.25)
			(stroke
				(width 0.15)
				(type solid)
			)
			(fill no)
			(layer "F.Fab")
		)
		(pad "1" smd roundrect
			(at -0.485 0 90)
			(size 0.59 0.64)
			(layers "F.Cu" "F.Mask" "F.Paste")
			(roundrect_rratio 0.25)
			(net 459 "3V3_SYS")
			(pintype "passive")
		)
		(pad "2" smd roundrect
			(at 0.485 0 90)
			(size 0.59 0.64)
			(layers "F.Cu" "F.Mask" "F.Paste")
			(roundrect_rratio 0.25)
			(net 21 "DONE")
			(pintype "passive")
		)
	)
	(footprint "antmicro-footprints:R_0402_1005Metric"
		(layer "F.Cu")
		(at 188.886328 92.720008 180)
		(descr "Resistor SMD 0402")
		(tags "resistor SMD 0402")
		(property "Reference" "R69"
			(at 1.086328 -1.279992 180)
			(layer "F.SilkS")
			(effects
				(font
					(size 0.7 0.7)
					(thickness 0.15)
				)
				(justify left bottom)
			)
		)
		(property "Value" "R_0R_0402"
			(at 0 1.4 180)
			(layer "F.Fab")
			(effects
				(font
					(size 0.7 0.7)
					(thickness 0.15)
				)
				(justify left bottom)
			)
		)
		(property "Description" "0R resistor in 0402 package with unspecified tolerance"
			(at 0 0 180)
			(layer "F.Fab")
			(hide yes)
			(effects
				(font
					(size 1.27 1.27)
					(thickness 0.15)
				)
			)
		)
		(property "Author" "Antmicro"
			(at 377.772656 185.440016 0)
			(layer "F.Fab")
			(hide yes)
			(effects
				(font
					(size 1 1)
					(thickness 0.15)
				)
			)
		)
		(property "Current" "1A"
			(at 377.772656 185.440016 0)
			(layer "F.Fab")
			(hide yes)
			(effects
				(font
					(size 1 1)
					(thickness 0.15)
				)
			)
		)
		(property "License" "Apache-2.0"
			(at 377.772656 185.440016 0)
			(layer "F.Fab")
			(hide yes)
			(effects
				(font
					(size 1 1)
					(thickness 0.15)
				)
			)
		)
		(property "MPN" "ERJ2GE0R00X"
			(at 377.772656 185.440016 0)
			(layer "F.Fab")
			(hide yes)
			(effects
				(font
					(size 1 1)
					(thickness 0.15)
				)
			)
		)
		(property "Manufacturer" "Panasonic"
			(at 377.772656 185.440016 0)
			(layer "F.Fab")
			(hide yes)
			(effects
				(font
					(size 1 1)
					(thickness 0.15)
				)
			)
		)
		(property "Tolerance" ""
			(at 377.772656 185.440016 0)
			(layer "F.Fab")
			(hide yes)
			(effects
				(font
					(size 1 1)
					(thickness 0.15)
				)
			)
		)
		(property "Val" "0R"
			(at 377.772656 185.440016 0)
			(layer "F.Fab")
			(hide yes)
			(effects
				(font
					(size 1 1)
					(thickness 0.15)
				)
			)
		)
		(sheetname "Config SPI flash")
		(sheetfile "config-spi.kicad_sch")
		(attr smd)
		(fp_rect
			(start -0.93 -0.47)
			(end 0.93 0.47)
			(stroke
				(width 0.05)
				(type solid)
			)
			(fill no)
			(layer "F.CrtYd")
		)
		(fp_rect
			(start -0.5 -0.25)
			(end 0.5 0.25)
			(stroke
				(width 0.15)
				(type solid)
			)
			(fill no)
			(layer "F.Fab")
		)
		(pad "1" smd roundrect
			(at -0.485 0 180)
			(size 0.59 0.64)
			(layers "F.Cu" "F.Mask" "F.Paste")
			(roundrect_rratio 0.25)
			(net 459 "3V3_SYS")
			(pintype "passive")
		)
		(pad "2" smd roundrect
			(at 0.485 0 180)
			(size 0.59 0.64)
			(layers "F.Cu" "F.Mask" "F.Paste")
			(roundrect_rratio 0.25)
			(net 219 "CFGBVS")
			(pintype "passive")
		)
	)
	(footprint "antmicro-footprints:R_0402_1005Metric"
		(layer "F.Cu")
		(at 180.1885 119.541)
		(descr "Resistor SMD 0402")
		(tags "resistor SMD 0402")
		(property "Reference" "R51"
			(at 0.8115 0.399 0)
			(layer "F.SilkS")
			(effects
				(font
					(size 0.7 0.7)
					(thickness 0.15)
				)
				(justify left bottom)
			)
		)
		(property "Value" "R_0R_0402"
			(at 0 1.4 0)
			(layer "F.Fab")
			(effects
				(font
					(size 0.7 0.7)
					(thickness 0.15)
				)
				(justify left bottom)
			)
		)
		(property "Description" "0R resistor in 0402 package with unspecified tolerance"
			(at 0 0 0)
			(layer "F.Fab")
			(hide yes)
			(effects
				(font
					(size 1.27 1.27)
					(thickness 0.15)
				)
			)
		)
		(property "Author" "Antmicro"
			(at 0 0 0)
			(layer "F.Fab")
			(hide yes)
			(effects
				(font
					(size 1 1)
					(thickness 0.15)
				)
			)
		)
		(property "Current" "1A"
			(at 0 0 0)
			(layer "F.Fab")
			(hide yes)
			(effects
				(font
					(size 1 1)
					(thickness 0.15)
				)
			)
		)
		(property "License" "Apache-2.0"
			(at 0 0 0)
			(layer "F.Fab")
			(hide yes)
			(effects
				(font
					(size 1 1)
					(thickness 0.15)
				)
			)
		)
		(property "MPN" "ERJ2GE0R00X"
			(at 0 0 0)
			(layer "F.Fab")
			(hide yes)
			(effects
				(font
					(size 1 1)
					(thickness 0.15)
				)
			)
		)
		(property "Manufacturer" "Panasonic"
			(at 0 0 0)
			(layer "F.Fab")
			(hide yes)
			(effects
				(font
					(size 1 1)
					(thickness 0.15)
				)
			)
		)
		(property "Tolerance" ""
			(at 0 0 0)
			(layer "F.Fab")
			(hide yes)
			(effects
				(font
					(size 1 1)
					(thickness 0.15)
				)
			)
		)
		(property "Val" "0R"
			(at 0 0 0)
			(layer "F.Fab")
			(hide yes)
			(effects
				(font
					(size 1 1)
					(thickness 0.15)
				)
			)
		)
		(sheetname "Config SPI flash")
		(sheetfile "config-spi.kicad_sch")
		(attr smd)
		(fp_rect
			(start -0.93 -0.47)
			(end 0.93 0.47)
			(stroke
				(width 0.05)
				(type solid)
			)
			(fill no)
			(layer "F.CrtYd")
		)
		(fp_rect
			(start -0.5 -0.25)
			(end 0.5 0.25)
			(stroke
				(width 0.15)
				(type solid)
			)
			(fill no)
			(layer "F.Fab")
		)
		(pad "1" smd roundrect
			(at -0.485 0)
			(size 0.59 0.64)
			(layers "F.Cu" "F.Mask" "F.Paste")
			(roundrect_rratio 0.25)
			(net 259 "Net-(U5-SI{slash}IO0)")
			(pintype "passive")
		)
		(pad "2" smd roundrect
			(at 0.485 0)
			(size 0.59 0.64)
			(layers "F.Cu" "F.Mask" "F.Paste")
			(roundrect_rratio 0.25)
			(net 15 "QSPI_DQ0")
			(pintype "passive")
		)
	)
	(footprint "antmicro-footprints:R_0402_1005Metric"
		(layer "F.Cu")
		(at 168.822 117.001 180)
		(descr "Resistor SMD 0402")
		(tags "resistor SMD 0402")
		(property "Reference" "R52"
			(at 1.322 -3.729 180)
			(layer "F.SilkS")
			(effects
				(font
					(size 0.7 0.7)
					(thickness 0.15)
				)
				(justify left bottom)
			)
		)
		(property "Value" "R_0R_0402"
			(at 0 1.4 180)
			(layer "F.Fab")
			(effects
				(font
					(size 0.7 0.7)
					(thickness 0.15)
				)
				(justify left bottom)
			)
		)
		(property "Description" "0R resistor in 0402 package with unspecified tolerance"
			(at 0 0 180)
			(layer "F.Fab")
			(hide yes)
			(effects
				(font
					(size 1.27 1.27)
					(thickness 0.15)
				)
			)
		)
		(property "Author" "Antmicro"
			(at 337.644 234.002 0)
			(layer "F.Fab")
			(hide yes)
			(effects
				(font
					(size 1 1)
					(thickness 0.15)
				)
			)
		)
		(property "Current" "1A"
			(at 337.644 234.002 0)
			(layer "F.Fab")
			(hide yes)
			(effects
				(font
					(size 1 1)
					(thickness 0.15)
				)
			)
		)
		(property "License" "Apache-2.0"
			(at 337.644 234.002 0)
			(layer "F.Fab")
			(hide yes)
			(effects
				(font
					(size 1 1)
					(thickness 0.15)
				)
			)
		)
		(property "MPN" "ERJ2GE0R00X"
			(at 337.644 234.002 0)
			(layer "F.Fab")
			(hide yes)
			(effects
				(font
					(size 1 1)
					(thickness 0.15)
				)
			)
		)
		(property "Manufacturer" "Panasonic"
			(at 337.644 234.002 0)
			(layer "F.Fab")
			(hide yes)
			(effects
				(font
					(size 1 1)
					(thickness 0.15)
				)
			)
		)
		(property "Tolerance" ""
			(at 337.644 234.002 0)
			(layer "F.Fab")
			(hide yes)
			(effects
				(font
					(size 1 1)
					(thickness 0.15)
				)
			)
		)
		(property "Val" "0R"
			(at 337.644 234.002 0)
			(layer "F.Fab")
			(hide yes)
			(effects
				(font
					(size 1 1)
					(thickness 0.15)
				)
			)
		)
		(sheetname "Config SPI flash")
		(sheetfile "config-spi.kicad_sch")
		(attr smd)
		(fp_rect
			(start -0.93 -0.47)
			(end 0.93 0.47)
			(stroke
				(width 0.05)
				(type solid)
			)
			(fill no)
			(layer "F.CrtYd")
		)
		(fp_rect
			(start -0.5 -0.25)
			(end 0.5 0.25)
			(stroke
				(width 0.15)
				(type solid)
			)
			(fill no)
			(layer "F.Fab")
		)
		(pad "1" smd roundrect
			(at -0.485 0 180)
			(size 0.59 0.64)
			(layers "F.Cu" "F.Mask" "F.Paste")
			(roundrect_rratio 0.25)
			(net 260 "Net-(U5-SO{slash}IO1)")
			(pintype "passive")
		)
		(pad "2" smd roundrect
			(at 0.485 0 180)
			(size 0.59 0.64)
			(layers "F.Cu" "F.Mask" "F.Paste")
			(roundrect_rratio 0.25)
			(net 16 "QSPI_DQ1")
			(pintype "passive")
		)
	)
	(footprint "antmicro-footprints:R_0402_1005Metric"
		(layer "F.Cu")
		(at 180.1885 118.271)
		(descr "Resistor SMD 0402")
		(tags "resistor SMD 0402")
		(property "Reference" "R48"
			(at 0.8115 0.399 0)
			(layer "F.SilkS")
			(effects
				(font
					(size 0.7 0.7)
					(thickness 0.15)
				)
				(justify left bottom)
			)
		)
		(property "Value" "R_0R_0402"
			(at 0 1.4 0)
			(layer "F.Fab")
			(effects
				(font
					(size 0.7 0.7)
					(thickness 0.15)
				)
				(justify left bottom)
			)
		)
		(property "Description" "0R resistor in 0402 package with unspecified tolerance"
			(at 0 0 0)
			(layer "F.Fab")
			(hide yes)
			(effects
				(font
					(size 1.27 1.27)
					(thickness 0.15)
				)
			)
		)
		(property "Author" "Antmicro"
			(at 0 0 0)
			(layer "F.Fab")
			(hide yes)
			(effects
				(font
					(size 1 1)
					(thickness 0.15)
				)
			)
		)
		(property "Current" "1A"
			(at 0 0 0)
			(layer "F.Fab")
			(hide yes)
			(effects
				(font
					(size 1 1)
					(thickness 0.15)
				)
			)
		)
		(property "License" "Apache-2.0"
			(at 0 0 0)
			(layer "F.Fab")
			(hide yes)
			(effects
				(font
					(size 1 1)
					(thickness 0.15)
				)
			)
		)
		(property "MPN" "ERJ2GE0R00X"
			(at 0 0 0)
			(layer "F.Fab")
			(hide yes)
			(effects
				(font
					(size 1 1)
					(thickness 0.15)
				)
			)
		)
		(property "Manufacturer" "Panasonic"
			(at 0 0 0)
			(layer "F.Fab")
			(hide yes)
			(effects
				(font
					(size 1 1)
					(thickness 0.15)
				)
			)
		)
		(property "Tolerance" ""
			(at 0 0 0)
			(layer "F.Fab")
			(hide yes)
			(effects
				(font
					(size 1 1)
					(thickness 0.15)
				)
			)
		)
		(property "Val" "0R"
			(at 0 0 0)
			(layer "F.Fab")
			(hide yes)
			(effects
				(font
					(size 1 1)
					(thickness 0.15)
				)
			)
		)
		(sheetname "Config SPI flash")
		(sheetfile "config-spi.kicad_sch")
		(attr smd)
		(fp_rect
			(start -0.93 -0.47)
			(end 0.93 0.47)
			(stroke
				(width 0.05)
				(type solid)
			)
			(fill no)
			(layer "F.CrtYd")
		)
		(fp_rect
			(start -0.5 -0.25)
			(end 0.5 0.25)
			(stroke
				(width 0.15)
				(type solid)
			)
			(fill no)
			(layer "F.Fab")
		)
		(pad "1" smd roundrect
			(at -0.485 0)
			(size 0.59 0.64)
			(layers "F.Cu" "F.Mask" "F.Paste")
			(roundrect_rratio 0.25)
			(net 256 "Net-(U5-SCK)")
			(pintype "passive")
		)
		(pad "2" smd roundrect
			(at 0.485 0)
			(size 0.59 0.64)
			(layers "F.Cu" "F.Mask" "F.Paste")
			(roundrect_rratio 0.25)
			(net 213 "CCLK")
			(pintype "passive")
		)
	)
	(footprint "antmicro-footprints:R_0402_1005Metric"
		(layer "F.Cu")
		(at 202.386328 84.820008 180)
		(descr "Resistor SMD 0402")
		(tags "resistor SMD 0402")
		(property "Reference" "R57"
			(at 0.886328 0.520008 180)
			(layer "F.SilkS")
			(effects
				(font
					(size 0.7 0.7)
					(thickness 0.15)
				)
				(justify left bottom)
			)
		)
		(property "Value" "R_330R_0402"
			(at 0 1.4 180)
			(layer "F.Fab")
			(effects
				(font
					(size 0.7 0.7)
					(thickness 0.15)
				)
				(justify left bottom)
			)
		)
		(property "Description" "330R resistor in 0402 package with 1% tolerance"
			(at 0 0 180)
			(layer "F.Fab")
			(hide yes)
			(effects
				(font
					(size 1.27 1.27)
					(thickness 0.15)
				)
			)
		)
		(property "Author" "Antmicro"
			(at 404.772656 169.640016 0)
			(layer "F.Fab")
			(hide yes)
			(effects
				(font
					(size 1 1)
					(thickness 0.15)
				)
			)
		)
		(property "License" "Apache-2.0"
			(at 404.772656 169.640016 0)
			(layer "F.Fab")
			(hide yes)
			(effects
				(font
					(size 1 1)
					(thickness 0.15)
				)
			)
		)
		(property "MPN" "CR0402-FX-3300GLF"
			(at 404.772656 169.640016 0)
			(layer "F.Fab")
			(hide yes)
			(effects
				(font
					(size 1 1)
					(thickness 0.15)
				)
			)
		)
		(property "Manufacturer" "Bourns"
			(at 404.772656 169.640016 0)
			(layer "F.Fab")
			(hide yes)
			(effects
				(font
					(size 1 1)
					(thickness 0.15)
				)
			)
		)
		(property "Tolerance" "1%"
			(at 404.772656 169.640016 0)
			(layer "F.Fab")
			(hide yes)
			(effects
				(font
					(size 1 1)
					(thickness 0.15)
				)
			)
		)
		(property "Val" "330R"
			(at 404.772656 169.640016 0)
			(layer "F.Fab")
			(hide yes)
			(effects
				(font
					(size 1 1)
					(thickness 0.15)
				)
			)
		)
		(sheetname "Config SPI flash")
		(sheetfile "config-spi.kicad_sch")
		(attr smd)
		(fp_rect
			(start -0.93 -0.47)
			(end 0.93 0.47)
			(stroke
				(width 0.05)
				(type solid)
			)
			(fill no)
			(layer "F.CrtYd")
		)
		(fp_rect
			(start -0.5 -0.25)
			(end 0.5 0.25)
			(stroke
				(width 0.15)
				(type solid)
			)
			(fill no)
			(layer "F.Fab")
		)
		(pad "1" smd roundrect
			(at -0.485 0 180)
			(size 0.59 0.64)
			(layers "F.Cu" "F.Mask" "F.Paste")
			(roundrect_rratio 0.25)
			(net 54 "Net-(D8-Pad2)")
			(pintype "passive")
		)
		(pad "2" smd roundrect
			(at 0.485 0 180)
			(size 0.59 0.64)
			(layers "F.Cu" "F.Mask" "F.Paste")
			(roundrect_rratio 0.25)
			(net 232 "Net-(Q6-D)")
			(pintype "passive")
		)
	)
	(footprint "antmicro-footprints:C_0603_1608Metric"
		(layer "F.Cu")
		(at 139.5 98.249 180)
		(descr "Capacitor SMD 0603")
		(tags "capacitor 0603")
		(property "Reference" "C137"
			(at 1.6 -1.351 180)
			(layer "F.SilkS")
			(effects
				(font
					(size 0.7 0.7)
					(thickness 0.15)
				)
				(justify left bottom)
			)
		)
		(property "Value" "C_10n_0603"
			(at 0 1.6 180)
			(layer "F.Fab")
			(effects
				(font
					(size 0.7 0.7)
					(thickness 0.15)
				)
				(justify left bottom)
			)
		)
		(property "Description" " "
			(at 0 0 180)
			(layer "F.Fab")
			(hide yes)
			(effects
				(font
					(size 1.27 1.27)
					(thickness 0.15)
				)
			)
		)
		(property "Author" "Antmicro"
			(at 279 196.498 0)
			(layer "F.Fab")
			(hide yes)
			(effects
				(font
					(size 1 1)
					(thickness 0.15)
				)
			)
		)
		(property "Dielectric" ""
			(at 279 196.498 0)
			(layer "F.Fab")
			(hide yes)
			(effects
				(font
					(size 1 1)
					(thickness 0.15)
				)
			)
		)
		(property "License" "Apache-2.0"
			(at 279 196.498 0)
			(layer "F.Fab")
			(hide yes)
			(effects
				(font
					(size 1 1)
					(thickness 0.15)
				)
			)
		)
		(property "MPN" "06031C103JAT2A"
			(at 279 196.498 0)
			(layer "F.Fab")
			(hide yes)
			(effects
				(font
					(size 1 1)
					(thickness 0.15)
				)
			)
		)
		(property "Manufacturer" "AVX"
			(at 279 196.498 0)
			(layer "F.Fab")
			(hide yes)
			(effects
				(font
					(size 1 1)
					(thickness 0.15)
				)
			)
		)
		(property "Val" "10n"
			(at 279 196.498 0)
			(layer "F.Fab")
			(hide yes)
			(effects
				(font
					(size 1 1)
					(thickness 0.15)
				)
			)
		)
		(property "Voltage" ""
			(at 279 196.498 0)
			(layer "F.Fab")
			(hide yes)
			(effects
				(font
					(size 1 1)
					(thickness 0.15)
				)
			)
		)
		(sheetname "Supply")
		(sheetfile "supply.kicad_sch")
		(attr smd)
		(fp_line
			(start -0.3 0.3)
			(end 0.3 0.3)
			(stroke
				(width 0.15)
				(type solid)
			)
			(layer "F.SilkS")
		)
		(fp_line
			(start -0.3 -0.3)
			(end 0.3 -0.3)
			(stroke
				(width 0.15)
				(type solid)
			)
			(layer "F.SilkS")
		)
		(fp_rect
			(start -1.24 -0.7)
			(end 1.24 0.7)
			(stroke
				(width 0.05)
				(type solid)
			)
			(fill no)
			(layer "F.CrtYd")
		)
		(fp_rect
			(start -0.8 -0.4)
			(end 0.8 0.4)
			(stroke
				(width 0.15)
				(type solid)
			)
			(fill no)
			(layer "F.Fab")
		)
		(pad "1" smd roundrect
			(at -0.7 0 180)
			(size 0.6 0.8)
			(layers "F.Cu" "F.Mask" "F.Paste")
			(roundrect_rratio 0.2)
			(net 58 "Net-(U7-TADJ)")
			(pintype "passive")
		)
		(pad "2" smd roundrect
			(at 0.7 0 180)
			(size 0.6 0.8)
			(layers "F.Cu" "F.Mask" "F.Paste")
			(roundrect_rratio 0.2)
			(net 5 "GND")
			(pintype "passive")
		)
	)
	(footprint "antmicro-footprints:C_0402_1005Metric"
		(layer "F.Cu")
		(at 133.5 94.499 180)
		(descr "Capacitor SMD 0402")
		(tags "capacitor SMD 0402")
		(property "Reference" "C133"
			(at 1.8 -1.301 180)
			(layer "F.SilkS")
			(effects
				(font
					(size 0.7 0.7)
					(thickness 0.15)
				)
				(justify left bottom)
			)
		)
		(property "Value" "C_100n_6V3_0402"
			(at 0 1.4 180)
			(layer "F.Fab")
			(effects
				(font
					(size 0.7 0.7)
					(thickness 0.15)
				)
				(justify left bottom)
			)
		)
		(property "Description" " "
			(at 0 0 180)
			(layer "F.Fab")
			(hide yes)
			(effects
				(font
					(size 1.27 1.27)
					(thickness 0.15)
				)
			)
		)
		(property "Author" "Antmicro"
			(at 267 188.998 0)
			(layer "F.Fab")
			(hide yes)
			(effects
				(font
					(size 1 1)
					(thickness 0.15)
				)
			)
		)
		(property "Dielectric" ""
			(at 267 188.998 0)
			(layer "F.Fab")
			(hide yes)
			(effects
				(font
					(size 1 1)
					(thickness 0.15)
				)
			)
		)
		(property "License" "Apache-2.0"
			(at 267 188.998 0)
			(layer "F.Fab")
			(hide yes)
			(effects
				(font
					(size 1 1)
					(thickness 0.15)
				)
			)
		)
		(property "MPN" "0402X104K6R3CT"
			(at 267 188.998 0)
			(layer "F.Fab")
			(hide yes)
			(effects
				(font
					(size 1 1)
					(thickness 0.15)
				)
			)
		)
		(property "Manufacturer" "Walsin"
			(at 267 188.998 0)
			(layer "F.Fab")
			(hide yes)
			(effects
				(font
					(size 1 1)
					(thickness 0.15)
				)
			)
		)
		(property "Val" "100n"
			(at 267 188.998 0)
			(layer "F.Fab")
			(hide yes)
			(effects
				(font
					(size 1 1)
					(thickness 0.15)
				)
			)
		)
		(property "Voltage" ""
			(at 267 188.998 0)
			(layer "F.Fab")
			(hide yes)
			(effects
				(font
					(size 1 1)
					(thickness 0.15)
				)
			)
		)
		(sheetname "Supply")
		(sheetfile "supply.kicad_sch")
		(attr smd)
		(fp_rect
			(start -0.94 -0.47)
			(end 0.94 0.47)
			(stroke
				(width 0.05)
				(type solid)
			)
			(fill no)
			(layer "F.CrtYd")
		)
		(fp_rect
			(start -0.499 -0.249)
			(end 0.499 0.249)
			(stroke
				(width 0.15)
				(type solid)
			)
			(fill no)
			(layer "F.Fab")
		)
		(pad "1" smd roundrect
			(at -0.484 0 180)
			(size 0.59 0.64)
			(layers "F.Cu" "F.Mask" "F.Paste")
			(roundrect_rratio 0.25)
			(net 463 "VCC5V0_INT")
			(pintype "passive")
		)
		(pad "2" smd roundrect
			(at 0.484 0 180)
			(size 0.59 0.64)
			(layers "F.Cu" "F.Mask" "F.Paste")
			(roundrect_rratio 0.25)
			(net 5 "GND")
			(pintype "passive")
		)
	)
	(footprint "antmicro-footprints:R_0402_1005Metric"
		(layer "F.Cu")
		(at 136.5 98.249)
		(descr "Resistor SMD 0402")
		(tags "resistor SMD 0402")
		(property "Reference" "R106"
			(at -1.4 1.351 0)
			(layer "F.SilkS")
			(effects
				(font
					(size 0.7 0.7)
					(thickness 0.15)
				)
				(justify left bottom)
			)
		)
		(property "Value" "R_0R_0402"
			(at 0 1.4 0)
			(layer "F.Fab")
			(effects
				(font
					(size 0.7 0.7)
					(thickness 0.15)
				)
				(justify left bottom)
			)
		)
		(property "Description" "0R resistor in 0402 package with unspecified tolerance"
			(at 0 0 0)
			(layer "F.Fab")
			(hide yes)
			(effects
				(font
					(size 1.27 1.27)
					(thickness 0.15)
				)
			)
		)
		(property "Author" "Antmicro"
			(at 0 0 0)
			(layer "F.Fab")
			(hide yes)
			(effects
				(font
					(size 1 1)
					(thickness 0.15)
				)
			)
		)
		(property "Current" "1A"
			(at 0 0 0)
			(layer "F.Fab")
			(hide yes)
			(effects
				(font
					(size 1 1)
					(thickness 0.15)
				)
			)
		)
		(property "License" "Apache-2.0"
			(at 0 0 0)
			(layer "F.Fab")
			(hide yes)
			(effects
				(font
					(size 1 1)
					(thickness 0.15)
				)
			)
		)
		(property "MPN" "ERJ2GE0R00X"
			(at 0 0 0)
			(layer "F.Fab")
			(hide yes)
			(effects
				(font
					(size 1 1)
					(thickness 0.15)
				)
			)
		)
		(property "Manufacturer" "Panasonic"
			(at 0 0 0)
			(layer "F.Fab")
			(hide yes)
			(effects
				(font
					(size 1 1)
					(thickness 0.15)
				)
			)
		)
		(property "Tolerance" ""
			(at 0 0 0)
			(layer "F.Fab")
			(hide yes)
			(effects
				(font
					(size 1 1)
					(thickness 0.15)
				)
			)
		)
		(property "Val" "0R"
			(at 0 0 0)
			(layer "F.Fab")
			(hide yes)
			(effects
				(font
					(size 1 1)
					(thickness 0.15)
				)
			)
		)
		(sheetname "Supply")
		(sheetfile "supply.kicad_sch")
		(attr smd)
		(fp_rect
			(start -0.93 -0.47)
			(end 0.93 0.47)
			(stroke
				(width 0.05)
				(type solid)
			)
			(fill no)
			(layer "F.CrtYd")
		)
		(fp_rect
			(start -0.5 -0.25)
			(end 0.5 0.25)
			(stroke
				(width 0.15)
				(type solid)
			)
			(fill no)
			(layer "F.Fab")
		)
		(pad "1" smd roundrect
			(at -0.485 0)
			(size 0.59 0.64)
			(layers "F.Cu" "F.Mask" "F.Paste")
			(roundrect_rratio 0.25)
			(net 262 "Net-(U7-INV)")
			(pintype "passive")
		)
		(pad "2" smd roundrect
			(at 0.485 0)
			(size 0.59 0.64)
			(layers "F.Cu" "F.Mask" "F.Paste")
			(roundrect_rratio 0.25)
			(net 5 "GND")
			(pintype "passive")
		)
	)
	(footprint "antmicro-footprints:TP_SMD_1mm"
		(layer "F.Cu")
		(at 142.625 93.7998)
		(property "Reference" "TP10"
			(at 0.475 0.4002 0)
			(layer "F.SilkS")
			(effects
				(font
					(size 0.7 0.7)
					(thickness 0.15)
				)
				(justify left bottom)
			)
		)
		(property "Value" "TP_1mm_SMD"
			(at 0 1.4 0)
			(layer "F.Fab")
			(effects
				(font
					(size 0.7 0.7)
					(thickness 0.15)
				)
				(justify left bottom)
			)
		)
		(property "Description" "Test Point 1mm"
			(at 0 0 0)
			(layer "F.Fab")
			(hide yes)
			(effects
				(font
					(size 1.27 1.27)
					(thickness 0.15)
				)
			)
		)
		(property "Author" "Antmicro"
			(at 0 0 0)
			(layer "F.Fab")
			(hide yes)
			(effects
				(font
					(size 1 1)
					(thickness 0.15)
				)
			)
		)
		(property "License" "Apache-2.0"
			(at 0 0 0)
			(layer "F.Fab")
			(hide yes)
			(effects
				(font
					(size 1 1)
					(thickness 0.15)
				)
			)
		)
		(property "MPN" ""
			(at 0 0 0)
			(layer "F.Fab")
			(hide yes)
			(effects
				(font
					(size 1 1)
					(thickness 0.15)
				)
			)
		)
		(property "Manufacturer" ""
			(at 0 0 0)
			(layer "F.Fab")
			(hide yes)
			(effects
				(font
					(size 1 1)
					(thickness 0.15)
				)
			)
		)
		(sheetname "Supply")
		(sheetfile "supply.kicad_sch")
		(attr exclude_from_pos_files)
		(pad "1" smd circle
			(at 0 0)
			(size 1 1)
			(layers "F.Cu" "F.Mask")
			(net 468 "/Supply/VCC_INT_EN")
			(pinfunction "1")
			(pintype "passive")
		)
	)
	(footprint "antmicro-footprints:TP_SMD_1mm"
		(layer "F.Cu")
		(at 142.625 95.249)
		(property "Reference" "TP11"
			(at 0.375 0.351 0)
			(layer "F.SilkS")
			(effects
				(font
					(size 0.7 0.7)
					(thickness 0.15)
				)
				(justify left bottom)
			)
		)
		(property "Value" "TP_1mm_SMD"
			(at 0 1.4 0)
			(layer "F.Fab")
			(effects
				(font
					(size 0.7 0.7)
					(thickness 0.15)
				)
				(justify left bottom)
			)
		)
		(property "Description" "Test Point 1mm"
			(at 0 0 0)
			(layer "F.Fab")
			(hide yes)
			(effects
				(font
					(size 1.27 1.27)
					(thickness 0.15)
				)
			)
		)
		(property "Author" "Antmicro"
			(at 0 0 0)
			(layer "F.Fab")
			(hide yes)
			(effects
				(font
					(size 1 1)
					(thickness 0.15)
				)
			)
		)
		(property "License" "Apache-2.0"
			(at 0 0 0)
			(layer "F.Fab")
			(hide yes)
			(effects
				(font
					(size 1 1)
					(thickness 0.15)
				)
			)
		)
		(property "MPN" ""
			(at 0 0 0)
			(layer "F.Fab")
			(hide yes)
			(effects
				(font
					(size 1 1)
					(thickness 0.15)
				)
			)
		)
		(property "Manufacturer" ""
			(at 0 0 0)
			(layer "F.Fab")
			(hide yes)
			(effects
				(font
					(size 1 1)
					(thickness 0.15)
				)
			)
		)
		(sheetname "Supply")
		(sheetfile "supply.kicad_sch")
		(attr exclude_from_pos_files)
		(pad "1" smd circle
			(at 0 0)
			(size 1 1)
			(layers "F.Cu" "F.Mask")
			(net 469 "/Supply/VCC_AUX_EN")
			(pinfunction "1")
			(pintype "passive")
		)
	)
	(footprint "antmicro-footprints:VSSOP-8_3x3mm_P0.65mm"
		(layer "F.Cu")
		(at 138.125 95.499)
		(property "Reference" "U7"
			(at 0 -2 0)
			(layer "F.SilkS")
			(effects
				(font
					(size 0.7 0.7)
					(thickness 0.15)
				)
				(justify left bottom)
			)
		)
		(property "Value" "LM3881MME_NOPB"
			(at 0 2.9 0)
			(layer "F.Fab")
			(effects
				(font
					(size 0.7 0.7)
					(thickness 0.15)
				)
				(justify left bottom)
			)
		)
		(property "Description" "Power Sequencer, 3-Monitors, 2.7V-5.5Vin,VSSOP-8"
			(at 0 0 0)
			(layer "F.Fab")
			(hide yes)
			(effects
				(font
					(size 1.27 1.27)
					(thickness 0.15)
				)
			)
		)
		(property "Author" "Antmicro"
			(at 0 0 0)
			(layer "F.Fab")
			(hide yes)
			(effects
				(font
					(size 1 1)
					(thickness 0.15)
				)
			)
		)
		(property "License" "Apache-2.0"
			(at 0 0 0)
			(layer "F.Fab")
			(hide yes)
			(effects
				(font
					(size 1 1)
					(thickness 0.15)
				)
			)
		)
		(property "MPN" "LM3881MME/NOPB"
			(at 0 0 0)
			(layer "F.Fab")
			(hide yes)
			(effects
				(font
					(size 1 1)
					(thickness 0.15)
				)
			)
		)
		(property "Manufacturer" "Texas Instruments"
			(at 0 0 0)
			(layer "F.Fab")
			(hide yes)
			(effects
				(font
					(size 1 1)
					(thickness 0.15)
				)
			)
		)
		(sheetname "Supply")
		(sheetfile "supply.kicad_sch")
		(attr smd)
		(fp_line
			(start -1.6 -1.625)
			(end 1.554 -1.625)
			(stroke
				(width 0.12)
				(type solid)
			)
			(layer "F.SilkS")
		)
		(fp_line
			(start -1.496 1.625)
			(end 1.554 1.625)
			(stroke
				(width 0.12)
				(type solid)
			)
			(layer "F.SilkS")
		)
		(fp_circle
			(center -2.1 -1.438)
			(end -2.05 -1.438)
			(stroke
				(width 0.12)
				(type solid)
			)
			(fill yes)
			(layer "F.SilkS")
		)
		(fp_rect
			(start -3 -1.838)
			(end 3 1.862)
			(stroke
				(width 0.05)
				(type solid)
			)
			(fill no)
			(layer "F.CrtYd")
		)
		(fp_line
			(start -1.497 -1.502)
			(end 1.504 -1.502)
			(stroke
				(width 0.15)
				(type solid)
			)
			(layer "F.Fab")
		)
		(fp_line
			(start -1.497 1.5)
			(end -1.497 -1.502)
			(stroke
				(width 0.15)
				(type solid)
			)
			(layer "F.Fab")
		)
		(fp_line
			(start 1.504 -1.502)
			(end 1.504 1.5)
			(stroke
				(width 0.15)
				(type solid)
			)
			(layer "F.Fab")
		)
		(fp_line
			(start 1.504 1.5)
			(end -1.497 1.5)
			(stroke
				(width 0.15)
				(type solid)
			)
			(layer "F.Fab")
		)
		(pad "1" smd rect
			(at -2.096 -0.975)
			(size 1.556504 0.457986)
			(layers "F.Cu" "F.Mask" "F.Paste")
			(net 463 "VCC5V0_INT")
			(pinfunction "VCC")
			(pintype "power_in")
		)
		(pad "2" smd roundrect
			(at -2.096 -0.326)
			(size 1.556504 0.457986)
			(layers "F.Cu" "F.Mask" "F.Paste")
			(roundrect_rratio 0.5)
			(net 466 "SYS_ON")
			(pinfunction "EN")
			(pintype "passive")
		)
		(pad "3" smd roundrect
			(at -2.096 0.325)
			(size 1.556504 0.457986)
			(layers "F.Cu" "F.Mask" "F.Paste")
			(roundrect_rratio 0.5)
			(net 5 "GND")
			(pinfunction "GND")
			(pintype "power_in")
		)
		(pad "4" smd roundrect
			(at -2.096 0.974)
			(size 1.556504 0.457986)
			(layers "F.Cu" "F.Mask" "F.Paste")
			(roundrect_rratio 0.5)
			(net 262 "Net-(U7-INV)")
			(pinfunction "INV")
			(pintype "input")
		)
		(pad "5" smd roundrect
			(at 2.105 0.974)
			(size 1.556504 0.457986)
			(layers "F.Cu" "F.Mask" "F.Paste")
			(roundrect_rratio 0.5)
			(net 58 "Net-(U7-TADJ)")
			(pinfunction "TADJ")
			(pintype "passive")
		)
		(pad "6" smd roundrect
			(at 2.105 0.325)
			(size 1.556504 0.457986)
			(layers "F.Cu" "F.Mask" "F.Paste")
			(roundrect_rratio 0.5)
			(net 470 "/Supply/VCC_IO_EN")
			(pinfunction "FLAG3")
			(pintype "open_collector")
		)
		(pad "7" smd roundrect
			(at 2.105 -0.326)
			(size 1.556504 0.457986)
			(layers "F.Cu" "F.Mask" "F.Paste")
			(roundrect_rratio 0.5)
			(net 469 "/Supply/VCC_AUX_EN")
			(pinfunction "FLAG2")
			(pintype "open_collector")
		)
		(pad "8" smd roundrect
			(at 2.105 -0.975)
			(size 1.556504 0.457986)
			(layers "F.Cu" "F.Mask" "F.Paste")
			(roundrect_rratio 0.5)
			(net 468 "/Supply/VCC_INT_EN")
			(pinfunction "FLAG1")
			(pintype "open_collector")
		)
	)
	(footprint "antmicro-footprints:C_0603_1608Metric"
		(layer "F.Cu")
		(at 175.026 132.368 -90)
		(descr "Capacitor SMD 0603")
		(tags "capacitor 0603")
		(property "Reference" "C21"
			(at -0.968 -0.374 270)
			(layer "F.SilkS")
			(effects
				(font
					(size 0.7 0.7)
					(thickness 0.15)
				)
				(justify left bottom)
			)
		)
		(property "Value" "C_1u_0603"
			(at 0 1.6 270)
			(layer "F.Fab")
			(effects
				(font
					(size 0.7 0.7)
					(thickness 0.15)
				)
				(justify left bottom)
			)
		)
		(property "Description" " "
			(at 0 0 270)
			(layer "F.Fab")
			(hide yes)
			(effects
				(font
					(size 1.27 1.27)
					(thickness 0.15)
				)
			)
		)
		(property "Author" "Antmicro"
			(at 42.658 307.394 0)
			(layer "F.Fab")
			(hide yes)
			(effects
				(font
					(size 1 1)
					(thickness 0.15)
				)
			)
		)
		(property "Dielectric" ""
			(at 42.658 307.394 0)
			(layer "F.Fab")
			(hide yes)
			(effects
				(font
					(size 1 1)
					(thickness 0.15)
				)
			)
		)
		(property "License" "Apache-2.0"
			(at 42.658 307.394 0)
			(layer "F.Fab")
			(hide yes)
			(effects
				(font
					(size 1 1)
					(thickness 0.15)
				)
			)
		)
		(property "MPN" "0603YD105KAT2A"
			(at 42.658 307.394 0)
			(layer "F.Fab")
			(hide yes)
			(effects
				(font
					(size 1 1)
					(thickness 0.15)
				)
			)
		)
		(property "Manufacturer" "Walsin"
			(at 42.658 307.394 0)
			(layer "F.Fab")
			(hide yes)
			(effects
				(font
					(size 1 1)
					(thickness 0.15)
				)
			)
		)
		(property "Val" "1u"
			(at 42.658 307.394 0)
			(layer "F.Fab")
			(hide yes)
			(effects
				(font
					(size 1 1)
					(thickness 0.15)
				)
			)
		)
		(property "Voltage" ""
			(at 42.658 307.394 0)
			(layer "F.Fab")
			(hide yes)
			(effects
				(font
					(size 1 1)
					(thickness 0.15)
				)
			)
		)
		(sheetname "Interfaces")
		(sheetfile "interfaces.kicad_sch")
		(attr smd)
		(fp_line
			(start -0.3 0.3)
			(end 0.3 0.3)
			(stroke
				(width 0.15)
				(type solid)
			)
			(layer "F.SilkS")
		)
		(fp_line
			(start -0.3 -0.3)
			(end 0.3 -0.3)
			(stroke
				(width 0.15)
				(type solid)
			)
			(layer "F.SilkS")
		)
		(fp_rect
			(start -1.24 -0.7)
			(end 1.24 0.7)
			(stroke
				(width 0.05)
				(type solid)
			)
			(fill no)
			(layer "F.CrtYd")
		)
		(fp_rect
			(start -0.8 -0.4)
			(end 0.8 0.4)
			(stroke
				(width 0.15)
				(type solid)
			)
			(fill no)
			(layer "F.Fab")
		)
		(pad "1" smd roundrect
			(at -0.7 0 270)
			(size 0.6 0.8)
			(layers "F.Cu" "F.Mask" "F.Paste")
			(roundrect_rratio 0.2)
			(net 5 "GND")
			(pintype "passive")
		)
		(pad "2" smd roundrect
			(at 0.7 0 270)
			(size 0.6 0.8)
			(layers "F.Cu" "F.Mask" "F.Paste")
			(roundrect_rratio 0.2)
			(net 459 "3V3_SYS")
			(pintype "passive")
		)
	)
	(footprint "antmicro-footprints:PinHeader_2x7_P2mm_Drill0.9mm_878311420"
		(layer "F.Cu")
		(at 214.160328 75.797157 90)
		(descr "2.00mm Pitch, Milli-Grid PCB Header, Dual Row, Vertical, Through Hole, Shrouded, 14 Circuits, 0.38µm Gold (Au) Plating, with Center Polarization Slot, with Locking Window, without PCB Locator, Tube")
		(tags "PINSTRIP, HEADER ")
		(property "Reference" "J4"
			(at 0 -4.6 90)
			(layer "F.SilkS")
			(effects
				(font
					(size 0.7 0.7)
					(thickness 0.15)
				)
				(justify left bottom)
			)
		)
		(property "Value" "PinHeader_2x7_P2mm_Drill0.9mm_878311420"
			(at 0 3.4 90)
			(layer "F.Fab")
			(effects
				(font
					(size 0.7 0.7)
					(thickness 0.15)
				)
				(justify left bottom)
			)
		)
		(property "Author" "Antmicro"
			(at 138.363171 289.957485 0)
			(layer "F.Fab")
			(hide yes)
			(effects
				(font
					(size 1 1)
					(thickness 0.15)
				)
			)
		)
		(property "License" "Apache-2.0"
			(at 138.363171 289.957485 0)
			(layer "F.Fab")
			(hide yes)
			(effects
				(font
					(size 1 1)
					(thickness 0.15)
				)
			)
		)
		(property "MPN" "0878311420"
			(at 138.363171 289.957485 0)
			(layer "F.Fab")
			(hide yes)
			(effects
				(font
					(size 1 1)
					(thickness 0.15)
				)
			)
		)
		(property "Manufacturer" "Molex"
			(at 138.363171 289.957485 0)
			(layer "F.Fab")
			(hide yes)
			(effects
				(font
					(size 1 1)
					(thickness 0.15)
				)
			)
		)
		(sheetname "Config SPI flash")
		(sheetfile "config-spi.kicad_sch")
		(attr through_hole)
		(fp_line
			(start 14.4 -4.2)
			(end 14.4 2.2)
			(stroke
				(width 0.15)
				(type solid)
			)
			(layer "F.SilkS")
		)
		(fp_line
			(start -2.4 -4.2)
			(end 14.4 -4.2)
			(stroke
				(width 0.15)
				(type solid)
			)
			(layer "F.SilkS")
		)
		(fp_line
			(start 14.4 2.2)
			(end 7.3 2.2)
			(stroke
				(width 0.15)
				(type solid)
			)
			(layer "F.SilkS")
		)
		(fp_line
			(start -2.4 2.2)
			(end -2.4 -4.2)
			(stroke
				(width 0.15)
				(type solid)
			)
			(layer "F.SilkS")
		)
		(fp_line
			(start -2.41 2.2)
			(end 4.7 2.2)
			(stroke
				(width 0.15)
				(type solid)
			)
			(layer "F.SilkS")
		)
		(fp_line
			(start -2.51 -4.34)
			(end 14.51 -4.34)
			(stroke
				(width 0.05)
				(type solid)
			)
			(layer "F.CrtYd")
		)
		(fp_line
			(start 14.51 2.34)
			(end 14.51 -4.34)
			(stroke
				(width 0.05)
				(type solid)
			)
			(layer "F.CrtYd")
		)
		(fp_line
			(start -2.51 2.34)
			(end -2.51 -4.34)
			(stroke
				(width 0.05)
				(type solid)
			)
			(layer "F.CrtYd")
		)
		(fp_line
			(start -2.51 2.34)
			(end 14.51 2.34)
			(stroke
				(width 0.05)
				(type solid)
			)
			(layer "F.CrtYd")
		)
		(fp_line
			(start 14.356 -4.15)
			(end -2.32 -4.15)
			(stroke
				(width 0.15)
				(type solid)
			)
			(layer "F.Fab")
		)
		(fp_line
			(start 14.356 1.898)
			(end 14.356 -4.15)
			(stroke
				(width 0.15)
				(type solid)
			)
			(layer "F.Fab")
		)
		(fp_line
			(start 14.356 2.15)
			(end -2.293 2.15)
			(stroke
				(width 0.15)
				(type solid)
			)
			(layer "F.Fab")
		)
		(fp_line
			(start -2.33 2.15)
			(end -2.33 -4.13)
			(stroke
				(width 0.15)
				(type solid)
			)
			(layer "F.Fab")
		)
		(fp_text user "Author: Antmicro"
			(at -14.7 9.2 90)
			(layer "F.Fab")
			(effects
				(font
					(size 0.7 0.7)
					(thickness 0.15)
				)
				(justify left bottom)
			)
		)
		(fp_text user "${REFERENCE}"
			(at -14.7 6.7 90)
			(layer "F.Fab")
			(effects
				(font
					(size 0.7 0.7)
					(thickness 0.15)
				)
				(justify left bottom)
			)
		)
		(fp_text user "License: Apache-2.0"
			(at -14.7 7.9 90)
			(layer "F.Fab")
			(effects
				(font
					(size 0.7 0.7)
					(thickness 0.15)
				)
				(justify left bottom)
			)
		)
		(pad "1" thru_hole rect
			(at 0 0 270)
			(size 1.6 1.6)
			(drill 0.9)
			(layers "*.Cu" "*.Mask")
			(remove_unused_layers no)
			(net 5 "GND")
			(pintype "passive")
		)
		(pad "2" thru_hole circle
			(at 0 -2 270)
			(size 1.6 1.6)
			(drill 0.9)
			(layers "*.Cu" "*.Mask")
			(remove_unused_layers no)
			(net 459 "3V3_SYS")
			(pintype "passive")
		)
		(pad "3" thru_hole circle
			(at 2 0 270)
			(size 1.6 1.6)
			(drill 0.9)
			(layers "*.Cu" "*.Mask")
			(remove_unused_layers no)
			(net 5 "GND")
			(pintype "passive")
		)
		(pad "4" thru_hole circle
			(at 2 -2 270)
			(size 1.6 1.6)
			(drill 0.9)
			(layers "*.Cu" "*.Mask")
			(remove_unused_layers no)
			(net 9 "TMS_JTAG")
			(pintype "passive")
		)
		(pad "5" thru_hole circle
			(at 4 0 270)
			(size 1.6 1.6)
			(drill 0.9)
			(layers "*.Cu" "*.Mask")
			(remove_unused_layers no)
			(net 5 "GND")
			(pintype "passive")
		)
		(pad "6" thru_hole circle
			(at 4 -2 270)
			(size 1.6 1.6)
			(drill 0.9)
			(layers "*.Cu" "*.Mask")
			(remove_unused_layers no)
			(net 8 "TCK_JTAG")
			(pintype "passive")
		)
		(pad "7" thru_hole circle
			(at 6 0 270)
			(size 1.6 1.6)
			(drill 0.9)
			(layers "*.Cu" "*.Mask")
			(remove_unused_layers no)
			(net 5 "GND")
			(pintype "passive")
		)
		(pad "8" thru_hole circle
			(at 6 -2 270)
			(size 1.6 1.6)
			(drill 0.9)
			(layers "*.Cu" "*.Mask")
			(remove_unused_layers no)
			(net 11 "TDO_JTAG")
			(pintype "passive")
		)
		(pad "9" thru_hole circle
			(at 8 0 270)
			(size 1.6 1.6)
			(drill 0.9)
			(layers "*.Cu" "*.Mask")
			(remove_unused_layers no)
			(net 5 "GND")
			(pintype "passive")
		)
		(pad "10" thru_hole circle
			(at 8 -2 270)
			(size 1.6 1.6)
			(drill 0.9)
			(layers "*.Cu" "*.Mask")
			(remove_unused_layers no)
			(net 10 "TDI_JTAG")
			(pintype "passive")
		)
		(pad "11" thru_hole circle
			(at 10 0 270)
			(size 1.6 1.6)
			(drill 0.9)
			(layers "*.Cu" "*.Mask")
			(remove_unused_layers no)
			(net 5 "GND")
			(pintype "passive")
		)
		(pad "12" thru_hole circle
			(at 10 -2 270)
			(size 1.6 1.6)
			(drill 0.9)
			(layers "*.Cu" "*.Mask")
			(remove_unused_layers no)
			(net 86 "unconnected-(J4-Pad12)")
			(pintype "passive+no_connect")
		)
		(pad "13" thru_hole circle
			(at 12 0 270)
			(size 1.6 1.6)
			(drill 0.9)
			(layers "*.Cu" "*.Mask")
			(remove_unused_layers no)
			(net 5 "GND")
			(pintype "passive")
		)
		(pad "14" thru_hole circle
			(at 12 -2 270)
			(size 1.6 1.6)
			(drill 0.9)
			(layers "*.Cu" "*.Mask")
			(remove_unused_layers no)
			(net 87 "unconnected-(J4-Pad14)")
			(pintype "passive+no_connect")
		)
	)
	(footprint "antmicro-footprints:C_0402_1005Metric"
		(layer "F.Cu")
		(at 180.995 112.429 -90)
		(descr "Capacitor SMD 0402")
		(tags "capacitor SMD 0402")
		(property "Reference" "C5"
			(at -0.829 -0.405 270)
			(layer "F.SilkS")
			(effects
				(font
					(size 0.7 0.7)
					(thickness 0.15)
				)
				(justify left bottom)
			)
		)
		(property "Value" "C_100n_6V3_0402"
			(at 0 1.4 270)
			(layer "F.Fab")
			(effects
				(font
					(size 0.7 0.7)
					(thickness 0.15)
				)
				(justify left bottom)
			)
		)
		(property "Description" " "
			(at 0 0 270)
			(layer "F.Fab")
			(hide yes)
			(effects
				(font
					(size 1.27 1.27)
					(thickness 0.15)
				)
			)
		)
		(property "Author" "Antmicro"
			(at 68.566 293.424 0)
			(layer "F.Fab")
			(hide yes)
			(effects
				(font
					(size 1 1)
					(thickness 0.15)
				)
			)
		)
		(property "Dielectric" ""
			(at 68.566 293.424 0)
			(layer "F.Fab")
			(hide yes)
			(effects
				(font
					(size 1 1)
					(thickness 0.15)
				)
			)
		)
		(property "License" "Apache-2.0"
			(at 68.566 293.424 0)
			(layer "F.Fab")
			(hide yes)
			(effects
				(font
					(size 1 1)
					(thickness 0.15)
				)
			)
		)
		(property "MPN" "0402X104K6R3CT"
			(at 68.566 293.424 0)
			(layer "F.Fab")
			(hide yes)
			(effects
				(font
					(size 1 1)
					(thickness 0.15)
				)
			)
		)
		(property "Manufacturer" "Walsin"
			(at 68.566 293.424 0)
			(layer "F.Fab")
			(hide yes)
			(effects
				(font
					(size 1 1)
					(thickness 0.15)
				)
			)
		)
		(property "Val" "100n"
			(at 68.566 293.424 0)
			(layer "F.Fab")
			(hide yes)
			(effects
				(font
					(size 1 1)
					(thickness 0.15)
				)
			)
		)
		(property "Voltage" ""
			(at 68.566 293.424 0)
			(layer "F.Fab")
			(hide yes)
			(effects
				(font
					(size 1 1)
					(thickness 0.15)
				)
			)
		)
		(sheetname "FPGA Banks")
		(sheetfile "fpga-banks.kicad_sch")
		(attr smd)
		(fp_rect
			(start -0.94 -0.47)
			(end 0.94 0.47)
			(stroke
				(width 0.05)
				(type solid)
			)
			(fill no)
			(layer "F.CrtYd")
		)
		(fp_rect
			(start -0.499 -0.249)
			(end 0.499 0.249)
			(stroke
				(width 0.15)
				(type solid)
			)
			(fill no)
			(layer "F.Fab")
		)
		(pad "1" smd roundrect
			(at -0.484 0 270)
			(size 0.59 0.64)
			(layers "F.Cu" "F.Mask" "F.Paste")
			(roundrect_rratio 0.25)
			(net 5 "GND")
			(pintype "passive")
		)
		(pad "2" smd roundrect
			(at 0.484 0 270)
			(size 0.59 0.64)
			(layers "F.Cu" "F.Mask" "F.Paste")
			(roundrect_rratio 0.25)
			(net 459 "3V3_SYS")
			(pintype "passive")
		)
	)
	(footprint "antmicro-footprints:R_0402_1005Metric"
		(layer "F.Cu")
		(at 197.486328 86.720008 90)
		(descr "Resistor SMD 0402")
		(tags "resistor SMD 0402")
		(property "Reference" "R66"
			(at -1.279992 -0.486328 90)
			(layer "F.SilkS")
			(effects
				(font
					(size 0.7 0.7)
					(thickness 0.15)
				)
				(justify left bottom)
			)
		)
		(property "Value" "R_4k7_0402"
			(at 0 1.4 90)
			(layer "F.Fab")
			(effects
				(font
					(size 0.7 0.7)
					(thickness 0.15)
				)
				(justify left bottom)
			)
		)
		(property "Description" "4k7 resistor in 0402 package with 1% tolerance"
			(at 0 0 90)
			(layer "F.Fab")
			(hide yes)
			(effects
				(font
					(size 1.27 1.27)
					(thickness 0.15)
				)
			)
		)
		(property "Author" "Antmicro"
			(at 284.206336 -110.76632 0)
			(layer "F.Fab")
			(hide yes)
			(effects
				(font
					(size 1 1)
					(thickness 0.15)
				)
			)
		)
		(property "License" "Apache-2.0"
			(at 284.206336 -110.76632 0)
			(layer "F.Fab")
			(hide yes)
			(effects
				(font
					(size 1 1)
					(thickness 0.15)
				)
			)
		)
		(property "MPN" "CR0402-FX-4701GLF"
			(at 284.206336 -110.76632 0)
			(layer "F.Fab")
			(hide yes)
			(effects
				(font
					(size 1 1)
					(thickness 0.15)
				)
			)
		)
		(property "Manufacturer" "Bourns"
			(at 284.206336 -110.76632 0)
			(layer "F.Fab")
			(hide yes)
			(effects
				(font
					(size 1 1)
					(thickness 0.15)
				)
			)
		)
		(property "Tolerance" "1%"
			(at 284.206336 -110.76632 0)
			(layer "F.Fab")
			(hide yes)
			(effects
				(font
					(size 1 1)
					(thickness 0.15)
				)
			)
		)
		(property "Val" "4k7"
			(at 284.206336 -110.76632 0)
			(layer "F.Fab")
			(hide yes)
			(effects
				(font
					(size 1 1)
					(thickness 0.15)
				)
			)
		)
		(sheetname "Config SPI flash")
		(sheetfile "config-spi.kicad_sch")
		(attr smd)
		(fp_rect
			(start -0.93 -0.47)
			(end 0.93 0.47)
			(stroke
				(width 0.05)
				(type solid)
			)
			(fill no)
			(layer "F.CrtYd")
		)
		(fp_rect
			(start -0.5 -0.25)
			(end 0.5 0.25)
			(stroke
				(width 0.15)
				(type solid)
			)
			(fill no)
			(layer "F.Fab")
		)
		(pad "1" smd roundrect
			(at -0.485 0 90)
			(size 0.59 0.64)
			(layers "F.Cu" "F.Mask" "F.Paste")
			(roundrect_rratio 0.25)
			(net 459 "3V3_SYS")
			(pintype "passive")
		)
		(pad "2" smd roundrect
			(at 0.485 0 90)
			(size 0.59 0.64)
			(layers "F.Cu" "F.Mask" "F.Paste")
			(roundrect_rratio 0.25)
			(net 210 "INIT_B")
			(pintype "passive")
		)
	)
	(footprint "antmicro-footprints:R_0402_1005Metric"
		(layer "F.Cu")
		(at 177.693 124.113 -90)
		(descr "Resistor SMD 0402")
		(tags "resistor SMD 0402")
		(property "Reference" "R31"
			(at -0.713 -0.407 270)
			(layer "F.SilkS")
			(effects
				(font
					(size 0.7 0.7)
					(thickness 0.15)
				)
				(justify left bottom)
			)
		)
		(property "Value" "R_20k_0402"
			(at 0 1.4 270)
			(layer "F.Fab")
			(effects
				(font
					(size 0.7 0.7)
					(thickness 0.15)
				)
				(justify left bottom)
			)
		)
		(property "Description" "20k resistor in 0402 package with 1% tolerance"
			(at 0 0 270)
			(layer "F.Fab")
			(hide yes)
			(effects
				(font
					(size 1.27 1.27)
					(thickness 0.15)
				)
			)
		)
		(property "Author" "Antmicro"
			(at 53.58 301.806 0)
			(layer "F.Fab")
			(hide yes)
			(effects
				(font
					(size 1 1)
					(thickness 0.15)
				)
			)
		)
		(property "License" "Apache-2.0"
			(at 53.58 301.806 0)
			(layer "F.Fab")
			(hide yes)
			(effects
				(font
					(size 1 1)
					(thickness 0.15)
				)
			)
		)
		(property "MPN" "CR0402-FX-2002GLF"
			(at 53.58 301.806 0)
			(layer "F.Fab")
			(hide yes)
			(effects
				(font
					(size 1 1)
					(thickness 0.15)
				)
			)
		)
		(property "Manufacturer" "Bourns"
			(at 53.58 301.806 0)
			(layer "F.Fab")
			(hide yes)
			(effects
				(font
					(size 1 1)
					(thickness 0.15)
				)
			)
		)
		(property "Tolerance" "1%"
			(at 53.58 301.806 0)
			(layer "F.Fab")
			(hide yes)
			(effects
				(font
					(size 1 1)
					(thickness 0.15)
				)
			)
		)
		(property "Val" "20k"
			(at 53.58 301.806 0)
			(layer "F.Fab")
			(hide yes)
			(effects
				(font
					(size 1 1)
					(thickness 0.15)
				)
			)
		)
		(sheetname "Interfaces")
		(sheetfile "interfaces.kicad_sch")
		(attr smd)
		(fp_rect
			(start -0.93 -0.47)
			(end 0.93 0.47)
			(stroke
				(width 0.05)
				(type solid)
			)
			(fill no)
			(layer "F.CrtYd")
		)
		(fp_rect
			(start -0.5 -0.25)
			(end 0.5 0.25)
			(stroke
				(width 0.15)
				(type solid)
			)
			(fill no)
			(layer "F.Fab")
		)
		(pad "1" smd roundrect
			(at -0.485 0 270)
			(size 0.59 0.64)
			(layers "F.Cu" "F.Mask" "F.Paste")
			(roundrect_rratio 0.25)
			(net 459 "3V3_SYS")
			(pintype "passive")
		)
		(pad "2" smd roundrect
			(at 0.485 0 270)
			(size 0.59 0.64)
			(layers "F.Cu" "F.Mask" "F.Paste")
			(roundrect_rratio 0.25)
			(net 198 "SD_CD")
			(pintype "passive")
		)
	)
	(footprint "antmicro-footprints:R_0402_1005Metric"
		(layer "F.Cu")
		(at 178.201 130.082 -90)
		(descr "Resistor SMD 0402")
		(tags "resistor SMD 0402")
		(property "Reference" "R33"
			(at -0.782 -0.431 270)
			(layer "F.SilkS")
			(effects
				(font
					(size 0.7 0.7)
					(thickness 0.15)
				)
				(justify left bottom)
			)
		)
		(property "Value" "R_20k_0402"
			(at 0 1.4 270)
			(layer "F.Fab")
			(effects
				(font
					(size 0.7 0.7)
					(thickness 0.15)
				)
				(justify left bottom)
			)
		)
		(property "Description" "20k resistor in 0402 package with 1% tolerance"
			(at 0 0 270)
			(layer "F.Fab")
			(hide yes)
			(effects
				(font
					(size 1.27 1.27)
					(thickness 0.15)
				)
			)
		)
		(property "Author" "Antmicro"
			(at 48.119 308.283 0)
			(layer "F.Fab")
			(hide yes)
			(effects
				(font
					(size 1 1)
					(thickness 0.15)
				)
			)
		)
		(property "License" "Apache-2.0"
			(at 48.119 308.283 0)
			(layer "F.Fab")
			(hide yes)
			(effects
				(font
					(size 1 1)
					(thickness 0.15)
				)
			)
		)
		(property "MPN" "CR0402-FX-2002GLF"
			(at 48.119 308.283 0)
			(layer "F.Fab")
			(hide yes)
			(effects
				(font
					(size 1 1)
					(thickness 0.15)
				)
			)
		)
		(property "Manufacturer" "Bourns"
			(at 48.119 308.283 0)
			(layer "F.Fab")
			(hide yes)
			(effects
				(font
					(size 1 1)
					(thickness 0.15)
				)
			)
		)
		(property "Tolerance" "1%"
			(at 48.119 308.283 0)
			(layer "F.Fab")
			(hide yes)
			(effects
				(font
					(size 1 1)
					(thickness 0.15)
				)
			)
		)
		(property "Val" "20k"
			(at 48.119 308.283 0)
			(layer "F.Fab")
			(hide yes)
			(effects
				(font
					(size 1 1)
					(thickness 0.15)
				)
			)
		)
		(sheetname "Interfaces")
		(sheetfile "interfaces.kicad_sch")
		(attr smd)
		(fp_rect
			(start -0.93 -0.47)
			(end 0.93 0.47)
			(stroke
				(width 0.05)
				(type solid)
			)
			(fill no)
			(layer "F.CrtYd")
		)
		(fp_rect
			(start -0.5 -0.25)
			(end 0.5 0.25)
			(stroke
				(width 0.15)
				(type solid)
			)
			(fill no)
			(layer "F.Fab")
		)
		(pad "1" smd roundrect
			(at -0.485 0 270)
			(size 0.59 0.64)
			(layers "F.Cu" "F.Mask" "F.Paste")
			(roundrect_rratio 0.25)
			(net 459 "3V3_SYS")
			(pintype "passive")
		)
		(pad "2" smd roundrect
			(at 0.485 0 270)
			(size 0.59 0.64)
			(layers "F.Cu" "F.Mask" "F.Paste")
			(roundrect_rratio 0.25)
			(net 193 "SD_DAT0")
			(pintype "passive")
		)
	)
	(footprint "antmicro-footprints:R_0402_1005Metric"
		(layer "F.Cu")
		(at 178.836 124.113 90)
		(descr "Resistor SMD 0402")
		(tags "resistor SMD 0402")
		(property "Reference" "R36"
			(at 0.713 0.364 90)
			(layer "F.SilkS")
			(effects
				(font
					(size 0.7 0.7)
					(thickness 0.15)
				)
				(justify left bottom)
			)
		)
		(property "Value" "R_220R_0402"
			(at 0 1.4 90)
			(layer "F.Fab")
			(effects
				(font
					(size 0.7 0.7)
					(thickness 0.15)
				)
				(justify left bottom)
			)
		)
		(property "Description" "220R resistor in 0402 package with 1% tolerance"
			(at 0 0 90)
			(layer "F.Fab")
			(hide yes)
			(effects
				(font
					(size 1.27 1.27)
					(thickness 0.15)
				)
			)
		)
		(property "Author" "Antmicro"
			(at 302.949 -54.723 0)
			(layer "F.Fab")
			(hide yes)
			(effects
				(font
					(size 1 1)
					(thickness 0.15)
				)
			)
		)
		(property "License" "Apache-2.0"
			(at 302.949 -54.723 0)
			(layer "F.Fab")
			(hide yes)
			(effects
				(font
					(size 1 1)
					(thickness 0.15)
				)
			)
		)
		(property "MPN" "CR0402-FX-2200GLF"
			(at 302.949 -54.723 0)
			(layer "F.Fab")
			(hide yes)
			(effects
				(font
					(size 1 1)
					(thickness 0.15)
				)
			)
		)
		(property "Manufacturer" "Bourns"
			(at 302.949 -54.723 0)
			(layer "F.Fab")
			(hide yes)
			(effects
				(font
					(size 1 1)
					(thickness 0.15)
				)
			)
		)
		(property "Tolerance" "1%"
			(at 302.949 -54.723 0)
			(layer "F.Fab")
			(hide yes)
			(effects
				(font
					(size 1 1)
					(thickness 0.15)
				)
			)
		)
		(property "Val" "220R"
			(at 302.949 -54.723 0)
			(layer "F.Fab")
			(hide yes)
			(effects
				(font
					(size 1 1)
					(thickness 0.15)
				)
			)
		)
		(sheetname "Interfaces")
		(sheetfile "interfaces.kicad_sch")
		(attr smd)
		(fp_rect
			(start -0.93 -0.47)
			(end 0.93 0.47)
			(stroke
				(width 0.05)
				(type solid)
			)
			(fill no)
			(layer "F.CrtYd")
		)
		(fp_rect
			(start -0.5 -0.25)
			(end 0.5 0.25)
			(stroke
				(width 0.15)
				(type solid)
			)
			(fill no)
			(layer "F.Fab")
		)
		(pad "1" smd roundrect
			(at -0.485 0 90)
			(size 0.59 0.64)
			(layers "F.Cu" "F.Mask" "F.Paste")
			(roundrect_rratio 0.25)
			(net 198 "SD_CD")
			(pintype "passive")
		)
		(pad "2" smd roundrect
			(at 0.485 0 90)
			(size 0.59 0.64)
			(layers "F.Cu" "F.Mask" "F.Paste")
			(roundrect_rratio 0.25)
			(net 85 "Net-(J3-CD1)")
			(pintype "passive")
		)
	)
	(footprint "antmicro-footprints:R_0402_1005Metric"
		(layer "F.Cu")
		(at 172.74 130.082 -90)
		(descr "Resistor SMD 0402")
		(tags "resistor SMD 0402")
		(property "Reference" "R37"
			(at -0.782 -0.403 270)
			(layer "F.SilkS")
			(effects
				(font
					(size 0.7 0.7)
					(thickness 0.15)
				)
				(justify left bottom)
			)
		)
		(property "Value" "R_20k_0402"
			(at 0 1.4 270)
			(layer "F.Fab")
			(effects
				(font
					(size 0.7 0.7)
					(thickness 0.15)
				)
				(justify left bottom)
			)
		)
		(property "Description" "20k resistor in 0402 package with 1% tolerance"
			(at 0 0 270)
			(layer "F.Fab")
			(hide yes)
			(effects
				(font
					(size 1.27 1.27)
					(thickness 0.15)
				)
			)
		)
		(property "Author" "Antmicro"
			(at 42.658 302.822 0)
			(layer "F.Fab")
			(hide yes)
			(effects
				(font
					(size 1 1)
					(thickness 0.15)
				)
			)
		)
		(property "License" "Apache-2.0"
			(at 42.658 302.822 0)
			(layer "F.Fab")
			(hide yes)
			(effects
				(font
					(size 1 1)
					(thickness 0.15)
				)
			)
		)
		(property "MPN" "CR0402-FX-2002GLF"
			(at 42.658 302.822 0)
			(layer "F.Fab")
			(hide yes)
			(effects
				(font
					(size 1 1)
					(thickness 0.15)
				)
			)
		)
		(property "Manufacturer" "Bourns"
			(at 42.658 302.822 0)
			(layer "F.Fab")
			(hide yes)
			(effects
				(font
					(size 1 1)
					(thickness 0.15)
				)
			)
		)
		(property "Tolerance" "1%"
			(at 42.658 302.822 0)
			(layer "F.Fab")
			(hide yes)
			(effects
				(font
					(size 1 1)
					(thickness 0.15)
				)
			)
		)
		(property "Val" "20k"
			(at 42.658 302.822 0)
			(layer "F.Fab")
			(hide yes)
			(effects
				(font
					(size 1 1)
					(thickness 0.15)
				)
			)
		)
		(sheetname "Interfaces")
		(sheetfile "interfaces.kicad_sch")
		(attr smd)
		(fp_rect
			(start -0.93 -0.47)
			(end 0.93 0.47)
			(stroke
				(width 0.05)
				(type solid)
			)
			(fill no)
			(layer "F.CrtYd")
		)
		(fp_rect
			(start -0.5 -0.25)
			(end 0.5 0.25)
			(stroke
				(width 0.15)
				(type solid)
			)
			(fill no)
			(layer "F.Fab")
		)
		(pad "1" smd roundrect
			(at -0.485 0 270)
			(size 0.59 0.64)
			(layers "F.Cu" "F.Mask" "F.Paste")
			(roundrect_rratio 0.25)
			(net 459 "3V3_SYS")
			(pintype "passive")
		)
		(pad "2" smd roundrect
			(at 0.485 0 270)
			(size 0.59 0.64)
			(layers "F.Cu" "F.Mask" "F.Paste")
			(roundrect_rratio 0.25)
			(net 196 "SD_DAT3")
			(pintype "passive")
		)
	)
	(footprint "antmicro-footprints:R_0402_1005Metric"
		(layer "F.Cu")
		(at 171.597 130.082 -90)
		(descr "Resistor SMD 0402")
		(tags "resistor SMD 0402")
		(property "Reference" "R38"
			(at -0.782 -0.403 270)
			(layer "F.SilkS")
			(effects
				(font
					(size 0.7 0.7)
					(thickness 0.15)
				)
				(justify left bottom)
			)
		)
		(property "Value" "R_20k_0402"
			(at 0 1.4 270)
			(layer "F.Fab")
			(effects
				(font
					(size 0.7 0.7)
					(thickness 0.15)
				)
				(justify left bottom)
			)
		)
		(property "Description" "20k resistor in 0402 package with 1% tolerance"
			(at 0 0 270)
			(layer "F.Fab")
			(hide yes)
			(effects
				(font
					(size 1.27 1.27)
					(thickness 0.15)
				)
			)
		)
		(property "Author" "Antmicro"
			(at 41.515 301.679 0)
			(layer "F.Fab")
			(hide yes)
			(effects
				(font
					(size 1 1)
					(thickness 0.15)
				)
			)
		)
		(property "License" "Apache-2.0"
			(at 41.515 301.679 0)
			(layer "F.Fab")
			(hide yes)
			(effects
				(font
					(size 1 1)
					(thickness 0.15)
				)
			)
		)
		(property "MPN" "CR0402-FX-2002GLF"
			(at 41.515 301.679 0)
			(layer "F.Fab")
			(hide yes)
			(effects
				(font
					(size 1 1)
					(thickness 0.15)
				)
			)
		)
		(property "Manufacturer" "Bourns"
			(at 41.515 301.679 0)
			(layer "F.Fab")
			(hide yes)
			(effects
				(font
					(size 1 1)
					(thickness 0.15)
				)
			)
		)
		(property "Tolerance" "1%"
			(at 41.515 301.679 0)
			(layer "F.Fab")
			(hide yes)
			(effects
				(font
					(size 1 1)
					(thickness 0.15)
				)
			)
		)
		(property "Val" "20k"
			(at 41.515 301.679 0)
			(layer "F.Fab")
			(hide yes)
			(effects
				(font
					(size 1 1)
					(thickness 0.15)
				)
			)
		)
		(sheetname "Interfaces")
		(sheetfile "interfaces.kicad_sch")
		(attr smd)
		(fp_rect
			(start -0.93 -0.47)
			(end 0.93 0.47)
			(stroke
				(width 0.05)
				(type solid)
			)
			(fill no)
			(layer "F.CrtYd")
		)
		(fp_rect
			(start -0.5 -0.25)
			(end 0.5 0.25)
			(stroke
				(width 0.15)
				(type solid)
			)
			(fill no)
			(layer "F.Fab")
		)
		(pad "1" smd roundrect
			(at -0.485 0 270)
			(size 0.59 0.64)
			(layers "F.Cu" "F.Mask" "F.Paste")
			(roundrect_rratio 0.25)
			(net 459 "3V3_SYS")
			(pintype "passive")
		)
		(pad "2" smd roundrect
			(at 0.485 0 270)
			(size 0.59 0.64)
			(layers "F.Cu" "F.Mask" "F.Paste")
			(roundrect_rratio 0.25)
			(net 197 "SD_DAT2")
			(pintype "passive")
		)
	)
	(footprint "antmicro-footprints:SW_B3U-1000P_SMD"
		(layer "F.Cu")
		(at 213.193336 96.42168 -90)
		(property "Reference" "PROG_B1"
			(at 1.87832 -2.506664 270)
			(layer "F.SilkS")
			(effects
				(font
					(size 0.7 0.7)
					(thickness 0.15)
				)
				(justify left bottom)
			)
		)
		(property "Value" "SW_B3U-1000P"
			(at 0 2.5 270)
			(layer "F.Fab")
			(effects
				(font
					(size 0.7 0.7)
					(thickness 0.15)
				)
				(justify left bottom)
			)
		)
		(property "Description" "Tactile Switch, B3U, Top Actuated, Surface Mount, Round Button, 153 gf, 50mA at 12VDC"
			(at 0 0 270)
			(layer "F.Fab")
			(hide yes)
			(effects
				(font
					(size 1.27 1.27)
					(thickness 0.15)
				)
			)
		)
		(property "Author" "Antmicro"
			(at 116.771656 309.615016 0)
			(layer "F.Fab")
			(hide yes)
			(effects
				(font
					(size 1 1)
					(thickness 0.15)
				)
			)
		)
		(property "License" "Apache-2.0"
			(at 116.771656 309.615016 0)
			(layer "F.Fab")
			(hide yes)
			(effects
				(font
					(size 1 1)
					(thickness 0.15)
				)
			)
		)
		(property "MPN" "B3U-1000P"
			(at 116.771656 309.615016 0)
			(layer "F.Fab")
			(hide yes)
			(effects
				(font
					(size 1 1)
					(thickness 0.15)
				)
			)
		)
		(property "Manufacturer" "Omron"
			(at 116.771656 309.615016 0)
			(layer "F.Fab")
			(hide yes)
			(effects
				(font
					(size 1 1)
					(thickness 0.15)
				)
			)
		)
		(sheetname "Config SPI flash")
		(sheetfile "config-spi.kicad_sch")
		(attr smd)
		(fp_line
			(start -1.6 1.4)
			(end -1.1 1.4)
			(stroke
				(width 0.15)
				(type solid)
			)
			(layer "F.SilkS")
		)
		(fp_line
			(start -1.6 1.4)
			(end -1.6 0.95)
			(stroke
				(width 0.15)
				(type solid)
			)
			(layer "F.SilkS")
		)
		(fp_line
			(start 1.6 1.4)
			(end 1.1 1.4)
			(stroke
				(width 0.15)
				(type solid)
			)
			(layer "F.SilkS")
		)
		(fp_line
			(start 1.6 1.4)
			(end 1.6 0.95)
			(stroke
				(width 0.15)
				(type solid)
			)
			(layer "F.SilkS")
		)
		(fp_line
			(start -1.601 -0.95)
			(end -2 -0.95)
			(stroke
				(width 0.15)
				(type solid)
			)
			(layer "F.SilkS")
		)
		(fp_line
			(start -1.6 -1.4)
			(end -1.601 -0.95)
			(stroke
				(width 0.15)
				(type solid)
			)
			(layer "F.SilkS")
		)
		(fp_line
			(start -1.6 -1.4)
			(end -1.1 -1.4)
			(stroke
				(width 0.15)
				(type solid)
			)
			(layer "F.SilkS")
		)
		(fp_line
			(start 1.6 -1.4)
			(end 1.6 -0.95)
			(stroke
				(width 0.15)
				(type solid)
			)
			(layer "F.SilkS")
		)
		(fp_line
			(start 1.6 -1.4)
			(end 1.1 -1.4)
			(stroke
				(width 0.15)
				(type solid)
			)
			(layer "F.SilkS")
		)
		(fp_rect
			(start -2.249 -1.55)
			(end 2.25 1.549)
			(stroke
				(width 0.05)
				(type solid)
			)
			(fill no)
			(layer "F.CrtYd")
		)
		(fp_rect
			(start -1.5 -1.29)
			(end 1.499 1.289)
			(stroke
				(width 0.15)
				(type solid)
			)
			(fill no)
			(layer "F.Fab")
		)
		(pad "1" smd rect
			(at -1.7 0 270)
			(size 0.8 1.7)
			(layers "F.Cu" "F.Mask" "F.Paste")
			(net 208 "PROGRAM_B")
			(pinfunction "1")
			(pintype "passive")
		)
		(pad "2" smd rect
			(at 1.699 0 270)
			(size 0.8 1.7)
			(layers "F.Cu" "F.Mask" "F.Paste")
			(net 5 "GND")
			(pinfunction "2")
			(pintype "passive")
		)
	)
	(footprint "antmicro-footprints:TP_SMD_1mm"
		(layer "F.Cu")
		(at 151.4832 121.16 90)
		(property "Reference" "TP3"
			(at -2.24 -0.534 90)
			(layer "F.SilkS")
			(effects
				(font
					(size 0.7 0.7)
					(thickness 0.15)
				)
				(justify left bottom)
			)
		)
		(property "Value" "TP_1mm_SMD"
			(at 0 1.4 90)
			(layer "F.Fab")
			(effects
				(font
					(size 0.7 0.7)
					(thickness 0.15)
				)
				(justify left bottom)
			)
		)
		(property "Description" "Test Point 1mm"
			(at 0 0 90)
			(layer "F.Fab")
			(hide yes)
			(effects
				(font
					(size 1.27 1.27)
					(thickness 0.15)
				)
			)
		)
		(property "Author" "Antmicro"
			(at 272.6432 -30.3232 0)
			(layer "F.Fab")
			(hide yes)
			(effects
				(font
					(size 1 1)
					(thickness 0.15)
				)
			)
		)
		(property "License" "Apache-2.0"
			(at 272.6432 -30.3232 0)
			(layer "F.Fab")
			(hide yes)
			(effects
				(font
					(size 1 1)
					(thickness 0.15)
				)
			)
		)
		(property "MPN" ""
			(at 272.6432 -30.3232 0)
			(layer "F.Fab")
			(hide yes)
			(effects
				(font
					(size 1 1)
					(thickness 0.15)
				)
			)
		)
		(property "Manufacturer" ""
			(at 272.6432 -30.3232 0)
			(layer "F.Fab")
			(hide yes)
			(effects
				(font
					(size 1 1)
					(thickness 0.15)
				)
			)
		)
		(sheetname "Interfaces")
		(sheetfile "interfaces.kicad_sch")
		(attr exclude_from_pos_files)
		(pad "1" smd circle
			(at 0 0 90)
			(size 1 1)
			(layers "F.Cu" "F.Mask")
			(net 81 "Net-(J2-SCL)")
			(pinfunction "1")
			(pintype "passive")
		)
	)
	(footprint "antmicro-footprints:TP_SMD_1mm"
		(layer "F.Cu")
		(at 148.534 119.16 90)
		(property "Reference" "TP4"
			(at 0.36 0.0008 90)
			(layer "F.SilkS")
			(effects
				(font
					(size 0.7 0.7)
					(thickness 0.15)
				)
				(justify left bottom)
			)
		)
		(property "Value" "TP_1mm_SMD"
			(at 0 1.4 90)
			(layer "F.Fab")
			(effects
				(font
					(size 0.7 0.7)
					(thickness 0.15)
				)
				(justify left bottom)
			)
		)
		(property "Description" "Test Point 1mm"
			(at 0 0 90)
			(layer "F.Fab")
			(hide yes)
			(effects
				(font
					(size 1.27 1.27)
					(thickness 0.15)
				)
			)
		)
		(property "Author" "Antmicro"
			(at 267.694 -29.374 0)
			(layer "F.Fab")
			(hide yes)
			(effects
				(font
					(size 1 1)
					(thickness 0.15)
				)
			)
		)
		(property "License" "Apache-2.0"
			(at 267.694 -29.374 0)
			(layer "F.Fab")
			(hide yes)
			(effects
				(font
					(size 1 1)
					(thickness 0.15)
				)
			)
		)
		(property "MPN" ""
			(at 267.694 -29.374 0)
			(layer "F.Fab")
			(hide yes)
			(effects
				(font
					(size 1 1)
					(thickness 0.15)
				)
			)
		)
		(property "Manufacturer" ""
			(at 267.694 -29.374 0)
			(layer "F.Fab")
			(hide yes)
			(effects
				(font
					(size 1 1)
					(thickness 0.15)
				)
			)
		)
		(sheetname "Interfaces")
		(sheetfile "interfaces.kicad_sch")
		(attr exclude_from_pos_files)
		(pad "1" smd circle
			(at 0 0 90)
			(size 1 1)
			(layers "F.Cu" "F.Mask")
			(net 84 "Net-(J2-HPD{slash}HEAC-)")
			(pinfunction "1")
			(pintype "passive")
		)
	)
	(footprint "antmicro-footprints:TP_SMD_1mm"
		(layer "F.Cu")
		(at 150.3992 119.16 90)
		(property "Reference" "TP5"
			(at 0.36 0.0008 90)
			(layer "F.SilkS")
			(effects
				(font
					(size 0.7 0.7)
					(thickness 0.15)
				)
				(justify left bottom)
			)
		)
		(property "Value" "TP_1mm_SMD"
			(at 0 1.4 90)
			(layer "F.Fab")
			(effects
				(font
					(size 0.7 0.7)
					(thickness 0.15)
				)
				(justify left bottom)
			)
		)
		(property "Description" "Test Point 1mm"
			(at 0 0 90)
			(layer "F.Fab")
			(hide yes)
			(effects
				(font
					(size 1.27 1.27)
					(thickness 0.15)
				)
			)
		)
		(property "Author" "Antmicro"
			(at 269.5592 -31.2392 0)
			(layer "F.Fab")
			(hide yes)
			(effects
				(font
					(size 1 1)
					(thickness 0.15)
				)
			)
		)
		(property "License" "Apache-2.0"
			(at 269.5592 -31.2392 0)
			(layer "F.Fab")
			(hide yes)
			(effects
				(font
					(size 1 1)
					(thickness 0.15)
				)
			)
		)
		(property "MPN" ""
			(at 269.5592 -31.2392 0)
			(layer "F.Fab")
			(hide yes)
			(effects
				(font
					(size 1 1)
					(thickness 0.15)
				)
			)
		)
		(property "Manufacturer" ""
			(at 269.5592 -31.2392 0)
			(layer "F.Fab")
			(hide yes)
			(effects
				(font
					(size 1 1)
					(thickness 0.15)
				)
			)
		)
		(sheetname "Interfaces")
		(sheetfile "interfaces.kicad_sch")
		(attr exclude_from_pos_files)
		(pad "1" smd circle
			(at 0 0 90)
			(size 1 1)
			(layers "F.Cu" "F.Mask")
			(net 82 "Net-(J2-SDA)")
			(pinfunction "1")
			(pintype "passive")
		)
	)
	(footprint "antmicro-footprints:TP_SMD_1mm"
		(layer "F.Cu")
		(at 149.534 121.16 90)
		(property "Reference" "TP6"
			(at -2.24 -0.534 90)
			(layer "F.SilkS")
			(effects
				(font
					(size 0.7 0.7)
					(thickness 0.15)
				)
				(justify left bottom)
			)
		)
		(property "Value" "TP_1mm_SMD"
			(at 0 1.4 90)
			(layer "F.Fab")
			(effects
				(font
					(size 0.7 0.7)
					(thickness 0.15)
				)
				(justify left bottom)
			)
		)
		(property "Description" "Test Point 1mm"
			(at 0 0 90)
			(layer "F.Fab")
			(hide yes)
			(effects
				(font
					(size 1.27 1.27)
					(thickness 0.15)
				)
			)
		)
		(property "Author" "Antmicro"
			(at 270.694 -28.374 0)
			(layer "F.Fab")
			(hide yes)
			(effects
				(font
					(size 1 1)
					(thickness 0.15)
				)
			)
		)
		(property "License" "Apache-2.0"
			(at 270.694 -28.374 0)
			(layer "F.Fab")
			(hide yes)
			(effects
				(font
					(size 1 1)
					(thickness 0.15)
				)
			)
		)
		(property "MPN" ""
			(at 270.694 -28.374 0)
			(layer "F.Fab")
			(hide yes)
			(effects
				(font
					(size 1 1)
					(thickness 0.15)
				)
			)
		)
		(property "Manufacturer" ""
			(at 270.694 -28.374 0)
			(layer "F.Fab")
			(hide yes)
			(effects
				(font
					(size 1 1)
					(thickness 0.15)
				)
			)
		)
		(sheetname "Interfaces")
		(sheetfile "interfaces.kicad_sch")
		(attr exclude_from_pos_files)
		(pad "1" smd circle
			(at 0 0 90)
			(size 1 1)
			(layers "F.Cu" "F.Mask")
			(net 83 "Net-(J2-+5V)")
			(pinfunction "1")
			(pintype "passive")
		)
	)
	(footprint "antmicro-footprints:HDMI-A_Receptacle_WE_685119134923"
		(layer "F.Cu")
		(at 155.09 130.104 180)
		(property "Reference" "J2"
			(at -6.454 6.914 180)
			(layer "F.SilkS")
			(effects
				(font
					(size 0.7 0.7)
					(thickness 0.15)
				)
				(justify left bottom)
			)
		)
		(property "Value" "HDMI-A_685119134923"
			(at 0 7.8 180)
			(layer "F.Fab")
			(effects
				(font
					(size 0.7 0.7)
					(thickness 0.15)
				)
				(justify left bottom)
			)
		)
		(property "Description" "HDMI Receptacle Connector 19 Position Surface Mount, Right Angle; Through Hole"
			(at 0 0 180)
			(layer "F.Fab")
			(hide yes)
			(effects
				(font
					(size 1.27 1.27)
					(thickness 0.15)
				)
			)
		)
		(property "Author" "Antmicro"
			(at 310.18 260.208 0)
			(layer "F.Fab")
			(hide yes)
			(effects
				(font
					(size 1 1)
					(thickness 0.15)
				)
			)
		)
		(property "License" "Apache-2.0"
			(at 310.18 260.208 0)
			(layer "F.Fab")
			(hide yes)
			(effects
				(font
					(size 1 1)
					(thickness 0.15)
				)
			)
		)
		(property "MPN" "685119134923"
			(at 310.18 260.208 0)
			(layer "F.Fab")
			(hide yes)
			(effects
				(font
					(size 1 1)
					(thickness 0.15)
				)
			)
		)
		(property "Manufacturer" "Würth Elektronik"
			(at 310.18 260.208 0)
			(layer "F.Fab")
			(hide yes)
			(effects
				(font
					(size 1 1)
					(thickness 0.15)
				)
			)
		)
		(sheetname "Interfaces")
		(sheetfile "interfaces.kicad_sch")
		(attr smd)
		(fp_line
			(start 7.55 2.75)
			(end 7.55 -0.15)
			(stroke
				(width 0.12)
				(type solid)
			)
			(layer "F.SilkS")
		)
		(fp_line
			(start 5.7 5.65)
			(end 4.75 5.65)
			(stroke
				(width 0.12)
				(type solid)
			)
			(layer "F.SilkS")
		)
		(fp_line
			(start -4.85 5.65)
			(end -5.8 5.65)
			(stroke
				(width 0.12)
				(type solid)
			)
			(layer "F.SilkS")
		)
		(fp_line
			(start -7.55 -0.125)
			(end -7.55 2.65)
			(stroke
				(width 0.12)
				(type solid)
			)
			(layer "F.SilkS")
		)
		(fp_circle
			(center -4.9 5.9)
			(end -4.85 5.9)
			(stroke
				(width 0.15)
				(type solid)
			)
			(fill no)
			(layer "F.SilkS")
		)
		(fp_rect
			(start -8.05 -6.32)
			(end 7.949 6.78)
			(stroke
				(width 0.05)
				(type solid)
			)
			(fill no)
			(layer "F.CrtYd")
		)
		(fp_line
			(start 6.95 6.535)
			(end 6.95 -5.616)
			(stroke
				(width 0.15)
				(type solid)
			)
			(layer "F.Fab")
		)
		(fp_line
			(start 6.95 6.535)
			(end -6.05 6.535)
			(stroke
				(width 0.15)
				(type solid)
			)
			(layer "F.Fab")
		)
		(fp_line
			(start -7.05 5.525)
			(end -6.05 6.525)
			(stroke
				(width 0.15)
				(type solid)
			)
			(layer "F.Fab")
		)
		(fp_line
			(start -7.05 5.525)
			(end -7.05 -5.616)
			(stroke
				(width 0.15)
				(type solid)
			)
			(layer "F.Fab")
		)
		(fp_line
			(start -7.05 -5.616)
			(end 6.95 -5.616)
			(stroke
				(width 0.15)
				(type solid)
			)
			(layer "F.Fab")
		)
		(pad "1" smd rect
			(at -4.55 5.224 180)
			(size 0.28 2.6)
			(layers "F.Cu" "F.Mask" "F.Paste")
			(net 670 "/Interfaces/C_TMDS_D2_P")
			(pinfunction "D2+")
			(pintype "bidirectional")
		)
		(pad "2" smd rect
			(at -4.05 5.224 180)
			(size 0.28 2.6)
			(layers "F.Cu" "F.Mask" "F.Paste")
			(net 5 "GND")
			(pinfunction "D2S")
			(pintype "passive")
		)
		(pad "3" smd rect
			(at -3.551 5.224 180)
			(size 0.28 2.6)
			(layers "F.Cu" "F.Mask" "F.Paste")
			(net 669 "/Interfaces/C_TMDS_D2_N")
			(pinfunction "D2-")
			(pintype "bidirectional")
		)
		(pad "4" smd rect
			(at -3.051 5.224 180)
			(size 0.28 2.6)
			(layers "F.Cu" "F.Mask" "F.Paste")
			(net 668 "/Interfaces/C_TMDS_D1_P")
			(pinfunction "D1+")
			(pintype "bidirectional")
		)
		(pad "5" smd rect
			(at -2.551 5.224 180)
			(size 0.28 2.6)
			(layers "F.Cu" "F.Mask" "F.Paste")
			(net 5 "GND")
			(pinfunction "D1S")
			(pintype "passive")
		)
		(pad "6" smd rect
			(at -2.05 5.224 180)
			(size 0.28 2.6)
			(layers "F.Cu" "F.Mask" "F.Paste")
			(net 667 "/Interfaces/C_TMDS_D1_N")
			(pinfunction "D1-")
			(pintype "bidirectional")
		)
		(pad "7" smd rect
			(at -1.551 5.224 180)
			(size 0.28 2.6)
			(layers "F.Cu" "F.Mask" "F.Paste")
			(net 666 "/Interfaces/C_TMDS_D0_P")
			(pinfunction "D0+")
			(pintype "bidirectional")
		)
		(pad "8" smd rect
			(at -1.051 5.224 180)
			(size 0.28 2.6)
			(layers "F.Cu" "F.Mask" "F.Paste")
			(net 5 "GND")
			(pinfunction "D0S")
			(pintype "passive")
		)
		(pad "9" smd rect
			(at -0.551 5.224 180)
			(size 0.28 2.6)
			(layers "F.Cu" "F.Mask" "F.Paste")
			(net 665 "/Interfaces/C_TMDS_D0_N")
			(pinfunction "D0-")
			(pintype "bidirectional")
		)
		(pad "10" smd rect
			(at -0.051 5.224 180)
			(size 0.28 2.6)
			(layers "F.Cu" "F.Mask" "F.Paste")
			(net 664 "/Interfaces/C_TMDS_CLK_P")
			(pinfunction "CK+")
			(pintype "bidirectional")
		)
		(pad "11" smd rect
			(at 0.45 5.224 180)
			(size 0.28 2.6)
			(layers "F.Cu" "F.Mask" "F.Paste")
			(net 5 "GND")
			(pinfunction "CKS")
			(pintype "passive")
		)
		(pad "12" smd rect
			(at 0.95 5.224 180)
			(size 0.28 2.6)
			(layers "F.Cu" "F.Mask" "F.Paste")
			(net 663 "/Interfaces/C_TMDS_CLK_N")
			(pinfunction "CK-")
			(pintype "bidirectional")
		)
		(pad "13" smd rect
			(at 1.449 5.224 180)
			(size 0.28 2.6)
			(layers "F.Cu" "F.Mask" "F.Paste")
			(net 80 "Net-(J2-CEC)")
			(pinfunction "CEC")
			(pintype "bidirectional")
		)
		(pad "14" smd rect
			(at 1.949 5.224 180)
			(size 0.28 2.6)
			(layers "F.Cu" "F.Mask" "F.Paste")
			(net 79 "unconnected-(J2-UTILITY{slash}HEAC+-Pad14)")
			(pinfunction "UTILITY/HEAC+")
			(pintype "bidirectional+no_connect")
		)
		(pad "15" smd rect
			(at 2.45 5.224 180)
			(size 0.28 2.6)
			(layers "F.Cu" "F.Mask" "F.Paste")
			(net 81 "Net-(J2-SCL)")
			(pinfunction "SCL")
			(pintype "bidirectional")
		)
		(pad "16" smd rect
			(at 2.95 5.224 180)
			(size 0.28 2.6)
			(layers "F.Cu" "F.Mask" "F.Paste")
			(net 82 "Net-(J2-SDA)")
			(pinfunction "SDA")
			(pintype "bidirectional")
		)
		(pad "17" smd rect
			(at 3.45 5.224 180)
			(size 0.28 2.6)
			(layers "F.Cu" "F.Mask" "F.Paste")
			(net 5 "GND")
			(pinfunction "GND")
			(pintype "power_in")
		)
		(pad "18" smd rect
			(at 3.95 5.224 180)
			(size 0.28 2.6)
			(layers "F.Cu" "F.Mask" "F.Paste")
			(net 83 "Net-(J2-+5V)")
			(pinfunction "+5V")
			(pintype "power_in")
		)
		(pad "19" smd rect
			(at 4.45 5.224 180)
			(size 0.28 2.6)
			(layers "F.Cu" "F.Mask" "F.Paste")
			(net 84 "Net-(J2-HPD{slash}HEAC-)")
			(pinfunction "HPD/HEAC-")
			(pintype "bidirectional")
		)
		(pad "SH" thru_hole oval
			(at -7.3 -1.577 180)
			(size 1.5 2.7)
			(drill oval 0.9 2.1)
			(layers "*.Cu" "*.Mask")
			(remove_unused_layers no)
			(net 5 "GND")
			(pinfunction "SH")
			(pintype "passive")
		)
		(pad "SH" thru_hole oval
			(at -7.3 4.424 180)
			(size 1.5 3.3)
			(drill oval 0.9 2.7)
			(layers "*.Cu" "*.Mask")
			(remove_unused_layers no)
			(net 5 "GND")
			(pinfunction "SH")
			(pintype "passive")
		)
		(pad "SH" thru_hole oval
			(at 7.2 -1.577 180)
			(size 1.5 2.7)
			(drill oval 0.9 2.1)
			(layers "*.Cu" "*.Mask")
			(remove_unused_layers no)
			(net 5 "GND")
			(pinfunction "SH")
			(pintype "passive")
		)
		(pad "SH" thru_hole oval
			(at 7.2 4.424 180)
			(size 1.5 3.3)
			(drill oval 0.9 2.7)
			(layers "*.Cu" "*.Mask")
			(remove_unused_layers no)
			(net 5 "GND")
			(pinfunction "SH")
			(pintype "passive")
		)
	)
	(footprint "antmicro-footprints:C_0402_1005Metric"
		(layer "F.Cu")
		(at 138.286328 113.968157)
		(descr "Capacitor SMD 0402")
		(tags "capacitor SMD 0402")
		(property "Reference" "C11"
			(at -1.086328 -0.468157 0)
			(layer "F.SilkS")
			(effects
				(font
					(size 0.7 0.7)
					(thickness 0.15)
				)
				(justify left bottom)
			)
		)
		(property "Value" "C_100n_6V3_0402"
			(at 0 1.4 0)
			(layer "F.Fab")
			(effects
				(font
					(size 0.7 0.7)
					(thickness 0.15)
				)
				(justify left bottom)
			)
		)
		(property "Description" " "
			(at 0 0 0)
			(layer "F.Fab")
			(hide yes)
			(effects
				(font
					(size 1.27 1.27)
					(thickness 0.15)
				)
			)
		)
		(property "Author" "Antmicro"
			(at 0 0 0)
			(layer "F.Fab")
			(hide yes)
			(effects
				(font
					(size 1 1)
					(thickness 0.15)
				)
			)
		)
		(property "Dielectric" ""
			(at 0 0 0)
			(layer "F.Fab")
			(hide yes)
			(effects
				(font
					(size 1 1)
					(thickness 0.15)
				)
			)
		)
		(property "License" "Apache-2.0"
			(at 0 0 0)
			(layer "F.Fab")
			(hide yes)
			(effects
				(font
					(size 1 1)
					(thickness 0.15)
				)
			)
		)
		(property "MPN" "0402X104K6R3CT"
			(at 0 0 0)
			(layer "F.Fab")
			(hide yes)
			(effects
				(font
					(size 1 1)
					(thickness 0.15)
				)
			)
		)
		(property "Manufacturer" "Walsin"
			(at 0 0 0)
			(layer "F.Fab")
			(hide yes)
			(effects
				(font
					(size 1 1)
					(thickness 0.15)
				)
			)
		)
		(property "Val" "100n"
			(at 0 0 0)
			(layer "F.Fab")
			(hide yes)
			(effects
				(font
					(size 1 1)
					(thickness 0.15)
				)
			)
		)
		(property "Voltage" ""
			(at 0 0 0)
			(layer "F.Fab")
			(hide yes)
			(effects
				(font
					(size 1 1)
					(thickness 0.15)
				)
			)
		)
		(sheetname "Interfaces")
		(sheetfile "interfaces.kicad_sch")
		(attr smd)
		(fp_rect
			(start -0.94 -0.47)
			(end 0.94 0.47)
			(stroke
				(width 0.05)
				(type solid)
			)
			(fill no)
			(layer "F.CrtYd")
		)
		(fp_rect
			(start -0.499 -0.249)
			(end 0.499 0.249)
			(stroke
				(width 0.15)
				(type solid)
			)
			(fill no)
			(layer "F.Fab")
		)
		(pad "1" smd roundrect
			(at -0.484 0)
			(size 0.59 0.64)
			(layers "F.Cu" "F.Mask" "F.Paste")
			(roundrect_rratio 0.25)
			(net 5 "GND")
			(pintype "passive")
		)
		(pad "2" smd roundrect
			(at 0.484 0)
			(size 0.59 0.64)
			(layers "F.Cu" "F.Mask" "F.Paste")
			(roundrect_rratio 0.25)
			(net 653 "/Interfaces/VPHY")
			(pintype "passive")
		)
	)
	(footprint "antmicro-footprints:C_0402_1005Metric"
		(layer "F.Cu")
		(at 135.1 104.799 180)
		(descr "Capacitor SMD 0402")
		(tags "capacitor SMD 0402")
		(property "Reference" "C12"
			(at 2.9 -0.401 180)
			(layer "F.SilkS")
			(effects
				(font
					(size 0.7 0.7)
					(thickness 0.15)
				)
				(justify left bottom)
			)
		)
		(property "Value" "C_100n_6V3_0402"
			(at 0 1.4 180)
			(layer "F.Fab")
			(effects
				(font
					(size 0.7 0.7)
					(thickness 0.15)
				)
				(justify left bottom)
			)
		)
		(property "Description" " "
			(at 0 0 180)
			(layer "F.Fab")
			(hide yes)
			(effects
				(font
					(size 1.27 1.27)
					(thickness 0.15)
				)
			)
		)
		(property "Author" "Antmicro"
			(at 270.2 209.598 0)
			(layer "F.Fab")
			(hide yes)
			(effects
				(font
					(size 1 1)
					(thickness 0.15)
				)
			)
		)
		(property "Dielectric" ""
			(at 270.2 209.598 0)
			(layer "F.Fab")
			(hide yes)
			(effects
				(font
					(size 1 1)
					(thickness 0.15)
				)
			)
		)
		(property "License" "Apache-2.0"
			(at 270.2 209.598 0)
			(layer "F.Fab")
			(hide yes)
			(effects
				(font
					(size 1 1)
					(thickness 0.15)
				)
			)
		)
		(property "MPN" "0402X104K6R3CT"
			(at 270.2 209.598 0)
			(layer "F.Fab")
			(hide yes)
			(effects
				(font
					(size 1 1)
					(thickness 0.15)
				)
			)
		)
		(property "Manufacturer" "Walsin"
			(at 270.2 209.598 0)
			(layer "F.Fab")
			(hide yes)
			(effects
				(font
					(size 1 1)
					(thickness 0.15)
				)
			)
		)
		(property "Val" "100n"
			(at 270.2 209.598 0)
			(layer "F.Fab")
			(hide yes)
			(effects
				(font
					(size 1 1)
					(thickness 0.15)
				)
			)
		)
		(property "Voltage" ""
			(at 270.2 209.598 0)
			(layer "F.Fab")
			(hide yes)
			(effects
				(font
					(size 1 1)
					(thickness 0.15)
				)
			)
		)
		(sheetname "Interfaces")
		(sheetfile "interfaces.kicad_sch")
		(attr smd)
		(fp_rect
			(start -0.94 -0.47)
			(end 0.94 0.47)
			(stroke
				(width 0.05)
				(type solid)
			)
			(fill no)
			(layer "F.CrtYd")
		)
		(fp_rect
			(start -0.499 -0.249)
			(end 0.499 0.249)
			(stroke
				(width 0.15)
				(type solid)
			)
			(fill no)
			(layer "F.Fab")
		)
		(pad "1" smd roundrect
			(at -0.484 0 180)
			(size 0.59 0.64)
			(layers "F.Cu" "F.Mask" "F.Paste")
			(roundrect_rratio 0.25)
			(net 459 "3V3_SYS")
			(pintype "passive")
		)
		(pad "2" smd roundrect
			(at 0.484 0 180)
			(size 0.59 0.64)
			(layers "F.Cu" "F.Mask" "F.Paste")
			(roundrect_rratio 0.25)
			(net 5 "GND")
			(pintype "passive")
		)
	)
	(footprint "antmicro-footprints:C_0402_1005Metric"
		(layer "F.Cu")
		(at 135.1 103.751157)
		(descr "Capacitor SMD 0402")
		(tags "capacitor SMD 0402")
		(property "Reference" "C17"
			(at -2.9 0.348843 0)
			(layer "F.SilkS")
			(effects
				(font
					(size 0.7 0.7)
					(thickness 0.15)
				)
				(justify left bottom)
			)
		)
		(property "Value" "C_100n_6V3_0402"
			(at 0 1.4 0)
			(layer "F.Fab")
			(effects
				(font
					(size 0.7 0.7)
					(thickness 0.15)
				)
				(justify left bottom)
			)
		)
		(property "Description" " "
			(at 0 0 0)
			(layer "F.Fab")
			(hide yes)
			(effects
				(font
					(size 1.27 1.27)
					(thickness 0.15)
				)
			)
		)
		(property "Author" "Antmicro"
			(at 0 0 0)
			(layer "F.Fab")
			(hide yes)
			(effects
				(font
					(size 1 1)
					(thickness 0.15)
				)
			)
		)
		(property "Dielectric" ""
			(at 0 0 0)
			(layer "F.Fab")
			(hide yes)
			(effects
				(font
					(size 1 1)
					(thickness 0.15)
				)
			)
		)
		(property "License" "Apache-2.0"
			(at 0 0 0)
			(layer "F.Fab")
			(hide yes)
			(effects
				(font
					(size 1 1)
					(thickness 0.15)
				)
			)
		)
		(property "MPN" "0402X104K6R3CT"
			(at 0 0 0)
			(layer "F.Fab")
			(hide yes)
			(effects
				(font
					(size 1 1)
					(thickness 0.15)
				)
			)
		)
		(property "Manufacturer" "Walsin"
			(at 0 0 0)
			(layer "F.Fab")
			(hide yes)
			(effects
				(font
					(size 1 1)
					(thickness 0.15)
				)
			)
		)
		(property "Val" "100n"
			(at 0 0 0)
			(layer "F.Fab")
			(hide yes)
			(effects
				(font
					(size 1 1)
					(thickness 0.15)
				)
			)
		)
		(property "Voltage" ""
			(at 0 0 0)
			(layer "F.Fab")
			(hide yes)
			(effects
				(font
					(size 1 1)
					(thickness 0.15)
				)
			)
		)
		(sheetname "Interfaces")
		(sheetfile "interfaces.kicad_sch")
		(attr smd)
		(fp_rect
			(start -0.94 -0.47)
			(end 0.94 0.47)
			(stroke
				(width 0.05)
				(type solid)
			)
			(fill no)
			(layer "F.CrtYd")
		)
		(fp_rect
			(start -0.499 -0.249)
			(end 0.499 0.249)
			(stroke
				(width 0.15)
				(type solid)
			)
			(fill no)
			(layer "F.Fab")
		)
		(pad "1" smd roundrect
			(at -0.484 0)
			(size 0.59 0.64)
			(layers "F.Cu" "F.Mask" "F.Paste")
			(roundrect_rratio 0.25)
			(net 5 "GND")
			(pintype "passive")
		)
		(pad "2" smd roundrect
			(at 0.484 0)
			(size 0.59 0.64)
			(layers "F.Cu" "F.Mask" "F.Paste")
			(roundrect_rratio 0.25)
			(net 2 "/Interfaces/1V8_FT")
			(pintype "passive")
		)
	)
	(footprint "antmicro-footprints:R_0402_1005Metric"
		(layer "F.Cu")
		(at 154.059 113.135 -90)
		(descr "Resistor SMD 0402")
		(tags "resistor SMD 0402")
		(property "Reference" "R39"
			(at -0.835 -0.416 270)
			(layer "F.SilkS")
			(effects
				(font
					(size 0.7 0.7)
					(thickness 0.15)
				)
				(justify left bottom)
			)
		)
		(property "Value" "R_0R_0402"
			(at 0 1.4 270)
			(layer "F.Fab")
			(effects
				(font
					(size 0.7 0.7)
					(thickness 0.15)
				)
				(justify left bottom)
			)
		)
		(property "Description" "0R resistor in 0402 package with unspecified tolerance"
			(at 0 0 270)
			(layer "F.Fab")
			(hide yes)
			(effects
				(font
					(size 1.27 1.27)
					(thickness 0.15)
				)
			)
		)
		(property "Author" "Antmicro"
			(at 40.924 267.194 0)
			(layer "F.Fab")
			(hide yes)
			(effects
				(font
					(size 1 1)
					(thickness 0.15)
				)
			)
		)
		(property "Current" "1A"
			(at 40.924 267.194 0)
			(layer "F.Fab")
			(hide yes)
			(effects
				(font
					(size 1 1)
					(thickness 0.15)
				)
			)
		)
		(property "License" "Apache-2.0"
			(at 40.924 267.194 0)
			(layer "F.Fab")
			(hide yes)
			(effects
				(font
					(size 1 1)
					(thickness 0.15)
				)
			)
		)
		(property "MPN" "ERJ2GE0R00X"
			(at 40.924 267.194 0)
			(layer "F.Fab")
			(hide yes)
			(effects
				(font
					(size 1 1)
					(thickness 0.15)
				)
			)
		)
		(property "Manufacturer" "Panasonic"
			(at 40.924 267.194 0)
			(layer "F.Fab")
			(hide yes)
			(effects
				(font
					(size 1 1)
					(thickness 0.15)
				)
			)
		)
		(property "Tolerance" ""
			(at 40.924 267.194 0)
			(layer "F.Fab")
			(hide yes)
			(effects
				(font
					(size 1 1)
					(thickness 0.15)
				)
			)
		)
		(property "Val" "0R"
			(at 40.924 267.194 0)
			(layer "F.Fab")
			(hide yes)
			(effects
				(font
					(size 1 1)
					(thickness 0.15)
				)
			)
		)
		(sheetname "Interfaces")
		(sheetfile "interfaces.kicad_sch")
		(attr smd)
		(fp_rect
			(start -0.93 -0.47)
			(end 0.93 0.47)
			(stroke
				(width 0.05)
				(type solid)
			)
			(fill no)
			(layer "F.CrtYd")
		)
		(fp_rect
			(start -0.5 -0.25)
			(end 0.5 0.25)
			(stroke
				(width 0.15)
				(type solid)
			)
			(fill no)
			(layer "F.Fab")
		)
		(pad "1" smd roundrect
			(at -0.485 0 270)
			(size 0.59 0.64)
			(layers "F.Cu" "F.Mask" "F.Paste")
			(roundrect_rratio 0.25)
			(net 45 "TMDS_CLK_N")
			(pintype "passive")
		)
		(pad "2" smd roundrect
			(at 0.485 0 270)
			(size 0.59 0.64)
			(layers "F.Cu" "F.Mask" "F.Paste")
			(roundrect_rratio 0.25)
			(net 663 "/Interfaces/C_TMDS_CLK_N")
			(pintype "passive")
		)
	)
	(footprint "antmicro-footprints:R_0402_1005Metric"
		(layer "F.Cu")
		(at 155.084 113.135 -90)
		(descr "Resistor SMD 0402")
		(tags "resistor SMD 0402")
		(property "Reference" "R40"
			(at -0.835 -0.416 270)
			(layer "F.SilkS")
			(effects
				(font
					(size 0.7 0.7)
					(thickness 0.15)
				)
				(justify left bottom)
			)
		)
		(property "Value" "R_0R_0402"
			(at 0 1.4 270)
			(layer "F.Fab")
			(effects
				(font
					(size 0.7 0.7)
					(thickness 0.15)
				)
				(justify left bottom)
			)
		)
		(property "Description" "0R resistor in 0402 package with unspecified tolerance"
			(at 0 0 270)
			(layer "F.Fab")
			(hide yes)
			(effects
				(font
					(size 1.27 1.27)
					(thickness 0.15)
				)
			)
		)
		(property "Author" "Antmicro"
			(at 41.949 268.219 0)
			(layer "F.Fab")
			(hide yes)
			(effects
				(font
					(size 1 1)
					(thickness 0.15)
				)
			)
		)
		(property "Current" "1A"
			(at 41.949 268.219 0)
			(layer "F.Fab")
			(hide yes)
			(effects
				(font
					(size 1 1)
					(thickness 0.15)
				)
			)
		)
		(property "License" "Apache-2.0"
			(at 41.949 268.219 0)
			(layer "F.Fab")
			(hide yes)
			(effects
				(font
					(size 1 1)
					(thickness 0.15)
				)
			)
		)
		(property "MPN" "ERJ2GE0R00X"
			(at 41.949 268.219 0)
			(layer "F.Fab")
			(hide yes)
			(effects
				(font
					(size 1 1)
					(thickness 0.15)
				)
			)
		)
		(property "Manufacturer" "Panasonic"
			(at 41.949 268.219 0)
			(layer "F.Fab")
			(hide yes)
			(effects
				(font
					(size 1 1)
					(thickness 0.15)
				)
			)
		)
		(property "Tolerance" ""
			(at 41.949 268.219 0)
			(layer "F.Fab")
			(hide yes)
			(effects
				(font
					(size 1 1)
					(thickness 0.15)
				)
			)
		)
		(property "Val" "0R"
			(at 41.949 268.219 0)
			(layer "F.Fab")
			(hide yes)
			(effects
				(font
					(size 1 1)
					(thickness 0.15)
				)
			)
		)
		(sheetname "Interfaces")
		(sheetfile "interfaces.kicad_sch")
		(attr smd)
		(fp_rect
			(start -0.93 -0.47)
			(end 0.93 0.47)
			(stroke
				(width 0.05)
				(type solid)
			)
			(fill no)
			(layer "F.CrtYd")
		)
		(fp_rect
			(start -0.5 -0.25)
			(end 0.5 0.25)
			(stroke
				(width 0.15)
				(type solid)
			)
			(fill no)
			(layer "F.Fab")
		)
		(pad "1" smd roundrect
			(at -0.485 0 270)
			(size 0.59 0.64)
			(layers "F.Cu" "F.Mask" "F.Paste")
			(roundrect_rratio 0.25)
			(net 44 "TMDS_CLK_P")
			(pintype "passive")
		)
		(pad "2" smd roundrect
			(at 0.485 0 270)
			(size 0.59 0.64)
			(layers "F.Cu" "F.Mask" "F.Paste")
			(roundrect_rratio 0.25)
			(net 664 "/Interfaces/C_TMDS_CLK_P")
			(pintype "passive")
		)
	)
	(footprint "antmicro-footprints:R_0402_1005Metric"
		(layer "F.Cu")
		(at 155.559 115.35 -90)
		(descr "Resistor SMD 0402")
		(tags "resistor SMD 0402")
		(property "Reference" "R41"
			(at 1.25 1.559 270)
			(layer "F.SilkS")
			(effects
				(font
					(size 0.7 0.7)
					(thickness 0.15)
				)
				(justify left bottom)
			)
		)
		(property "Value" "R_0R_0402"
			(at 0 1.4 270)
			(layer "F.Fab")
			(effects
				(font
					(size 0.7 0.7)
					(thickness 0.15)
				)
				(justify left bottom)
			)
		)
		(property "Description" "0R resistor in 0402 package with unspecified tolerance"
			(at 0 0 270)
			(layer "F.Fab")
			(hide yes)
			(effects
				(font
					(size 1.27 1.27)
					(thickness 0.15)
				)
			)
		)
		(property "Author" "Antmicro"
			(at 40.209 270.909 0)
			(layer "F.Fab")
			(hide yes)
			(effects
				(font
					(size 1 1)
					(thickness 0.15)
				)
			)
		)
		(property "Current" "1A"
			(at 40.209 270.909 0)
			(layer "F.Fab")
			(hide yes)
			(effects
				(font
					(size 1 1)
					(thickness 0.15)
				)
			)
		)
		(property "License" "Apache-2.0"
			(at 40.209 270.909 0)
			(layer "F.Fab")
			(hide yes)
			(effects
				(font
					(size 1 1)
					(thickness 0.15)
				)
			)
		)
		(property "MPN" "ERJ2GE0R00X"
			(at 40.209 270.909 0)
			(layer "F.Fab")
			(hide yes)
			(effects
				(font
					(size 1 1)
					(thickness 0.15)
				)
			)
		)
		(property "Manufacturer" "Panasonic"
			(at 40.209 270.909 0)
			(layer "F.Fab")
			(hide yes)
			(effects
				(font
					(size 1 1)
					(thickness 0.15)
				)
			)
		)
		(property "Tolerance" ""
			(at 40.209 270.909 0)
			(layer "F.Fab")
			(hide yes)
			(effects
				(font
					(size 1 1)
					(thickness 0.15)
				)
			)
		)
		(property "Val" "0R"
			(at 40.209 270.909 0)
			(layer "F.Fab")
			(hide yes)
			(effects
				(font
					(size 1 1)
					(thickness 0.15)
				)
			)
		)
		(sheetname "Interfaces")
		(sheetfile "interfaces.kicad_sch")
		(attr smd)
		(fp_rect
			(start -0.93 -0.47)
			(end 0.93 0.47)
			(stroke
				(width 0.05)
				(type solid)
			)
			(fill no)
			(layer "F.CrtYd")
		)
		(fp_rect
			(start -0.5 -0.25)
			(end 0.5 0.25)
			(stroke
				(width 0.15)
				(type solid)
			)
			(fill no)
			(layer "F.Fab")
		)
		(pad "1" smd roundrect
			(at -0.485 0 270)
			(size 0.59 0.64)
			(layers "F.Cu" "F.Mask" "F.Paste")
			(roundrect_rratio 0.25)
			(net 47 "TMDS_D0_N")
			(pintype "passive")
		)
		(pad "2" smd roundrect
			(at 0.485 0 270)
			(size 0.59 0.64)
			(layers "F.Cu" "F.Mask" "F.Paste")
			(roundrect_rratio 0.25)
			(net 665 "/Interfaces/C_TMDS_D0_N")
			(pintype "passive")
		)
	)
	(footprint "antmicro-footprints:R_0402_1005Metric"
		(layer "F.Cu")
		(at 156.584 115.35 -90)
		(descr "Resistor SMD 0402")
		(tags "resistor SMD 0402")
		(property "Reference" "R42"
			(at 1.25 1.559 270)
			(layer "F.SilkS")
			(effects
				(font
					(size 0.7 0.7)
					(thickness 0.15)
				)
				(justify left bottom)
			)
		)
		(property "Value" "R_0R_0402"
			(at 0 1.4 270)
			(layer "F.Fab")
			(effects
				(font
					(size 0.7 0.7)
					(thickness 0.15)
				)
				(justify left bottom)
			)
		)
		(property "Description" "0R resistor in 0402 package with unspecified tolerance"
			(at 0 0 270)
			(layer "F.Fab")
			(hide yes)
			(effects
				(font
					(size 1.27 1.27)
					(thickness 0.15)
				)
			)
		)
		(property "Author" "Antmicro"
			(at 41.234 271.934 0)
			(layer "F.Fab")
			(hide yes)
			(effects
				(font
					(size 1 1)
					(thickness 0.15)
				)
			)
		)
		(property "Current" "1A"
			(at 41.234 271.934 0)
			(layer "F.Fab")
			(hide yes)
			(effects
				(font
					(size 1 1)
					(thickness 0.15)
				)
			)
		)
		(property "License" "Apache-2.0"
			(at 41.234 271.934 0)
			(layer "F.Fab")
			(hide yes)
			(effects
				(font
					(size 1 1)
					(thickness 0.15)
				)
			)
		)
		(property "MPN" "ERJ2GE0R00X"
			(at 41.234 271.934 0)
			(layer "F.Fab")
			(hide yes)
			(effects
				(font
					(size 1 1)
					(thickness 0.15)
				)
			)
		)
		(property "Manufacturer" "Panasonic"
			(at 41.234 271.934 0)
			(layer "F.Fab")
			(hide yes)
			(effects
				(font
					(size 1 1)
					(thickness 0.15)
				)
			)
		)
		(property "Tolerance" ""
			(at 41.234 271.934 0)
			(layer "F.Fab")
			(hide yes)
			(effects
				(font
					(size 1 1)
					(thickness 0.15)
				)
			)
		)
		(property "Val" "0R"
			(at 41.234 271.934 0)
			(layer "F.Fab")
			(hide yes)
			(effects
				(font
					(size 1 1)
					(thickness 0.15)
				)
			)
		)
		(sheetname "Interfaces")
		(sheetfile "interfaces.kicad_sch")
		(attr smd)
		(fp_rect
			(start -0.93 -0.47)
			(end 0.93 0.47)
			(stroke
				(width 0.05)
				(type solid)
			)
			(fill no)
			(layer "F.CrtYd")
		)
		(fp_rect
			(start -0.5 -0.25)
			(end 0.5 0.25)
			(stroke
				(width 0.15)
				(type solid)
			)
			(fill no)
			(layer "F.Fab")
		)
		(pad "1" smd roundrect
			(at -0.485 0 270)
			(size 0.59 0.64)
			(layers "F.Cu" "F.Mask" "F.Paste")
			(roundrect_rratio 0.25)
			(net 46 "TMDS_D0_P")
			(pintype "passive")
		)
		(pad "2" smd roundrect
			(at 0.485 0 270)
			(size 0.59 0.64)
			(layers "F.Cu" "F.Mask" "F.Paste")
			(roundrect_rratio 0.25)
			(net 666 "/Interfaces/C_TMDS_D0_P")
			(pintype "passive")
		)
	)
	(footprint "antmicro-footprints:R_0402_1005Metric"
		(layer "F.Cu")
		(at 158.104 113.05 -90)
		(descr "Resistor SMD 0402")
		(tags "resistor SMD 0402")
		(property "Reference" "R44"
			(at -0.835 -0.416 270)
			(layer "F.SilkS")
			(effects
				(font
					(size 0.7 0.7)
					(thickness 0.15)
				)
				(justify left bottom)
			)
		)
		(property "Value" "R_0R_0402"
			(at 0 1.4 270)
			(layer "F.Fab")
			(effects
				(font
					(size 0.7 0.7)
					(thickness 0.15)
				)
				(justify left bottom)
			)
		)
		(property "Description" "0R resistor in 0402 package with unspecified tolerance"
			(at 0 0 270)
			(layer "F.Fab")
			(hide yes)
			(effects
				(font
					(size 1.27 1.27)
					(thickness 0.15)
				)
			)
		)
		(property "Author" "Antmicro"
			(at 45.054 271.154 0)
			(layer "F.Fab")
			(hide yes)
			(effects
				(font
					(size 1 1)
					(thickness 0.15)
				)
			)
		)
		(property "Current" "1A"
			(at 45.054 271.154 0)
			(layer "F.Fab")
			(hide yes)
			(effects
				(font
					(size 1 1)
					(thickness 0.15)
				)
			)
		)
		(property "License" "Apache-2.0"
			(at 45.054 271.154 0)
			(layer "F.Fab")
			(hide yes)
			(effects
				(font
					(size 1 1)
					(thickness 0.15)
				)
			)
		)
		(property "MPN" "ERJ2GE0R00X"
			(at 45.054 271.154 0)
			(layer "F.Fab")
			(hide yes)
			(effects
				(font
					(size 1 1)
					(thickness 0.15)
				)
			)
		)
		(property "Manufacturer" "Panasonic"
			(at 45.054 271.154 0)
			(layer "F.Fab")
			(hide yes)
			(effects
				(font
					(size 1 1)
					(thickness 0.15)
				)
			)
		)
		(property "Tolerance" ""
			(at 45.054 271.154 0)
			(layer "F.Fab")
			(hide yes)
			(effects
				(font
					(size 1 1)
					(thickness 0.15)
				)
			)
		)
		(property "Val" "0R"
			(at 45.054 271.154 0)
			(layer "F.Fab")
			(hide yes)
			(effects
				(font
					(size 1 1)
					(thickness 0.15)
				)
			)
		)
		(sheetname "Interfaces")
		(sheetfile "interfaces.kicad_sch")
		(attr smd)
		(fp_rect
			(start -0.93 -0.47)
			(end 0.93 0.47)
			(stroke
				(width 0.05)
				(type solid)
			)
			(fill no)
			(layer "F.CrtYd")
		)
		(fp_rect
			(start -0.5 -0.25)
			(end 0.5 0.25)
			(stroke
				(width 0.15)
				(type solid)
			)
			(fill no)
			(layer "F.Fab")
		)
		(pad "1" smd roundrect
			(at -0.485 0 270)
			(size 0.59 0.64)
			(layers "F.Cu" "F.Mask" "F.Paste")
			(roundrect_rratio 0.25)
			(net 48 "TMDS_D1_P")
			(pintype "passive")
		)
		(pad "2" smd roundrect
			(at 0.485 0 270)
			(size 0.59 0.64)
			(layers "F.Cu" "F.Mask" "F.Paste")
			(roundrect_rratio 0.25)
			(net 668 "/Interfaces/C_TMDS_D1_P")
			(pintype "passive")
		)
	)
	(footprint "antmicro-footprints:R_0402_1005Metric"
		(layer "F.Cu")
		(at 158.643 115.477 -90)
		(descr "Resistor SMD 0402")
		(tags "resistor SMD 0402")
		(property "Reference" "R45"
			(at 1.25 -2.341 270)
			(layer "F.SilkS")
			(effects
				(font
					(size 0.7 0.7)
					(thickness 0.15)
				)
				(justify left bottom)
			)
		)
		(property "Value" "R_0R_0402"
			(at 0 1.4 270)
			(layer "F.Fab")
			(effects
				(font
					(size 0.7 0.7)
					(thickness 0.15)
				)
				(justify left bottom)
			)
		)
		(property "Description" "0R resistor in 0402 package with unspecified tolerance"
			(at 0 0 270)
			(layer "F.Fab")
			(hide yes)
			(effects
				(font
					(size 1.27 1.27)
					(thickness 0.15)
				)
			)
		)
		(property "Author" "Antmicro"
			(at 43.166 274.12 0)
			(layer "F.Fab")
			(hide yes)
			(effects
				(font
					(size 1 1)
					(thickness 0.15)
				)
			)
		)
		(property "Current" "1A"
			(at 43.166 274.12 0)
			(layer "F.Fab")
			(hide yes)
			(effects
				(font
					(size 1 1)
					(thickness 0.15)
				)
			)
		)
		(property "License" "Apache-2.0"
			(at 43.166 274.12 0)
			(layer "F.Fab")
			(hide yes)
			(effects
				(font
					(size 1 1)
					(thickness 0.15)
				)
			)
		)
		(property "MPN" "ERJ2GE0R00X"
			(at 43.166 274.12 0)
			(layer "F.Fab")
			(hide yes)
			(effects
				(font
					(size 1 1)
					(thickness 0.15)
				)
			)
		)
		(property "Manufacturer" "Panasonic"
			(at 43.166 274.12 0)
			(layer "F.Fab")
			(hide yes)
			(effects
				(font
					(size 1 1)
					(thickness 0.15)
				)
			)
		)
		(property "Tolerance" ""
			(at 43.166 274.12 0)
			(layer "F.Fab")
			(hide yes)
			(effects
				(font
					(size 1 1)
					(thickness 0.15)
				)
			)
		)
		(property "Val" "0R"
			(at 43.166 274.12 0)
			(layer "F.Fab")
			(hide yes)
			(effects
				(font
					(size 1 1)
					(thickness 0.15)
				)
			)
		)
		(sheetname "Interfaces")
		(sheetfile "interfaces.kicad_sch")
		(attr smd)
		(fp_rect
			(start -0.93 -0.47)
			(end 0.93 0.47)
			(stroke
				(width 0.05)
				(type solid)
			)
			(fill no)
			(layer "F.CrtYd")
		)
		(fp_rect
			(start -0.5 -0.25)
			(end 0.5 0.25)
			(stroke
				(width 0.15)
				(type solid)
			)
			(fill no)
			(layer "F.Fab")
		)
		(pad "1" smd roundrect
			(at -0.485 0 270)
			(size 0.59 0.64)
			(layers "F.Cu" "F.Mask" "F.Paste")
			(roundrect_rratio 0.25)
			(net 51 "TMDS_D2_N")
			(pintype "passive")
		)
		(pad "2" smd roundrect
			(at 0.485 0 270)
			(size 0.59 0.64)
			(layers "F.Cu" "F.Mask" "F.Paste")
			(roundrect_rratio 0.25)
			(net 669 "/Interfaces/C_TMDS_D2_N")
			(pintype "passive")
		)
	)
	(footprint "antmicro-footprints:R-PDSO-N15"
		(layer "F.Cu")
		(at 156.86 119.629 -90)
		(property "Reference" "IC1"
			(at 0.271 -4.14 270)
			(layer "F.SilkS")
			(effects
				(font
					(size 0.7 0.7)
					(thickness 0.15)
				)
				(justify left bottom)
			)
		)
		(property "Value" "TPD8S009DSMR"
			(at 0 4.4 270)
			(layer "F.Fab")
			(effects
				(font
					(size 0.7 0.7)
					(thickness 0.15)
				)
				(justify left bottom)
			)
		)
		(property "Author" "Antmicro"
			(at 37.231 276.489 0)
			(layer "F.Fab")
			(hide yes)
			(effects
				(font
					(size 1 1)
					(thickness 0.15)
				)
			)
		)
		(property "License" "Apache-2.0"
			(at 37.231 276.489 0)
			(layer "F.Fab")
			(hide yes)
			(effects
				(font
					(size 1 1)
					(thickness 0.15)
				)
			)
		)
		(property "MPN" "TPD8S009DSMR"
			(at 37.231 276.489 0)
			(layer "F.Fab")
			(hide yes)
			(effects
				(font
					(size 1 1)
					(thickness 0.15)
				)
			)
		)
		(property "Manufacturer" "Texas Instruments"
			(at 37.231 276.489 0)
			(layer "F.Fab")
			(hide yes)
			(effects
				(font
					(size 1 1)
					(thickness 0.15)
				)
			)
		)
		(sheetname "Interfaces")
		(sheetfile "interfaces.kicad_sch")
		(attr smd)
		(fp_circle
			(center -1.6 -3.2)
			(end -1.6 -3.15)
			(stroke
				(width 0.15)
				(type solid)
			)
			(fill yes)
			(layer "F.SilkS")
		)
		(fp_rect
			(start 1.8 -3.5)
			(end -1.89 3.49)
			(stroke
				(width 0.05)
				(type solid)
			)
			(fill no)
			(layer "F.CrtYd")
		)
		(fp_line
			(start -1.3 -3.051)
			(end -1.1 -3.25)
			(stroke
				(width 0.15)
				(type solid)
			)
			(layer "F.Fab")
		)
		(fp_rect
			(start 1.301 -3.25)
			(end -1.3 3.249)
			(stroke
				(width 0.15)
				(type solid)
			)
			(fill no)
			(layer "F.Fab")
		)
		(pad "1" smd roundrect
			(at -0.95 -2.75 180)
			(size 0.3 1.45)
			(layers "F.Cu" "F.Mask" "F.Paste")
			(roundrect_rratio 0.25)
			(net 670 "/Interfaces/C_TMDS_D2_P")
			(pinfunction "D0+")
			(pintype "passive")
		)
		(pad "2" smd roundrect
			(at -0.95 -2.25 180)
			(size 0.3 1.45)
			(layers "F.Cu" "F.Mask" "F.Paste")
			(roundrect_rratio 0.25)
			(net 5 "GND")
			(pinfunction "GND")
			(pintype "passive")
		)
		(pad "3" smd roundrect
			(at -0.95 -1.75 180)
			(size 0.3 1.45)
			(layers "F.Cu" "F.Mask" "F.Paste")
			(roundrect_rratio 0.25)
			(net 669 "/Interfaces/C_TMDS_D2_N")
			(pinfunction "D0-")
			(pintype "passive")
		)
		(pad "4" smd roundrect
			(at -0.95 -1.25 180)
			(size 0.3 1.45)
			(layers "F.Cu" "F.Mask" "F.Paste")
			(roundrect_rratio 0.25)
			(net 668 "/Interfaces/C_TMDS_D1_P")
			(pinfunction "D1+")
			(pintype "passive")
		)
		(pad "5" smd roundrect
			(at -0.95 -0.75 180)
			(size 0.3 1.45)
			(layers "F.Cu" "F.Mask" "F.Paste")
			(roundrect_rratio 0.25)
			(net 5 "GND")
			(pinfunction "GND")
			(pintype "passive")
		)
		(pad "6" smd roundrect
			(at -0.95 -0.25 180)
			(size 0.3 1.45)
			(layers "F.Cu" "F.Mask" "F.Paste")
			(roundrect_rratio 0.25)
			(net 667 "/Interfaces/C_TMDS_D1_N")
			(pinfunction "D1-")
			(pintype "passive")
		)
		(pad "7" smd roundrect
			(at -0.95 0.247 180)
			(size 0.3 1.45)
			(layers "F.Cu" "F.Mask" "F.Paste")
			(roundrect_rratio 0.25)
			(net 666 "/Interfaces/C_TMDS_D0_P")
			(pinfunction "D2+")
			(pintype "passive")
		)
		(pad "8" smd roundrect
			(at -0.95 0.747 180)
			(size 0.3 1.45)
			(layers "F.Cu" "F.Mask" "F.Paste")
			(roundrect_rratio 0.25)
			(net 5 "GND")
			(pinfunction "GND")
			(pintype "passive")
		)
		(pad "9" smd roundrect
			(at -0.95 1.249 180)
			(size 0.3 1.45)
			(layers "F.Cu" "F.Mask" "F.Paste")
			(roundrect_rratio 0.25)
			(net 665 "/Interfaces/C_TMDS_D0_N")
			(pinfunction "D2-")
			(pintype "passive")
		)
		(pad "10" smd roundrect
			(at -0.95 1.749 180)
			(size 0.3 1.45)
			(layers "F.Cu" "F.Mask" "F.Paste")
			(roundrect_rratio 0.25)
			(net 664 "/Interfaces/C_TMDS_CLK_P")
			(pinfunction "D3+")
			(pintype "passive")
		)
		(pad "11" smd roundrect
			(at -0.95 2.249 180)
			(size 0.3 1.45)
			(layers "F.Cu" "F.Mask" "F.Paste")
			(roundrect_rratio 0.25)
			(net 5 "GND")
			(pinfunction "GND")
			(pintype "passive")
		)
		(pad "12" smd roundrect
			(at -0.95 2.749 180)
			(size 0.3 1.45)
			(layers "F.Cu" "F.Mask" "F.Paste")
			(roundrect_rratio 0.25)
			(net 663 "/Interfaces/C_TMDS_CLK_N")
			(pinfunction "D3-")
			(pintype "passive")
		)
		(pad "13" smd roundrect
			(at 0.901 1.499 180)
			(size 0.3 1.45)
			(layers "F.Cu" "F.Mask" "F.Paste")
			(roundrect_rratio 0.25)
			(net 459 "3V3_SYS")
			(pinfunction "VCC")
			(pintype "power_in")
		)
		(pad "14" smd roundrect
			(at 0.901 0 180)
			(size 0.3 1.45)
			(layers "F.Cu" "F.Mask" "F.Paste")
			(roundrect_rratio 0.25)
			(net 75 "unconnected-(IC1-NC-Pad14)")
			(pinfunction "NC")
			(pintype "no_connect")
		)
		(pad "15" smd roundrect
			(at 0.901 -1.5 180)
			(size 0.3 1.45)
			(layers "F.Cu" "F.Mask" "F.Paste")
			(roundrect_rratio 0.25)
			(net 459 "3V3_SYS")
			(pinfunction "VCC")
			(pintype "passive")
		)
	)
	(footprint "antmicro-footprints:R_0402_1005Metric"
		(layer "F.Cu")
		(at 159.659 115.477 -90)
		(descr "Resistor SMD 0402")
		(tags "resistor SMD 0402")
		(property "Reference" "R46"
			(at 1.25 -2.341 270)
			(layer "F.SilkS")
			(effects
				(font
					(size 0.7 0.7)
					(thickness 0.15)
				)
				(justify left bottom)
			)
		)
		(property "Value" "R_0R_0402"
			(at 0 1.4 270)
			(layer "F.Fab")
			(effects
				(font
					(size 0.7 0.7)
					(thickness 0.15)
				)
				(justify left bottom)
			)
		)
		(property "Description" "0R resistor in 0402 package with unspecified tolerance"
			(at 0 0 270)
			(layer "F.Fab")
			(hide yes)
			(effects
				(font
					(size 1.27 1.27)
					(thickness 0.15)
				)
			)
		)
		(property "Author" "Antmicro"
			(at 44.182 275.136 0)
			(layer "F.Fab")
			(hide yes)
			(effects
				(font
					(size 1 1)
					(thickness 0.15)
				)
			)
		)
		(property "Current" "1A"
			(at 44.182 275.136 0)
			(layer "F.Fab")
			(hide yes)
			(effects
				(font
					(size 1 1)
					(thickness 0.15)
				)
			)
		)
		(property "License" "Apache-2.0"
			(at 44.182 275.136 0)
			(layer "F.Fab")
			(hide yes)
			(effects
				(font
					(size 1 1)
					(thickness 0.15)
				)
			)
		)
		(property "MPN" "ERJ2GE0R00X"
			(at 44.182 275.136 0)
			(layer "F.Fab")
			(hide yes)
			(effects
				(font
					(size 1 1)
					(thickness 0.15)
				)
			)
		)
		(property "Manufacturer" "Panasonic"
			(at 44.182 275.136 0)
			(layer "F.Fab")
			(hide yes)
			(effects
				(font
					(size 1 1)
					(thickness 0.15)
				)
			)
		)
		(property "Tolerance" ""
			(at 44.182 275.136 0)
			(layer "F.Fab")
			(hide yes)
			(effects
				(font
					(size 1 1)
					(thickness 0.15)
				)
			)
		)
		(property "Val" "0R"
			(at 44.182 275.136 0)
			(layer "F.Fab")
			(hide yes)
			(effects
				(font
					(size 1 1)
					(thickness 0.15)
				)
			)
		)
		(sheetname "Interfaces")
		(sheetfile "interfaces.kicad_sch")
		(attr smd)
		(fp_rect
			(start -0.93 -0.47)
			(end 0.93 0.47)
			(stroke
				(width 0.05)
				(type solid)
			)
			(fill no)
			(layer "F.CrtYd")
		)
		(fp_rect
			(start -0.5 -0.25)
			(end 0.5 0.25)
			(stroke
				(width 0.15)
				(type solid)
			)
			(fill no)
			(layer "F.Fab")
		)
		(pad "1" smd roundrect
			(at -0.485 0 270)
			(size 0.59 0.64)
			(layers "F.Cu" "F.Mask" "F.Paste")
			(roundrect_rratio 0.25)
			(net 50 "TMDS_D2_P")
			(pintype "passive")
		)
		(pad "2" smd roundrect
			(at 0.485 0 270)
			(size 0.59 0.64)
			(layers "F.Cu" "F.Mask" "F.Paste")
			(roundrect_rratio 0.25)
			(net 670 "/Interfaces/C_TMDS_D2_P")
			(pintype "passive")
		)
	)
	(footprint "antmicro-footprints:C_Pol_EIA-D"
		(layer "F.Cu")
		(at 150.4564 87.3496 180)
		(descr "Capacitor SMD KEMET_D")
		(tags "capacitor SMD KEMET_D")
		(property "Reference" "C81"
			(at -1.7436 -3.1504 180)
			(layer "F.SilkS")
			(effects
				(font
					(size 0.7 0.7)
					(thickness 0.15)
				)
				(justify left bottom)
			)
		)
		(property "Value" "C_330u_KEMET_D"
			(at 0 3.4 180)
			(layer "F.Fab")
			(effects
				(font
					(size 0.7 0.7)
					(thickness 0.15)
				)
				(justify left bottom)
			)
		)
		(property "Description" " "
			(at 0 0 180)
			(layer "F.Fab")
			(hide yes)
			(effects
				(font
					(size 1.27 1.27)
					(thickness 0.15)
				)
			)
		)
		(property "Author" "Antmicro"
			(at 300.9128 174.6992 0)
			(layer "F.Fab")
			(hide yes)
			(effects
				(font
					(size 1 1)
					(thickness 0.15)
				)
			)
		)
		(property "Dielectric" ""
			(at 300.9128 174.6992 0)
			(layer "F.Fab")
			(hide yes)
			(effects
				(font
					(size 1 1)
					(thickness 0.15)
				)
			)
		)
		(property "License" "Apache-2.0"
			(at 300.9128 174.6992 0)
			(layer "F.Fab")
			(hide yes)
			(effects
				(font
					(size 1 1)
					(thickness 0.15)
				)
			)
		)
		(property "MPN" "T520D337M006ATE045"
			(at 300.9128 174.6992 0)
			(layer "F.Fab")
			(hide yes)
			(effects
				(font
					(size 1 1)
					(thickness 0.15)
				)
			)
		)
		(property "Manufacturer" "KEMET"
			(at 300.9128 174.6992 0)
			(layer "F.Fab")
			(hide yes)
			(effects
				(font
					(size 1 1)
					(thickness 0.15)
				)
			)
		)
		(property "Val" "330u"
			(at 300.9128 174.6992 0)
			(layer "F.Fab")
			(hide yes)
			(effects
				(font
					(size 1 1)
					(thickness 0.15)
				)
			)
		)
		(property "Voltage" ""
			(at 300.9128 174.6992 0)
			(layer "F.Fab")
			(hide yes)
			(effects
				(font
					(size 1 1)
					(thickness 0.15)
				)
			)
		)
		(sheetname "FPGA power")
		(sheetfile "fpga-power.kicad_sch")
		(attr smd)
		(fp_line
			(start 3.65 2.15)
			(end 3.65 1.6)
			(stroke
				(width 0.15)
				(type solid)
			)
			(layer "F.SilkS")
		)
		(fp_line
			(start 3.65 -2.15)
			(end 3.65 -1.6)
			(stroke
				(width 0.15)
				(type solid)
			)
			(layer "F.SilkS")
		)
		(fp_line
			(start -3.65 2.15)
			(end 3.65 2.15)
			(stroke
				(width 0.15)
				(type solid)
			)
			(layer "F.SilkS")
		)
		(fp_line
			(start -3.65 1.6)
			(end -3.65 2.15)
			(stroke
				(width 0.15)
				(type solid)
			)
			(layer "F.SilkS")
		)
		(fp_line
			(start -3.65 -1.6)
			(end -3.65 -2.15)
			(stroke
				(width 0.15)
				(type solid)
			)
			(layer "F.SilkS")
		)
		(fp_line
			(start -3.65 -2.15)
			(end 3.65 -2.15)
			(stroke
				(width 0.15)
				(type solid)
			)
			(layer "F.SilkS")
		)
		(fp_line
			(start -4 -1.75)
			(end -4 -1.35)
			(stroke
				(width 0.12)
				(type solid)
			)
			(layer "F.SilkS")
		)
		(fp_line
			(start -4.2 -1.55)
			(end -3.8 -1.55)
			(stroke
				(width 0.12)
				(type solid)
			)
			(layer "F.SilkS")
		)
		(fp_line
			(start 4.3 1.5)
			(end 3.8 1.5)
			(stroke
				(width 0.05)
				(type solid)
			)
			(layer "F.CrtYd")
		)
		(fp_line
			(start 4.3 -1.5)
			(end 4.3 1.5)
			(stroke
				(width 0.05)
				(type solid)
			)
			(layer "F.CrtYd")
		)
		(fp_line
			(start 3.8 2.4)
			(end -3.8 2.4)
			(stroke
				(width 0.05)
				(type solid)
			)
			(layer "F.CrtYd")
		)
		(fp_line
			(start 3.8 1.5)
			(end 3.8 2.4)
			(stroke
				(width 0.05)
				(type solid)
			)
			(layer "F.CrtYd")
		)
		(fp_line
			(start 3.8 -1.5)
			(end 4.3 -1.5)
			(stroke
				(width 0.05)
				(type solid)
			)
			(layer "F.CrtYd")
		)
		(fp_line
			(start 3.8 -2.4)
			(end 3.8 -1.5)
			(stroke
				(width 0.05)
				(type solid)
			)
			(layer "F.CrtYd")
		)
		(fp_line
			(start -3.8 2.4)
			(end -3.8 1.5)
			(stroke
				(width 0.05)
				(type solid)
			)
			(layer "F.CrtYd")
		)
		(fp_line
			(start -3.8 1.5)
			(end -4.3 1.5)
			(stroke
				(width 0.05)
				(type solid)
			)
			(layer "F.CrtYd")
		)
		(fp_line
			(start -3.8 -1.5)
			(end -4.3 -1.5)
			(stroke
				(width 0.05)
				(type solid)
			)
			(layer "F.CrtYd")
		)
		(fp_line
			(start -3.8 -2.4)
			(end 3.8 -2.4)
			(stroke
				(width 0.05)
				(type solid)
			)
			(layer "F.CrtYd")
		)
		(fp_line
			(start -3.8 -2.4)
			(end -3.8 -1.5)
			(stroke
				(width 0.05)
				(type solid)
			)
			(layer "F.CrtYd")
		)
		(fp_line
			(start -4.3 1.5)
			(end -4.3 -1.5)
			(stroke
				(width 0.05)
				(type solid)
			)
			(layer "F.CrtYd")
		)
		(fp_rect
			(start -3.65 -2.15)
			(end 3.65 2.15)
			(stroke
				(width 0.15)
				(type solid)
			)
			(fill no)
			(layer "F.Fab")
		)
		(pad "1" smd rect
			(at -3.1 0 180)
			(size 2.31 2.52)
			(layers "F.Cu" "F.Mask" "F.Paste")
			(net 465 "1V0_SYS")
			(pintype "passive")
		)
		(pad "2" smd rect
			(at 3.1 0 180)
			(size 2.31 2.52)
			(layers "F.Cu" "F.Mask" "F.Paste")
			(net 5 "GND")
			(pintype "passive")
		)
	)
	(footprint "antmicro-footprints:C_0603_1608Metric"
		(layer "F.Cu")
		(at 151.003 92.455)
		(descr "Capacitor SMD 0603")
		(tags "capacitor 0603")
		(property "Reference" "C1"
			(at -0.779 -0.655 0)
			(layer "F.SilkS")
			(effects
				(font
					(size 0.7 0.7)
					(thickness 0.15)
				)
				(justify left bottom)
			)
		)
		(property "Value" "C_47u_0603"
			(at 0 1.6 0)
			(layer "F.Fab")
			(effects
				(font
					(size 0.7 0.7)
					(thickness 0.15)
				)
				(justify left bottom)
			)
		)
		(property "Description" " "
			(at 0 0 0)
			(layer "F.Fab")
			(hide yes)
			(effects
				(font
					(size 1.27 1.27)
					(thickness 0.15)
				)
			)
		)
		(property "Author" "Antmicro"
			(at 0 0 0)
			(layer "F.Fab")
			(hide yes)
			(effects
				(font
					(size 1 1)
					(thickness 0.15)
				)
			)
		)
		(property "Dielectric" ""
			(at 0 0 0)
			(layer "F.Fab")
			(hide yes)
			(effects
				(font
					(size 1 1)
					(thickness 0.15)
				)
			)
		)
		(property "License" "Apache-2.0"
			(at 0 0 0)
			(layer "F.Fab")
			(hide yes)
			(effects
				(font
					(size 1 1)
					(thickness 0.15)
				)
			)
		)
		(property "MPN" "GRM188R60J476ME15D"
			(at 0 0 0)
			(layer "F.Fab")
			(hide yes)
			(effects
				(font
					(size 1 1)
					(thickness 0.15)
				)
			)
		)
		(property "Manufacturer" "Murata"
			(at 0 0 0)
			(layer "F.Fab")
			(hide yes)
			(effects
				(font
					(size 1 1)
					(thickness 0.15)
				)
			)
		)
		(property "Val" "47u"
			(at 0 0 0)
			(layer "F.Fab")
			(hide yes)
			(effects
				(font
					(size 1 1)
					(thickness 0.15)
				)
			)
		)
		(property "Voltage" ""
			(at 0 0 0)
			(layer "F.Fab")
			(hide yes)
			(effects
				(font
					(size 1 1)
					(thickness 0.15)
				)
			)
		)
		(sheetname "HyperRAM")
		(sheetfile "hyperram.kicad_sch")
		(attr smd)
		(fp_line
			(start -0.3 -0.3)
			(end 0.3 -0.3)
			(stroke
				(width 0.15)
				(type solid)
			)
			(layer "F.SilkS")
		)
		(fp_line
			(start -0.3 0.3)
			(end 0.3 0.3)
			(stroke
				(width 0.15)
				(type solid)
			)
			(layer "F.SilkS")
		)
		(fp_rect
			(start -1.24 -0.7)
			(end 1.24 0.7)
			(stroke
				(width 0.05)
				(type solid)
			)
			(fill no)
			(layer "F.CrtYd")
		)
		(fp_rect
			(start -0.8 -0.4)
			(end 0.8 0.4)
			(stroke
				(width 0.15)
				(type solid)
			)
			(fill no)
			(layer "F.Fab")
		)
		(pad "1" smd roundrect
			(at -0.7 0)
			(size 0.6 0.8)
			(layers "F.Cu" "F.Mask" "F.Paste")
			(roundrect_rratio 0.2)
			(net 459 "3V3_SYS")
			(pintype "passive")
		)
		(pad "2" smd roundrect
			(at 0.7 0)
			(size 0.6 0.8)
			(layers "F.Cu" "F.Mask" "F.Paste")
			(roundrect_rratio 0.2)
			(net 5 "GND")
			(pintype "passive")
		)
	)
	(footprint "antmicro-footprints:R_0402_1005Metric"
		(layer "F.Cu")
		(at 148.9202 92.201 -90)
		(descr "Resistor SMD 0402")
		(tags "resistor SMD 0402")
		(property "Reference" "R1"
			(at -0.701 -0.3974 270)
			(layer "F.SilkS")
			(effects
				(font
					(size 0.7 0.7)
					(thickness 0.15)
				)
				(justify left bottom)
			)
		)
		(property "Value" "R_10k_0402"
			(at 0 1.4 270)
			(layer "F.Fab")
			(effects
				(font
					(size 0.7 0.7)
					(thickness 0.15)
				)
				(justify left bottom)
			)
		)
		(property "Description" "10k resistor in 0402 package with 1% tolerance"
			(at 0 0 270)
			(layer "F.Fab")
			(hide yes)
			(effects
				(font
					(size 1.27 1.27)
					(thickness 0.15)
				)
			)
		)
		(property "Author" "Antmicro"
			(at 56.7192 241.1212 0)
			(layer "F.Fab")
			(hide yes)
			(effects
				(font
					(size 1 1)
					(thickness 0.15)
				)
			)
		)
		(property "License" "Apache-2.0"
			(at 56.7192 241.1212 0)
			(layer "F.Fab")
			(hide yes)
			(effects
				(font
					(size 1 1)
					(thickness 0.15)
				)
			)
		)
		(property "MPN" "CR0402-FX-1002GLF"
			(at 56.7192 241.1212 0)
			(layer "F.Fab")
			(hide yes)
			(effects
				(font
					(size 1 1)
					(thickness 0.15)
				)
			)
		)
		(property "Manufacturer" "Bourns"
			(at 56.7192 241.1212 0)
			(layer "F.Fab")
			(hide yes)
			(effects
				(font
					(size 1 1)
					(thickness 0.15)
				)
			)
		)
		(property "Tolerance" "1%"
			(at 56.7192 241.1212 0)
			(layer "F.Fab")
			(hide yes)
			(effects
				(font
					(size 1 1)
					(thickness 0.15)
				)
			)
		)
		(property "Val" "10k"
			(at 56.7192 241.1212 0)
			(layer "F.Fab")
			(hide yes)
			(effects
				(font
					(size 1 1)
					(thickness 0.15)
				)
			)
		)
		(sheetname "HyperRAM")
		(sheetfile "hyperram.kicad_sch")
		(attr smd)
		(fp_rect
			(start -0.93 -0.47)
			(end 0.93 0.47)
			(stroke
				(width 0.05)
				(type solid)
			)
			(fill no)
			(layer "F.CrtYd")
		)
		(fp_rect
			(start -0.5 -0.25)
			(end 0.5 0.25)
			(stroke
				(width 0.15)
				(type solid)
			)
			(fill no)
			(layer "F.Fab")
		)
		(pad "1" smd roundrect
			(at -0.485 0 270)
			(size 0.59 0.64)
			(layers "F.Cu" "F.Mask" "F.Paste")
			(roundrect_rratio 0.25)
			(net 459 "3V3_SYS")
			(pintype "passive")
		)
		(pad "2" smd roundrect
			(at 0.485 0 270)
			(size 0.59 0.64)
			(layers "F.Cu" "F.Mask" "F.Paste")
			(roundrect_rratio 0.25)
			(net 488 "HR_RST")
			(pintype "passive")
		)
	)
	(footprint "antmicro-footprints:R_0402_1005Metric"
		(layer "F.Cu")
		(at 147.8026 92.201 -90)
		(descr "Resistor SMD 0402")
		(tags "resistor SMD 0402")
		(property "Reference" "R2"
			(at -0.701 -0.3974 270)
			(layer "F.SilkS")
			(effects
				(font
					(size 0.7 0.7)
					(thickness 0.15)
				)
				(justify left bottom)
			)
		)
		(property "Value" "R_10k_0402"
			(at 0 1.4 270)
			(layer "F.Fab")
			(effects
				(font
					(size 0.7 0.7)
					(thickness 0.15)
				)
				(justify left bottom)
			)
		)
		(property "Description" "10k resistor in 0402 package with 1% tolerance"
			(at 0 0 270)
			(layer "F.Fab")
			(hide yes)
			(effects
				(font
					(size 1.27 1.27)
					(thickness 0.15)
				)
			)
		)
		(property "Author" "Antmicro"
			(at 55.6016 240.0036 0)
			(layer "F.Fab")
			(hide yes)
			(effects
				(font
					(size 1 1)
					(thickness 0.15)
				)
			)
		)
		(property "License" "Apache-2.0"
			(at 55.6016 240.0036 0)
			(layer "F.Fab")
			(hide yes)
			(effects
				(font
					(size 1 1)
					(thickness 0.15)
				)
			)
		)
		(property "MPN" "CR0402-FX-1002GLF"
			(at 55.6016 240.0036 0)
			(layer "F.Fab")
			(hide yes)
			(effects
				(font
					(size 1 1)
					(thickness 0.15)
				)
			)
		)
		(property "Manufacturer" "Bourns"
			(at 55.6016 240.0036 0)
			(layer "F.Fab")
			(hide yes)
			(effects
				(font
					(size 1 1)
					(thickness 0.15)
				)
			)
		)
		(property "Tolerance" "1%"
			(at 55.6016 240.0036 0)
			(layer "F.Fab")
			(hide yes)
			(effects
				(font
					(size 1 1)
					(thickness 0.15)
				)
			)
		)
		(property "Val" "10k"
			(at 55.6016 240.0036 0)
			(layer "F.Fab")
			(hide yes)
			(effects
				(font
					(size 1 1)
					(thickness 0.15)
				)
			)
		)
		(sheetname "HyperRAM")
		(sheetfile "hyperram.kicad_sch")
		(attr smd)
		(fp_rect
			(start -0.93 -0.47)
			(end 0.93 0.47)
			(stroke
				(width 0.05)
				(type solid)
			)
			(fill no)
			(layer "F.CrtYd")
		)
		(fp_rect
			(start -0.5 -0.25)
			(end 0.5 0.25)
			(stroke
				(width 0.15)
				(type solid)
			)
			(fill no)
			(layer "F.Fab")
		)
		(pad "1" smd roundrect
			(at -0.485 0 270)
			(size 0.59 0.64)
			(layers "F.Cu" "F.Mask" "F.Paste")
			(roundrect_rratio 0.25)
			(net 459 "3V3_SYS")
			(pintype "passive")
		)
		(pad "2" smd roundrect
			(at 0.485 0 270)
			(size 0.59 0.64)
			(layers "F.Cu" "F.Mask" "F.Paste")
			(roundrect_rratio 0.25)
			(net 489 "HR_CS")
			(pintype "passive")
		)
	)
	(footprint "antmicro-footprints:FBGA-25-24_6x8mm_Layout5x5_P1mm"
		(layer "F.Cu")
		(at 150.696328 97.276157 90)
		(property "Reference" "U1"
			(at -0.723843 -4.196328 90)
			(layer "F.SilkS")
			(effects
				(font
					(size 0.7 0.7)
					(thickness 0.15)
				)
				(justify left bottom)
			)
		)
		(property "Value" "S27KL0641DABHI023"
			(at 0.1 5.3 90)
			(layer "F.Fab")
			(effects
				(font
					(size 0.7 0.7)
					(thickness 0.15)
				)
				(justify left bottom)
			)
		)
		(property "Author" "Antmicro"
			(at 247.972485 -53.420171 0)
			(layer "F.Fab")
			(hide yes)
			(effects
				(font
					(size 1 1)
					(thickness 0.15)
				)
			)
		)
		(property "License" "Apache-2.0"
			(at 247.972485 -53.420171 0)
			(layer "F.Fab")
			(hide yes)
			(effects
				(font
					(size 1 1)
					(thickness 0.15)
				)
			)
		)
		(property "MPN" "S27KL0641DABHI023"
			(at 247.972485 -53.420171 0)
			(layer "F.Fab")
			(hide yes)
			(effects
				(font
					(size 1 1)
					(thickness 0.15)
				)
			)
		)
		(property "Manufacturer" "Cypress Semiconductor"
			(at 247.972485 -53.420171 0)
			(layer "F.Fab")
			(hide yes)
			(effects
				(font
					(size 1 1)
					(thickness 0.15)
				)
			)
		)
		(sheetname "HyperRAM")
		(sheetfile "hyperram.kicad_sch")
		(attr smd)
		(fp_line
			(start 3.12 -4.121)
			(end 3.12 -2.121)
			(stroke
				(width 0.15)
				(type solid)
			)
			(layer "F.SilkS")
		)
		(fp_line
			(start 3.12 -4.121)
			(end 3.12 -2.121)
			(stroke
				(width 0.15)
				(type solid)
			)
			(layer "F.SilkS")
		)
		(fp_line
			(start 3.12 -4.121)
			(end 3.12 -2.121)
			(stroke
				(width 0.15)
				(type solid)
			)
			(layer "F.SilkS")
		)
		(fp_line
			(start 1.62 -4.121)
			(end 3.12 -4.121)
			(stroke
				(width 0.15)
				(type solid)
			)
			(layer "F.SilkS")
		)
		(fp_line
			(start 1.62 -4.121)
			(end 3.12 -4.121)
			(stroke
				(width 0.15)
				(type solid)
			)
			(layer "F.SilkS")
		)
		(fp_line
			(start 1.62 -4.121)
			(end 3.12 -4.121)
			(stroke
				(width 0.15)
				(type solid)
			)
			(layer "F.SilkS")
		)
		(fp_line
			(start -1.621 -4.121)
			(end -2 -4.121)
			(stroke
				(width 0.15)
				(type solid)
			)
			(layer "F.SilkS")
		)
		(fp_line
			(start -2 -4.121)
			(end -3.121 -3)
			(stroke
				(width 0.15)
				(type solid)
			)
			(layer "F.SilkS")
		)
		(fp_line
			(start -3.121 -3)
			(end -3.121 -2.121)
			(stroke
				(width 0.15)
				(type solid)
			)
			(layer "F.SilkS")
		)
		(fp_line
			(start 3.12 4.12)
			(end 3.12 2.12)
			(stroke
				(width 0.15)
				(type solid)
			)
			(layer "F.SilkS")
		)
		(fp_line
			(start 1.62 4.12)
			(end 3.12 4.12)
			(stroke
				(width 0.15)
				(type solid)
			)
			(layer "F.SilkS")
		)
		(fp_line
			(start -1.621 4.12)
			(end -3.121 4.12)
			(stroke
				(width 0.15)
				(type solid)
			)
			(layer "F.SilkS")
		)
		(fp_line
			(start -3.121 4.12)
			(end -3.121 2.12)
			(stroke
				(width 0.15)
				(type solid)
			)
			(layer "F.SilkS")
		)
		(fp_circle
			(center -3.6 -3.9)
			(end -3.5 -3.9)
			(stroke
				(width 0.15)
				(type solid)
			)
			(fill yes)
			(layer "F.SilkS")
		)
		(fp_line
			(start 3.24 -4.25)
			(end 3.24 4.24)
			(stroke
				(width 0.05)
				(type solid)
			)
			(layer "F.CrtYd")
		)
		(fp_line
			(start -3.25 -4.25)
			(end 3.24 -4.25)
			(stroke
				(width 0.05)
				(type solid)
			)
			(layer "F.CrtYd")
		)
		(fp_line
			(start 3.24 4.24)
			(end -3.25 4.24)
			(stroke
				(width 0.05)
				(type solid)
			)
			(layer "F.CrtYd")
		)
		(fp_line
			(start -3.25 4.24)
			(end -3.25 -4.25)
			(stroke
				(width 0.05)
				(type solid)
			)
			(layer "F.CrtYd")
		)
		(fp_line
			(start 2.999 -4)
			(end -2 -4)
			(stroke
				(width 0.15)
				(type solid)
			)
			(layer "F.Fab")
		)
		(fp_line
			(start -2 -4)
			(end -3 -3)
			(stroke
				(width 0.15)
				(type solid)
			)
			(layer "F.Fab")
		)
		(fp_line
			(start -3 -3)
			(end -3 3.999)
			(stroke
				(width 0.15)
				(type solid)
			)
			(layer "F.Fab")
		)
		(fp_line
			(start 2.999 3.999)
			(end 2.999 -4)
			(stroke
				(width 0.15)
				(type solid)
			)
			(layer "F.Fab")
		)
		(fp_line
			(start -3 3.999)
			(end 2.999 3.999)
			(stroke
				(width 0.15)
				(type solid)
			)
			(layer "F.Fab")
		)
		(pad "A2" smd circle
			(at -1 -2 90)
			(size 0.4 0.4)
			(layers "F.Cu" "F.Mask" "F.Paste")
			(net 266 "unconnected-(U1-NC-PadA2)")
			(pinfunction "NC")
			(pintype "no_connect")
		)
		(pad "A3" smd circle
			(at 0 -2 90)
			(size 0.4 0.4)
			(layers "F.Cu" "F.Mask" "F.Paste")
			(net 489 "HR_CS")
			(pinfunction "~{CS}")
			(pintype "input")
		)
		(pad "A4" smd circle
			(at 0.999 -2 90)
			(size 0.4 0.4)
			(layers "F.Cu" "F.Mask" "F.Paste")
			(net 488 "HR_RST")
			(pinfunction "~{RESET}")
			(pintype "input")
		)
		(pad "A5" smd circle
			(at 1.999 -2 90)
			(size 0.4 0.4)
			(layers "F.Cu" "F.Mask" "F.Paste")
			(net 267 "unconnected-(U1-NC-PadA5)")
			(pinfunction "NC")
			(pintype "no_connect")
		)
		(pad "B1" smd circle
			(at -2 -1 90)
			(size 0.4 0.4)
			(layers "F.Cu" "F.Mask" "F.Paste")
			(net 493 "HR_CKN")
			(pinfunction "CK-")
			(pintype "input")
		)
		(pad "B2" smd circle
			(at -1 -1 90)
			(size 0.4 0.4)
			(layers "F.Cu" "F.Mask" "F.Paste")
			(net 498 "HR_CKP")
			(pinfunction "CK+")
			(pintype "input")
		)
		(pad "B3" smd circle
			(at 0 -1 90)
			(size 0.4 0.4)
			(layers "F.Cu" "F.Mask" "F.Paste")
			(net 5 "GND")
			(pinfunction "VSS")
			(pintype "power_in")
		)
		(pad "B4" smd circle
			(at 0.999 -1 90)
			(size 0.4 0.4)
			(layers "F.Cu" "F.Mask" "F.Paste")
			(net 459 "3V3_SYS")
			(pinfunction "VCC")
			(pintype "power_in")
		)
		(pad "B5" smd circle
			(at 1.999 -1 90)
			(size 0.4 0.4)
			(layers "F.Cu" "F.Mask" "F.Paste")
			(net 268 "unconnected-(U1-NC-PadB5)")
			(pinfunction "NC")
			(pintype "no_connect")
		)
		(pad "C1" smd circle
			(at -2 0 90)
			(size 0.4 0.4)
			(layers "F.Cu" "F.Mask" "F.Paste")
			(net 5 "GND")
			(pinfunction "VSSQ")
			(pintype "power_in")
		)
		(pad "C2" smd circle
			(at -1 0 90)
			(size 0.4 0.4)
			(layers "F.Cu" "F.Mask" "F.Paste")
			(net 269 "unconnected-(U1-NC-PadC2)")
			(pinfunction "NC")
			(pintype "no_connect")
		)
		(pad "C3" smd circle
			(at 0 0 90)
			(size 0.4 0.4)
			(layers "F.Cu" "F.Mask" "F.Paste")
			(net 492 "HR_RW")
			(pinfunction "RWDS")
			(pintype "bidirectional")
		)
		(pad "C4" smd circle
			(at 0.999 0 90)
			(size 0.4 0.4)
			(layers "F.Cu" "F.Mask" "F.Paste")
			(net 500 "HR_DQ2")
			(pinfunction "DQ2")
			(pintype "bidirectional")
		)
		(pad "C5" smd circle
			(at 1.999 0 90)
			(size 0.4 0.4)
			(layers "F.Cu" "F.Mask" "F.Paste")
			(net 270 "unconnected-(U1-NC-PadC5)")
			(pinfunction "NC")
			(pintype "no_connect")
		)
		(pad "D1" smd circle
			(at -2 0.999 90)
			(size 0.4 0.4)
			(layers "F.Cu" "F.Mask" "F.Paste")
			(net 459 "3V3_SYS")
			(pinfunction "VCCQ")
			(pintype "power_in")
		)
		(pad "D2" smd circle
			(at -1 0.999 90)
			(size 0.4 0.4)
			(layers "F.Cu" "F.Mask" "F.Paste")
			(net 490 "HR_DQ1")
			(pinfunction "DQ1")
			(pintype "bidirectional")
		)
		(pad "D3" smd circle
			(at 0 0.999 90)
			(size 0.4 0.4)
			(layers "F.Cu" "F.Mask" "F.Paste")
			(net 491 "HR_DQ0")
			(pinfunction "DQ0")
			(pintype "bidirectional")
		)
		(pad "D4" smd circle
			(at 0.999 0.999 90)
			(size 0.4 0.4)
			(layers "F.Cu" "F.Mask" "F.Paste")
			(net 499 "HR_DQ3")
			(pinfunction "DQ3")
			(pintype "bidirectional")
		)
		(pad "D5" smd circle
			(at 1.999 0.999 90)
			(size 0.4 0.4)
			(layers "F.Cu" "F.Mask" "F.Paste")
			(net 495 "HR_DQ4")
			(pinfunction "DQ4")
			(pintype "bidirectional")
		)
		(pad "E1" smd circle
			(at -2 1.999 90)
			(size 0.4 0.4)
			(layers "F.Cu" "F.Mask" "F.Paste")
			(net 496 "HR_DQ7")
			(pinfunction "DQ7")
			(pintype "bidirectional")
		)
		(pad "E2" smd circle
			(at -1 1.999 90)
			(size 0.4 0.4)
			(layers "F.Cu" "F.Mask" "F.Paste")
			(net 497 "HR_DQ6")
			(pinfunction "DQ6")
			(pintype "bidirectional")
		)
		(pad "E3" smd circle
			(at 0 1.999 90)
			(size 0.4 0.4)
			(layers "F.Cu" "F.Mask" "F.Paste")
			(net 494 "HR_DQ5")
			(pinfunction "DQ5")
			(pintype "bidirectional")
		)
		(pad "E4" smd circle
			(at 0.999 1.999 90)
			(size 0.4 0.4)
			(layers "F.Cu" "F.Mask" "F.Paste")
			(net 459 "3V3_SYS")
			(pinfunction "VCCQ")
			(pintype "passive")
		)
		(pad "E5" smd circle
			(at 1.999 1.999 90)
			(size 0.4 0.4)
			(layers "F.Cu" "F.Mask" "F.Paste")
			(net 5 "GND")
			(pinfunction "VSSQ")
			(pintype "passive")
		)
	)
	(footprint "antmicro-footprints:BGA-484_23x23mm_Layout22x22_P1mm_FBG484"
		(locked yes)
		(layer "F.Cu")
		(at 169.036328 95.997157 -90)
		(property "Reference" "U3"
			(at -11.8 -12 270)
			(layer "F.SilkS")
			(effects
				(font
					(size 0.7 0.7)
					(thickness 0.15)
				)
				(justify left bottom)
			)
		)
		(property "Value" "XC7K70T-FBG484"
			(at -10.4 0.4 270)
			(layer "F.Fab")
			(effects
				(font
					(size 0.7 0.7)
					(thickness 0.15)
				)
				(justify left bottom)
			)
		)
		(property "Description" "Kintex®-7 Field Programmable Gate Array (FPGA) IC 285 484-BBGA, FCBGA"
			(at 0 0 270)
			(layer "F.Fab")
			(hide yes)
			(effects
				(font
					(size 1.27 1.27)
					(thickness 0.15)
				)
			)
		)
		(property "Author" "Antmicro"
			(at 73.039171 265.033485 0)
			(layer "F.Fab")
			(hide yes)
			(effects
				(font
					(size 1 1)
					(thickness 0.15)
				)
			)
		)
		(property "License" "Apache-2.0"
			(at 73.039171 265.033485 0)
			(layer "F.Fab")
			(hide yes)
			(effects
				(font
					(size 1 1)
					(thickness 0.15)
				)
			)
		)
		(property "MPN" "XC7K70T-1FBG484C"
			(at 73.039171 265.033485 0)
			(layer "F.Fab")
			(hide yes)
			(effects
				(font
					(size 1 1)
					(thickness 0.15)
				)
			)
		)
		(property "Manufacturer" "AMD-Xilinx"
			(at 73.039171 265.033485 0)
			(layer "F.Fab")
			(hide yes)
			(effects
				(font
					(size 1 1)
					(thickness 0.15)
				)
			)
		)
		(sheetname "FPGA Banks")
		(sheetfile "fpga-banks.kicad_sch")
		(attr smd)
		(fp_line
			(start -11.6 11.599)
			(end -11.6 -11.6)
			(stroke
				(width 0.15)
				(type solid)
			)
			(layer "F.SilkS")
		)
		(fp_line
			(start 11.599 11.599)
			(end -11.6 11.599)
			(stroke
				(width 0.15)
				(type solid)
			)
			(layer "F.SilkS")
		)
		(fp_line
			(start -11.6 -11.6)
			(end 11.599 -11.6)
			(stroke
				(width 0.15)
				(type solid)
			)
			(layer "F.SilkS")
		)
		(fp_line
			(start 11.599 -11.6)
			(end 11.599 11.599)
			(stroke
				(width 0.15)
				(type solid)
			)
			(layer "F.SilkS")
		)
		(fp_circle
			(center -12 -12)
			(end -11.95 -12)
			(stroke
				(width 0.15)
				(type solid)
			)
			(fill yes)
			(layer "F.SilkS")
		)
		(fp_rect
			(start -12.5 -12.5)
			(end 12.499 12.499)
			(stroke
				(width 0.05)
				(type solid)
			)
			(fill no)
			(layer "F.CrtYd")
		)
		(fp_line
			(start -11.5 -10.8)
			(end -10.8 -11.5)
			(stroke
				(width 0.15)
				(type solid)
			)
			(layer "F.Fab")
		)
		(fp_line
			(start -11.5 -11)
			(end -11 -11.5)
			(stroke
				(width 0.15)
				(type solid)
			)
			(layer "F.Fab")
		)
		(fp_line
			(start -11.5 -11.2)
			(end -11.2 -11.5)
			(stroke
				(width 0.15)
				(type solid)
			)
			(layer "F.Fab")
		)
		(fp_line
			(start -11.5 -11.3)
			(end -11.3 -11.5)
			(stroke
				(width 0.15)
				(type solid)
			)
			(layer "F.Fab")
		)
		(fp_rect
			(start -11.5 -11.5)
			(end 11.499 11.499)
			(stroke
				(width 0.15)
				(type solid)
			)
			(fill no)
			(layer "F.Fab")
		)
		(pad "A1" smd circle
			(at -10.5 -10.5 270)
			(size 0.51 0.51)
			(layers "F.Cu" "F.Mask" "F.Paste")
			(net 5 "GND")
			(pinfunction "GND")
			(pintype "power_in")
		)
		(pad "A2" smd circle
			(at -9.5 -10.5 270)
			(size 0.51 0.51)
			(layers "F.Cu" "F.Mask" "F.Paste")
			(net 271 "unconnected-(U3A-MGTAVTT-PadA2)")
			(pinfunction "MGTAVTT")
			(pintype "power_in+no_connect")
		)
		(pad "A3" smd circle
			(at -8.5 -10.5 270)
			(size 0.51 0.51)
			(layers "F.Cu" "F.Mask" "F.Paste")
			(net 272 "unconnected-(U3C-MGTXTXN3_115-PadA3)")
			(pinfunction "MGTXTXN3_115")
			(pintype "bidirectional+no_connect")
		)
		(pad "A4" smd circle
			(at -7.5 -10.5 270)
			(size 0.51 0.51)
			(layers "F.Cu" "F.Mask" "F.Paste")
			(net 274 "unconnected-(U3C-MGTXTXP3_115-PadA4)")
			(pinfunction "MGTXTXP3_115")
			(pintype "bidirectional+no_connect")
		)
		(pad "A5" smd circle
			(at -6.5 -10.5 270)
			(size 0.51 0.51)
			(layers "F.Cu" "F.Mask" "F.Paste")
			(net 5 "GND")
			(pinfunction "GND")
			(pintype "passive")
		)
		(pad "A6" smd circle
			(at -5.5 -10.5 270)
			(size 0.51 0.51)
			(layers "F.Cu" "F.Mask" "F.Paste")
			(net 275 "unconnected-(U3A-MGTAVCC-PadA6)")
			(pinfunction "MGTAVCC")
			(pintype "power_in+no_connect")
		)
		(pad "A7" smd circle
			(at -4.5 -10.5 270)
			(size 0.51 0.51)
			(layers "F.Cu" "F.Mask" "F.Paste")
			(net 5 "GND")
			(pinfunction "GND")
			(pintype "passive")
		)
		(pad "A8" smd circle
			(at -3.5 -10.5 270)
			(size 0.51 0.51)
			(layers "F.Cu" "F.Mask" "F.Paste")
			(net 57 "USR_LED3")
			(pinfunction "IO_L21N_T3_DQS_16")
			(pintype "bidirectional")
		)
		(pad "A9" smd circle
			(at -2.5 -10.5 270)
			(size 0.51 0.51)
			(layers "F.Cu" "F.Mask" "F.Paste")
			(net 276 "unconnected-(U3F-IO_L21P_T3_DQS_16-PadA9)")
			(pinfunction "IO_L21P_T3_DQS_16")
			(pintype "bidirectional+no_connect")
		)
		(pad "A10" smd circle
			(at -1.5 -10.5 270)
			(size 0.51 0.51)
			(layers "F.Cu" "F.Mask" "F.Paste")
			(net 277 "unconnected-(U3F-IO_L23N_T3_16-PadA10)")
			(pinfunction "IO_L23N_T3_16")
			(pintype "bidirectional+no_connect")
		)
		(pad "A11" smd circle
			(at -0.5 -10.5 270)
			(size 0.51 0.51)
			(layers "F.Cu" "F.Mask" "F.Paste")
			(net 278 "unconnected-(U3F-IO_L23P_T3_16-PadA11)")
			(pinfunction "IO_L23P_T3_16")
			(pintype "bidirectional+no_connect")
		)
		(pad "A12" smd circle
			(at 0.5 -10.5 270)
			(size 0.51 0.51)
			(layers "F.Cu" "F.Mask" "F.Paste")
			(net 5 "GND")
			(pinfunction "GND")
			(pintype "passive")
		)
		(pad "A13" smd circle
			(at 1.5 -10.5 270)
			(size 0.51 0.51)
			(layers "F.Cu" "F.Mask" "F.Paste")
			(net 31 "ETH_TX_EN")
			(pinfunction "IO_L4P_T0_AD9P_15")
			(pintype "bidirectional")
		)
		(pad "A14" smd circle
			(at 2.5 -10.5 270)
			(size 0.51 0.51)
			(layers "F.Cu" "F.Mask" "F.Paste")
			(net 33 "ETH_RXD3")
			(pinfunction "IO_L4N_T0_AD9N_15")
			(pintype "bidirectional")
		)
		(pad "A15" smd circle
			(at 3.5 -10.5 270)
			(size 0.51 0.51)
			(layers "F.Cu" "F.Mask" "F.Paste")
			(net 23 "ETH_RXD1")
			(pinfunction "IO_L9N_T1_DQS_AD11N_15")
			(pintype "bidirectional")
		)
		(pad "A16" smd circle
			(at 4.5 -10.5 270)
			(size 0.51 0.51)
			(layers "F.Cu" "F.Mask" "F.Paste")
			(net 34 "ETH_RX_DV")
			(pinfunction "IO_L8N_T1_AD3N_15")
			(pintype "bidirectional")
		)
		(pad "A17" smd circle
			(at 5.5 -10.5 270)
			(size 0.51 0.51)
			(layers "F.Cu" "F.Mask" "F.Paste")
			(net 459 "3V3_SYS")
			(pinfunction "VCCO_15")
			(pintype "power_in")
		)
		(pad "A18" smd circle
			(at 6.5 -10.5 270)
			(size 0.51 0.51)
			(layers "F.Cu" "F.Mask" "F.Paste")
			(net 29 "ETH_TXD3")
			(pinfunction "IO_L10N_T1_AD4N_15")
			(pintype "bidirectional")
		)
		(pad "A19" smd circle
			(at 7.5 -10.5 270)
			(size 0.51 0.51)
			(layers "F.Cu" "F.Mask" "F.Paste")
			(net 28 "ETH_TXD2")
			(pinfunction "IO_L20N_T3_A19_15")
			(pintype "bidirectional")
		)
		(pad "A20" smd circle
			(at 8.5 -10.5 270)
			(size 0.51 0.51)
			(layers "F.Cu" "F.Mask" "F.Paste")
			(net 279 "unconnected-(U3G-IO_L22P_T3_A17_15-PadA20)")
			(pinfunction "IO_L22P_T3_A17_15")
			(pintype "bidirectional+no_connect")
		)
		(pad "A21" smd circle
			(at 9.5 -10.5 270)
			(size 0.51 0.51)
			(layers "F.Cu" "F.Mask" "F.Paste")
			(net 280 "unconnected-(U3G-IO_L22N_T3_A16_15-PadA21)")
			(pinfunction "IO_L22N_T3_A16_15")
			(pintype "bidirectional+no_connect")
		)
		(pad "A22" smd circle
			(at 10.5 -10.5 270)
			(size 0.51 0.51)
			(layers "F.Cu" "F.Mask" "F.Paste")
			(net 5 "GND")
			(pinfunction "GND")
			(pintype "passive")
		)
		(pad "AA1" smd circle
			(at -10.5 9.5 270)
			(size 0.51 0.51)
			(layers "F.Cu" "F.Mask" "F.Paste")
			(net 333 "DQ10_A")
			(pinfunction "IO_L22P_T3_34")
			(pintype "bidirectional")
		)
		(pad "AA2" smd circle
			(at -9.5 9.5 270)
			(size 0.51 0.51)
			(layers "F.Cu" "F.Mask" "F.Paste")
			(net 5 "GND")
			(pinfunction "GND")
			(pintype "passive")
		)
		(pad "AA3" smd circle
			(at -8.5 9.5 270)
			(size 0.51 0.51)
			(layers "F.Cu" "F.Mask" "F.Paste")
			(net 70 "CA3_A")
			(pinfunction "IO_L23P_T3_34")
			(pintype "bidirectional")
		)
		(pad "AA4" smd circle
			(at -7.5 9.5 270)
			(size 0.51 0.51)
			(layers "F.Cu" "F.Mask" "F.Paste")
			(net 71 "CA2_A")
			(pinfunction "IO_L24P_T3_34")
			(pintype "bidirectional")
		)
		(pad "AA5" smd circle
			(at -6.5 9.5 270)
			(size 0.51 0.51)
			(layers "F.Cu" "F.Mask" "F.Paste")
			(net 281 "unconnected-(U3E-IO_L1P_T0_33-PadAA5)")
			(pinfunction "IO_L1P_T0_33")
			(pintype "bidirectional+no_connect")
		)
		(pad "AA6" smd circle
			(at -5.5 9.5 270)
			(size 0.51 0.51)
			(layers "F.Cu" "F.Mask" "F.Paste")
			(net 282 "unconnected-(U3E-IO_L3P_T0_DQS_33-PadAA6)")
			(pinfunction "IO_L3P_T0_DQS_33")
			(pintype "bidirectional+no_connect")
		)
		(pad "AA7" smd circle
			(at -4.5 9.5 270)
			(size 0.51 0.51)
			(layers "F.Cu" "F.Mask" "F.Paste")
			(net 66 "VDDQ")
			(pinfunction "VCCO_33")
			(pintype "power_in")
		)
		(pad "AA8" smd circle
			(at -3.5 9.5 270)
			(size 0.51 0.51)
			(layers "F.Cu" "F.Mask" "F.Paste")
			(net 283 "unconnected-(U3E-IO_L5N_T0_33-PadAA8)")
			(pinfunction "IO_L5N_T0_33")
			(pintype "bidirectional+no_connect")
		)
		(pad "AA9" smd circle
			(at -2.5 9.5 270)
			(size 0.51 0.51)
			(layers "F.Cu" "F.Mask" "F.Paste")
			(net 284 "unconnected-(U3E-IO_L5P_T0_33-PadAA9)")
			(pinfunction "IO_L5P_T0_33")
			(pintype "bidirectional+no_connect")
		)
		(pad "AA10" smd circle
			(at -1.5 9.5 270)
			(size 0.51 0.51)
			(layers "F.Cu" "F.Mask" "F.Paste")
			(net 285 "unconnected-(U3E-IO_L4P_T0_33-PadAA10)")
			(pinfunction "IO_L4P_T0_33")
			(pintype "bidirectional+no_connect")
		)
		(pad "AA11" smd circle
			(at -0.5 9.5 270)
			(size 0.51 0.51)
			(layers "F.Cu" "F.Mask" "F.Paste")
			(net 481 "IO_AA11")
			(pinfunction "IO_L20P_T3_33")
			(pintype "bidirectional")
		)
		(pad "AA12" smd circle
			(at 0.5 9.5 270)
			(size 0.51 0.51)
			(layers "F.Cu" "F.Mask" "F.Paste")
			(net 5 "GND")
			(pinfunction "GND")
			(pintype "passive")
		)
		(pad "AA13" smd circle
			(at 1.5 9.5 270)
			(size 0.51 0.51)
			(layers "F.Cu" "F.Mask" "F.Paste")
			(net 286 "unconnected-(U3E-IO_L21N_T3_DQS_33-PadAA13)")
			(pinfunction "IO_L21N_T3_DQS_33")
			(pintype "bidirectional+no_connect")
		)
		(pad "AA14" smd circle
			(at 2.5 9.5 270)
			(size 0.51 0.51)
			(layers "F.Cu" "F.Mask" "F.Paste")
			(net 500 "HR_DQ2")
			(pinfunction "IO_L18P_T2_13")
			(pintype "bidirectional")
		)
		(pad "AA15" smd circle
			(at 3.5 9.5 270)
			(size 0.51 0.51)
			(layers "F.Cu" "F.Mask" "F.Paste")
			(net 490 "HR_DQ1")
			(pinfunction "IO_L18N_T2_13")
			(pintype "bidirectional")
		)
		(pad "AA16" smd circle
			(at 4.5 9.5 270)
			(size 0.51 0.51)
			(layers "F.Cu" "F.Mask" "F.Paste")
			(net 489 "HR_CS")
			(pinfunction "IO_L17P_T2_13")
			(pintype "bidirectional")
		)
		(pad "AA17" smd circle
			(at 5.5 9.5 270)
			(size 0.51 0.51)
			(layers "F.Cu" "F.Mask" "F.Paste")
			(net 459 "3V3_SYS")
			(pinfunction "VCCO_13")
			(pintype "power_in")
		)
		(pad "AA18" smd circle
			(at 6.5 9.5 270)
			(size 0.51 0.51)
			(layers "F.Cu" "F.Mask" "F.Paste")
			(net 451 "UART0_RX")
			(pinfunction "IO_L15P_T2_DQS_13")
			(pintype "bidirectional")
		)
		(pad "AA19" smd circle
			(at 7.5 9.5 270)
			(size 0.51 0.51)
			(layers "F.Cu" "F.Mask" "F.Paste")
			(net 287 "unconnected-(U3I-IO_L10P_T1_13-PadAA19)")
			(pinfunction "IO_L10P_T1_13")
			(pintype "bidirectional+no_connect")
		)
		(pad "AA20" smd circle
			(at 8.5 9.5 270)
			(size 0.51 0.51)
			(layers "F.Cu" "F.Mask" "F.Paste")
			(net 457 "UART1_TX")
			(pinfunction "IO_L8P_T1_13")
			(pintype "bidirectional")
		)
		(pad "AA21" smd circle
			(at 9.5 9.5 270)
			(size 0.51 0.51)
			(layers "F.Cu" "F.Mask" "F.Paste")
			(net 646 "FPGA_AA21_BALL")
			(pinfunction "IO_L9P_T1_DQS_13")
			(pintype "bidirectional")
		)
		(pad "AA22" smd circle
			(at 10.5 9.5 270)
			(size 0.51 0.51)
			(layers "F.Cu" "F.Mask" "F.Paste")
			(net 5 "GND")
			(pinfunction "GND")
			(pintype "passive")
		)
		(pad "AB1" smd circle
			(at -10.5 10.5 270)
			(size 0.51 0.51)
			(layers "F.Cu" "F.Mask" "F.Paste")
			(net 332 "DQ11_A")
			(pinfunction "IO_L22N_T3_34")
			(pintype "bidirectional")
		)
		(pad "AB2" smd circle
			(at -9.5 10.5 270)
			(size 0.51 0.51)
			(layers "F.Cu" "F.Mask" "F.Paste")
			(net 68 "CA5_A")
			(pinfunction "IO_L23N_T3_34")
			(pintype "bidirectional")
		)
		(pad "AB3" smd circle
			(at -8.5 10.5 270)
			(size 0.51 0.51)
			(layers "F.Cu" "F.Mask" "F.Paste")
			(net 69 "CA4_A")
			(pinfunction "IO_L24N_T3_34")
			(pintype "bidirectional")
		)
		(pad "AB4" smd circle
			(at -7.5 10.5 270)
			(size 0.51 0.51)
			(layers "F.Cu" "F.Mask" "F.Paste")
			(net 66 "VDDQ")
			(pinfunction "VCCO_34")
			(pintype "power_in")
		)
		(pad "AB5" smd circle
			(at -6.5 10.5 270)
			(size 0.51 0.51)
			(layers "F.Cu" "F.Mask" "F.Paste")
			(net 288 "unconnected-(U3E-IO_L1N_T0_33-PadAB5)")
			(pinfunction "IO_L1N_T0_33")
			(pintype "bidirectional+no_connect")
		)
		(pad "AB6" smd circle
			(at -5.5 10.5 270)
			(size 0.51 0.51)
			(layers "F.Cu" "F.Mask" "F.Paste")
			(net 289 "unconnected-(U3E-IO_L3N_T0_DQS_33-PadAB6)")
			(pinfunction "IO_L3N_T0_DQS_33")
			(pintype "bidirectional+no_connect")
		)
		(pad "AB7" smd circle
			(at -4.5 10.5 270)
			(size 0.51 0.51)
			(layers "F.Cu" "F.Mask" "F.Paste")
			(net 290 "unconnected-(U3E-IO_L2N_T0_33-PadAB7)")
			(pinfunction "IO_L2N_T0_33")
			(pintype "bidirectional+no_connect")
		)
		(pad "AB8" smd circle
			(at -3.5 10.5 270)
			(size 0.51 0.51)
			(layers "F.Cu" "F.Mask" "F.Paste")
			(net 291 "unconnected-(U3E-IO_L2P_T0_33-PadAB8)")
			(pinfunction "IO_L2P_T0_33")
			(pintype "bidirectional+no_connect")
		)
		(pad "AB9" smd circle
			(at -2.5 10.5 270)
			(size 0.51 0.51)
			(layers "F.Cu" "F.Mask" "F.Paste")
			(net 5 "GND")
			(pinfunction "GND")
			(pintype "passive")
		)
		(pad "AB10" smd circle
			(at -1.5 10.5 270)
			(size 0.51 0.51)
			(layers "F.Cu" "F.Mask" "F.Paste")
			(net 480 "IO_AB10")
			(pinfunction "IO_L4N_T0_33")
			(pintype "bidirectional")
		)
		(pad "AB11" smd circle
			(at -0.5 10.5 270)
			(size 0.51 0.51)
			(layers "F.Cu" "F.Mask" "F.Paste")
			(net 479 "IO_AB11")
			(pinfunction "IO_L20N_T3_33")
			(pintype "bidirectional")
		)
		(pad "AB12" smd circle
			(at 0.5 10.5 270)
			(size 0.51 0.51)
			(layers "F.Cu" "F.Mask" "F.Paste")
			(net 292 "unconnected-(U3E-IO_L22N_T3_33-PadAB12)")
			(pinfunction "IO_L22N_T3_33")
			(pintype "bidirectional+no_connect")
		)
		(pad "AB13" smd circle
			(at 1.5 10.5 270)
			(size 0.51 0.51)
			(layers "F.Cu" "F.Mask" "F.Paste")
			(net 293 "unconnected-(U3E-IO_L22P_T3_33-PadAB13)")
			(pinfunction "IO_L22P_T3_33")
			(pintype "bidirectional+no_connect")
		)
		(pad "AB14" smd circle
			(at 2.5 10.5 270)
			(size 0.51 0.51)
			(layers "F.Cu" "F.Mask" "F.Paste")
			(net 459 "3V3_SYS")
			(pinfunction "VCCO_13")
			(pintype "passive")
		)
		(pad "AB15" smd circle
			(at 3.5 10.5 270)
			(size 0.51 0.51)
			(layers "F.Cu" "F.Mask" "F.Paste")
			(net 498 "HR_CKP")
			(pinfunction "IO_L16P_T2_13")
			(pintype "bidirectional")
		)
		(pad "AB16" smd circle
			(at 4.5 10.5 270)
			(size 0.51 0.51)
			(layers "F.Cu" "F.Mask" "F.Paste")
			(net 493 "HR_CKN")
			(pinfunction "IO_L16N_T2_13")
			(pintype "bidirectional")
		)
		(pad "AB17" smd circle
			(at 5.5 10.5 270)
			(size 0.51 0.51)
			(layers "F.Cu" "F.Mask" "F.Paste")
			(net 449 "AUX_JTAG_RST")
			(pinfunction "IO_L17N_T2_13")
			(pintype "bidirectional")
		)
		(pad "AB18" smd circle
			(at 6.5 10.5 270)
			(size 0.51 0.51)
			(layers "F.Cu" "F.Mask" "F.Paste")
			(net 453 "UART0_TX")
			(pinfunction "IO_L15N_T2_DQS_13")
			(pintype "bidirectional")
		)
		(pad "AB19" smd circle
			(at 7.5 10.5 270)
			(size 0.51 0.51)
			(layers "F.Cu" "F.Mask" "F.Paste")
			(net 5 "GND")
			(pinfunction "GND")
			(pintype "passive")
		)
		(pad "AB20" smd circle
			(at 8.5 10.5 270)
			(size 0.51 0.51)
			(layers "F.Cu" "F.Mask" "F.Paste")
			(net 455 "UART1_RX")
			(pinfunction "IO_L10N_T1_13")
			(pintype "bidirectional")
		)
		(pad "AB21" smd circle
			(at 9.5 10.5 270)
			(size 0.51 0.51)
			(layers "F.Cu" "F.Mask" "F.Paste")
			(net 644 "FPGA_AB21_BALL")
			(pinfunction "IO_L8N_T1_13")
			(pintype "bidirectional")
		)
		(pad "AB22" smd circle
			(at 10.5 10.5 270)
			(size 0.51 0.51)
			(layers "F.Cu" "F.Mask" "F.Paste")
			(net 643 "FPGA_AB22_BALL")
			(pinfunction "IO_L9N_T1_DQS_13")
			(pintype "bidirectional")
		)
		(pad "B1" smd circle
			(at -10.5 -9.5 270)
			(size 0.51 0.51)
			(layers "F.Cu" "F.Mask" "F.Paste")
			(net 294 "unconnected-(U3C-MGTXTXN2_115-PadB1)")
			(pinfunction "MGTXTXN2_115")
			(pintype "bidirectional+no_connect")
		)
		(pad "B2" smd circle
			(at -9.5 -9.5 270)
			(size 0.51 0.51)
			(layers "F.Cu" "F.Mask" "F.Paste")
			(net 295 "unconnected-(U3C-MGTXTXP2_115-PadB2)")
			(pinfunction "MGTXTXP2_115")
			(pintype "bidirectional+no_connect")
		)
		(pad "B3" smd circle
			(at -8.5 -9.5 270)
			(size 0.51 0.51)
			(layers "F.Cu" "F.Mask" "F.Paste")
			(net 5 "GND")
			(pinfunction "GND")
			(pintype "passive")
		)
		(pad "B4" smd circle
			(at -7.5 -9.5 270)
			(size 0.51 0.51)
			(layers "F.Cu" "F.Mask" "F.Paste")
			(net 5 "GND")
			(pinfunction "GND")
			(pintype "passive")
		)
		(pad "B5" smd circle
			(at -6.5 -9.5 270)
			(size 0.51 0.51)
			(layers "F.Cu" "F.Mask" "F.Paste")
			(net 296 "unconnected-(U3C-MGTXRXN3_115-PadB5)")
			(pinfunction "MGTXRXN3_115")
			(pintype "bidirectional+no_connect")
		)
		(pad "B6" smd circle
			(at -5.5 -9.5 270)
			(size 0.51 0.51)
			(layers "F.Cu" "F.Mask" "F.Paste")
			(net 297 "unconnected-(U3C-MGTXRXP3_115-PadB6)")
			(pinfunction "MGTXRXP3_115")
			(pintype "bidirectional+no_connect")
		)
		(pad "B7" smd circle
			(at -4.5 -9.5 270)
			(size 0.51 0.51)
			(layers "F.Cu" "F.Mask" "F.Paste")
			(net 5 "GND")
			(pinfunction "GND")
			(pintype "passive")
		)
		(pad "B8" smd circle
			(at -3.5 -9.5 270)
			(size 0.51 0.51)
			(layers "F.Cu" "F.Mask" "F.Paste")
			(net 391 "USR_BTN2")
			(pinfunction "IO_L22N_T3_16")
			(pintype "bidirectional")
		)
		(pad "B9" smd circle
			(at -2.5 -9.5 270)
			(size 0.51 0.51)
			(layers "F.Cu" "F.Mask" "F.Paste")
			(net 5 "GND")
			(pinfunction "GND")
			(pintype "passive")
		)
		(pad "B10" smd circle
			(at -1.5 -9.5 270)
			(size 0.51 0.51)
			(layers "F.Cu" "F.Mask" "F.Paste")
			(net 298 "unconnected-(U3F-IO_L20N_T3_16-PadB10)")
			(pinfunction "IO_L20N_T3_16")
			(pintype "bidirectional+no_connect")
		)
		(pad "B11" smd circle
			(at -0.5 -9.5 270)
			(size 0.51 0.51)
			(layers "F.Cu" "F.Mask" "F.Paste")
			(net 299 "unconnected-(U3F-IO_L20P_T3_16-PadB11)")
			(pinfunction "IO_L20P_T3_16")
			(pintype "bidirectional+no_connect")
		)
		(pad "B12" smd circle
			(at 0.5 -9.5 270)
			(size 0.51 0.51)
			(layers "F.Cu" "F.Mask" "F.Paste")
			(net 300 "unconnected-(U3G-IO_L2N_T0_AD8N_15-PadB12)")
			(pinfunction "IO_L2N_T0_AD8N_15")
			(pintype "bidirectional+no_connect")
		)
		(pad "B13" smd circle
			(at 1.5 -9.5 270)
			(size 0.51 0.51)
			(layers "F.Cu" "F.Mask" "F.Paste")
			(net 301 "unconnected-(U3G-IO_L5N_T0_AD2N_15-PadB13)")
			(pinfunction "IO_L5N_T0_AD2N_15")
			(pintype "bidirectional+no_connect")
		)
		(pad "B14" smd circle
			(at 2.5 -9.5 270)
			(size 0.51 0.51)
			(layers "F.Cu" "F.Mask" "F.Paste")
			(net 459 "3V3_SYS")
			(pinfunction "VCCO_15")
			(pintype "passive")
		)
		(pad "B15" smd circle
			(at 3.5 -9.5 270)
			(size 0.51 0.51)
			(layers "F.Cu" "F.Mask" "F.Paste")
			(net 37 "ETH_RXD2")
			(pinfunction "IO_L9P_T1_DQS_AD11P_15")
			(pintype "bidirectional")
		)
		(pad "B16" smd circle
			(at 4.5 -9.5 270)
			(size 0.51 0.51)
			(layers "F.Cu" "F.Mask" "F.Paste")
			(net 22 "ETH_RXD0")
			(pinfunction "IO_L8P_T1_AD3P_15")
			(pintype "bidirectional")
		)
		(pad "B17" smd circle
			(at 5.5 -9.5 270)
			(size 0.51 0.51)
			(layers "F.Cu" "F.Mask" "F.Paste")
			(net 35 "ETH_MDC")
			(pinfunction "IO_L10P_T1_AD4P_15")
			(pintype "bidirectional")
		)
		(pad "B18" smd circle
			(at 6.5 -9.5 270)
			(size 0.51 0.51)
			(layers "F.Cu" "F.Mask" "F.Paste")
			(net 302 "unconnected-(U3G-IO_L20P_T3_A20_15-PadB18)")
			(pinfunction "IO_L20P_T3_A20_15")
			(pintype "bidirectional+no_connect")
		)
		(pad "B19" smd circle
			(at 7.5 -9.5 270)
			(size 0.51 0.51)
			(layers "F.Cu" "F.Mask" "F.Paste")
			(net 5 "GND")
			(pinfunction "GND")
			(pintype "passive")
		)
		(pad "B20" smd circle
			(at 8.5 -9.5 270)
			(size 0.51 0.51)
			(layers "F.Cu" "F.Mask" "F.Paste")
			(net 27 "ETH_TXD1")
			(pinfunction "IO_L24P_T3_RS1_15")
			(pintype "bidirectional")
		)
		(pad "B21" smd circle
			(at 9.5 -9.5 270)
			(size 0.51 0.51)
			(layers "F.Cu" "F.Mask" "F.Paste")
			(net 32 "ETH_TXD0")
			(pinfunction "IO_L24N_T3_RS0_15")
			(pintype "bidirectional")
		)
		(pad "B22" smd circle
			(at 10.5 -9.5 270)
			(size 0.51 0.51)
			(layers "F.Cu" "F.Mask" "F.Paste")
			(net 198 "SD_CD")
			(pinfunction "IO_L21N_T3_DQS_A18_15")
			(pintype "bidirectional")
		)
		(pad "C1" smd circle
			(at -10.5 -8.5 270)
			(size 0.51 0.51)
			(layers "F.Cu" "F.Mask" "F.Paste")
			(net 5 "GND")
			(pinfunction "GND")
			(pintype "passive")
		)
		(pad "C2" smd circle
			(at -9.5 -8.5 270)
			(size 0.51 0.51)
			(layers "F.Cu" "F.Mask" "F.Paste")
			(net 271 "unconnected-(U3A-MGTAVTT-PadA2)")
			(pinfunction "MGTAVTT")
			(pintype "passive+no_connect")
		)
		(pad "C3" smd circle
			(at -8.5 -8.5 270)
			(size 0.51 0.51)
			(layers "F.Cu" "F.Mask" "F.Paste")
			(net 303 "unconnected-(U3C-MGTXRXN2_115-PadC3)")
			(pinfunction "MGTXRXN2_115")
			(pintype "bidirectional+no_connect")
		)
		(pad "C4" smd circle
			(at -7.5 -8.5 270)
			(size 0.51 0.51)
			(layers "F.Cu" "F.Mask" "F.Paste")
			(net 304 "unconnected-(U3C-MGTXRXP2_115-PadC4)")
			(pinfunction "MGTXRXP2_115")
			(pintype "bidirectional+no_connect")
		)
		(pad "C5" smd circle
			(at -6.5 -8.5 270)
			(size 0.51 0.51)
			(layers "F.Cu" "F.Mask" "F.Paste")
			(net 5 "GND")
			(pinfunction "GND")
			(pintype "passive")
		)
		(pad "C6" smd circle
			(at -5.5 -8.5 270)
			(size 0.51 0.51)
			(layers "F.Cu" "F.Mask" "F.Paste")
			(net 275 "unconnected-(U3A-MGTAVCC-PadA6)")
			(pinfunction "MGTAVCC")
			(pintype "passive+no_connect")
		)
		(pad "C7" smd circle
			(at -4.5 -8.5 270)
			(size 0.51 0.51)
			(layers "F.Cu" "F.Mask" "F.Paste")
			(net 5 "GND")
			(pinfunction "GND")
			(pintype "passive")
		)
		(pad "C8" smd circle
			(at -3.5 -8.5 270)
			(size 0.51 0.51)
			(layers "F.Cu" "F.Mask" "F.Paste")
			(net 59 "USR_LED2")
			(pinfunction "IO_L22P_T3_16")
			(pintype "bidirectional")
		)
		(pad "C9" smd circle
			(at -2.5 -8.5 270)
			(size 0.51 0.51)
			(layers "F.Cu" "F.Mask" "F.Paste")
			(net 392 "USR_BTN3")
			(pinfunction "IO_L19N_T3_VREF_16")
			(pintype "bidirectional")
		)
		(pad "C10" smd circle
			(at -1.5 -8.5 270)
			(size 0.51 0.51)
			(layers "F.Cu" "F.Mask" "F.Paste")
			(net 305 "unconnected-(U3F-IO_L7N_T1_16-PadC10)")
			(pinfunction "IO_L7N_T1_16")
			(pintype "bidirectional+no_connect")
		)
		(pad "C11" smd circle
			(at -0.5 -8.5 270)
			(size 0.51 0.51)
			(layers "F.Cu" "F.Mask" "F.Paste")
			(net 459 "3V3_SYS")
			(pinfunction "VCCO_16")
			(pintype "power_in")
		)
		(pad "C12" smd circle
			(at 0.5 -8.5 270)
			(size 0.51 0.51)
			(layers "F.Cu" "F.Mask" "F.Paste")
			(net 26 "ETH_REF_CLK")
			(pinfunction "IO_L2P_T0_AD8P_15")
			(pintype "bidirectional")
		)
		(pad "C13" smd circle
			(at 1.5 -8.5 270)
			(size 0.51 0.51)
			(layers "F.Cu" "F.Mask" "F.Paste")
			(net 306 "unconnected-(U3G-IO_L5P_T0_AD2P_15-PadC13)")
			(pinfunction "IO_L5P_T0_AD2P_15")
			(pintype "bidirectional+no_connect")
		)
		(pad "C14" smd circle
			(at 2.5 -8.5 270)
			(size 0.51 0.51)
			(layers "F.Cu" "F.Mask" "F.Paste")
			(net 25 "ETH_MDIO")
			(pinfunction "IO_L7P_T1_AD10P_15")
			(pintype "bidirectional")
		)
		(pad "C15" smd circle
			(at 3.5 -8.5 270)
			(size 0.51 0.51)
			(layers "F.Cu" "F.Mask" "F.Paste")
			(net 541 "ETH_INT_N")
			(pinfunction "IO_L7N_T1_AD10N_15")
			(pintype "bidirectional")
		)
		(pad "C16" smd circle
			(at 4.5 -8.5 270)
			(size 0.51 0.51)
			(layers "F.Cu" "F.Mask" "F.Paste")
			(net 5 "GND")
			(pinfunction "GND")
			(pintype "passive")
		)
		(pad "C17" smd circle
			(at 5.5 -8.5 270)
			(size 0.51 0.51)
			(layers "F.Cu" "F.Mask" "F.Paste")
			(net 36 "ETH_RX_CLK")
			(pinfunction "IO_L12P_T1_MRCC_AD5P_15")
			(pintype "bidirectional")
		)
		(pad "C18" smd circle
			(at 6.5 -8.5 270)
			(size 0.51 0.51)
			(layers "F.Cu" "F.Mask" "F.Paste")
			(net 307 "unconnected-(U3G-IO_L12N_T1_MRCC_AD5N_15-PadC18)")
			(pinfunction "IO_L12N_T1_MRCC_AD5N_15")
			(pintype "bidirectional+no_connect")
		)
		(pad "C19" smd circle
			(at 7.5 -8.5 270)
			(size 0.51 0.51)
			(layers "F.Cu" "F.Mask" "F.Paste")
			(net 308 "unconnected-(U3G-IO_L19P_T3_A22_15-PadC19)")
			(pinfunction "IO_L19P_T3_A22_15")
			(pintype "bidirectional+no_connect")
		)
		(pad "C20" smd circle
			(at 8.5 -8.5 270)
			(size 0.51 0.51)
			(layers "F.Cu" "F.Mask" "F.Paste")
			(net 195 "SD_CMD")
			(pinfunction "IO_L19N_T3_A21_VREF_15")
			(pintype "bidirectional")
		)
		(pad "C21" smd circle
			(at 9.5 -8.5 270)
			(size 0.51 0.51)
			(layers "F.Cu" "F.Mask" "F.Paste")
			(net 459 "3V3_SYS")
			(pinfunction "VCCO_15")
			(pintype "passive")
		)
		(pad "C22" smd circle
			(at 10.5 -8.5 270)
			(size 0.51 0.51)
			(layers "F.Cu" "F.Mask" "F.Paste")
			(net 192 "SD_DAT1")
			(pinfunction "IO_L21P_T3_DQS_15")
			(pintype "bidirectional")
		)
		(pad "D1" smd circle
			(at -10.5 -7.5 270)
			(size 0.51 0.51)
			(layers "F.Cu" "F.Mask" "F.Paste")
			(net 309 "unconnected-(U3C-MGTXTXN1_115-PadD1)")
			(pinfunction "MGTXTXN1_115")
			(pintype "bidirectional+no_connect")
		)
		(pad "D2" smd circle
			(at -9.5 -7.5 270)
			(size 0.51 0.51)
			(layers "F.Cu" "F.Mask" "F.Paste")
			(net 310 "unconnected-(U3C-MGTXTXP1_115-PadD2)")
			(pinfunction "MGTXTXP1_115")
			(pintype "bidirectional+no_connect")
		)
		(pad "D3" smd circle
			(at -8.5 -7.5 270)
			(size 0.51 0.51)
			(layers "F.Cu" "F.Mask" "F.Paste")
			(net 5 "GND")
			(pinfunction "GND")
			(pintype "passive")
		)
		(pad "D4" smd circle
			(at -7.5 -7.5 270)
			(size 0.51 0.51)
			(layers "F.Cu" "F.Mask" "F.Paste")
			(net 5 "GND")
			(pinfunction "GND")
			(pintype "passive")
		)
		(pad "D5" smd circle
			(at -6.5 -7.5 270)
			(size 0.51 0.51)
			(layers "F.Cu" "F.Mask" "F.Paste")
			(net 311 "unconnected-(U3C-MGTREFCLK0N_115-PadD5)")
			(pinfunction "MGTREFCLK0N_115")
			(pintype "bidirectional+no_connect")
		)
		(pad "D6" smd circle
			(at -5.5 -7.5 270)
			(size 0.51 0.51)
			(layers "F.Cu" "F.Mask" "F.Paste")
			(net 312 "unconnected-(U3C-MGTREFCLK0P_115-PadD6)")
			(pinfunction "MGTREFCLK0P_115")
			(pintype "bidirectional+no_connect")
		)
		(pad "D7" smd circle
			(at -4.5 -7.5 270)
			(size 0.51 0.51)
			(layers "F.Cu" "F.Mask" "F.Paste")
			(net 5 "GND")
			(pinfunction "GND")
			(pintype "passive")
		)
		(pad "D8" smd circle
			(at -3.5 -7.5 270)
			(size 0.51 0.51)
			(layers "F.Cu" "F.Mask" "F.Paste")
			(net 459 "3V3_SYS")
			(pinfunction "VCCO_16")
			(pintype "passive")
		)
		(pad "D9" smd circle
			(at -2.5 -7.5 270)
			(size 0.51 0.51)
			(layers "F.Cu" "F.Mask" "F.Paste")
			(net 61 "USR_LED4")
			(pinfunction "IO_L19P_T3_16")
			(pintype "bidirectional")
		)
		(pad "D10" smd circle
			(at -1.5 -7.5 270)
			(size 0.51 0.51)
			(layers "F.Cu" "F.Mask" "F.Paste")
			(net 313 "unconnected-(U3F-IO_L7P_T1_16-PadD10)")
			(pinfunction "IO_L7P_T1_16")
			(pintype "bidirectional+no_connect")
		)
		(pad "D11" smd circle
			(at -0.5 -7.5 270)
			(size 0.51 0.51)
			(layers "F.Cu" "F.Mask" "F.Paste")
			(net 314 "unconnected-(U3F-IO_L12N_T1_MRCC_16-PadD11)")
			(pinfunction "IO_L12N_T1_MRCC_16")
			(pintype "bidirectional+no_connect")
		)
		(pad "D12" smd circle
			(at 0.5 -7.5 270)
			(size 0.51 0.51)
			(layers "F.Cu" "F.Mask" "F.Paste")
			(net 315 "unconnected-(U3G-IO_0_15-PadD12)")
			(pinfunction "IO_0_15")
			(pintype "bidirectional+no_connect")
		)
		(pad "D13" smd circle
			(at 1.5 -7.5 270)
			(size 0.51 0.51)
			(layers "F.Cu" "F.Mask" "F.Paste")
			(net 5 "GND")
			(pinfunction "GND")
			(pintype "passive")
		)
		(pad "D14" smd circle
			(at 2.5 -7.5 270)
			(size 0.51 0.51)
			(layers "F.Cu" "F.Mask" "F.Paste")
			(net 316 "unconnected-(U3G-IO_L6N_T0_VREF_15-PadD14)")
			(pinfunction "IO_L6N_T0_VREF_15")
			(pintype "bidirectional+no_connect")
		)
		(pad "D15" smd circle
			(at 3.5 -7.5 270)
			(size 0.51 0.51)
			(layers "F.Cu" "F.Mask" "F.Paste")
			(net 317 "unconnected-(U3G-IO_L11P_T1_SRCC_AD12P_15-PadD15)")
			(pinfunction "IO_L11P_T1_SRCC_AD12P_15")
			(pintype "bidirectional+no_connect")
		)
		(pad "D16" smd circle
			(at 4.5 -7.5 270)
			(size 0.51 0.51)
			(layers "F.Cu" "F.Mask" "F.Paste")
			(net 318 "unconnected-(U3G-IO_L11N_T1_SRCC_AD12N_15-PadD16)")
			(pinfunction "IO_L11N_T1_SRCC_AD12N_15")
			(pintype "bidirectional+no_connect")
		)
		(pad "D17" smd circle
			(at 5.5 -7.5 270)
			(size 0.51 0.51)
			(layers "F.Cu" "F.Mask" "F.Paste")
			(net 319 "unconnected-(U3G-IO_L14N_T2_SRCC_15-PadD17)")
			(pinfunction "IO_L14N_T2_SRCC_15")
			(pintype "bidirectional+no_connect")
		)
		(pad "D18" smd circle
			(at 6.5 -7.5 270)
			(size 0.51 0.51)
			(layers "F.Cu" "F.Mask" "F.Paste")
			(net 459 "3V3_SYS")
			(pinfunction "VCCO_15")
			(pintype "passive")
		)
		(pad "D19" smd circle
			(at 7.5 -7.5 270)
			(size 0.51 0.51)
			(layers "F.Cu" "F.Mask" "F.Paste")
			(net 197 "SD_DAT2")
			(pinfunction "IO_L18P_T2_A24_15")
			(pintype "bidirectional")
		)
		(pad "D20" smd circle
			(at 8.5 -7.5 270)
			(size 0.51 0.51)
			(layers "F.Cu" "F.Mask" "F.Paste")
			(net 196 "SD_DAT3")
			(pinfunction "IO_L18N_T2_A23_15")
			(pintype "bidirectional")
		)
		(pad "D21" smd circle
			(at 9.5 -7.5 270)
			(size 0.51 0.51)
			(layers "F.Cu" "F.Mask" "F.Paste")
			(net 193 "SD_DAT0")
			(pinfunction "IO_L23P_T3_FOE_B_15")
			(pintype "bidirectional")
		)
		(pad "D22" smd circle
			(at 10.5 -7.5 270)
			(size 0.51 0.51)
			(layers "F.Cu" "F.Mask" "F.Paste")
			(net 194 "SD_CLK")
			(pinfunction "IO_L23N_T3_FWE_B_15")
			(pintype "bidirectional")
		)
		(pad "E1" smd circle
			(at -10.5 -6.5 270)
			(size 0.51 0.51)
			(layers "F.Cu" "F.Mask" "F.Paste")
			(net 5 "GND")
			(pinfunction "GND")
			(pintype "passive")
		)
		(pad "E2" smd circle
			(at -9.5 -6.5 270)
			(size 0.51 0.51)
			(layers "F.Cu" "F.Mask" "F.Paste")
			(net 271 "unconnected-(U3A-MGTAVTT-PadA2)")
			(pinfunction "MGTAVTT")
			(pintype "passive+no_connect")
		)
		(pad "E3" smd circle
			(at -8.5 -6.5 270)
			(size 0.51 0.51)
			(layers "F.Cu" "F.Mask" "F.Paste")
			(net 320 "unconnected-(U3C-MGTXRXN1_115-PadE3)")
			(pinfunction "MGTXRXN1_115")
			(pintype "bidirectional+no_connect")
		)
		(pad "E4" smd circle
			(at -7.5 -6.5 270)
			(size 0.51 0.51)
			(layers "F.Cu" "F.Mask" "F.Paste")
			(net 321 "unconnected-(U3C-MGTXRXP1_115-PadE4)")
			(pinfunction "MGTXRXP1_115")
			(pintype "bidirectional+no_connect")
		)
		(pad "E5" smd circle
			(at -6.5 -6.5 270)
			(size 0.51 0.51)
			(layers "F.Cu" "F.Mask" "F.Paste")
			(net 5 "GND")
			(pinfunction "GND")
			(pintype "passive")
		)
		(pad "E6" smd circle
			(at -5.5 -6.5 270)
			(size 0.51 0.51)
			(layers "F.Cu" "F.Mask" "F.Paste")
			(net 275 "unconnected-(U3A-MGTAVCC-PadA6)")
			(pinfunction "MGTAVCC")
			(pintype "passive+no_connect")
		)
		(pad "E7" smd circle
			(at -4.5 -6.5 270)
			(size 0.51 0.51)
			(layers "F.Cu" "F.Mask" "F.Paste")
			(net 5 "GND")
			(pinfunction "GND")
			(pintype "passive")
		)
		(pad "E8" smd circle
			(at -3.5 -6.5 270)
			(size 0.51 0.51)
			(layers "F.Cu" "F.Mask" "F.Paste")
			(net 390 "USR_BTN1")
			(pinfunction "IO_24_T3_16")
			(pintype "bidirectional")
		)
		(pad "E9" smd circle
			(at -2.5 -6.5 270)
			(size 0.51 0.51)
			(layers "F.Cu" "F.Mask" "F.Paste")
			(net 436 "USR_BTN4")
			(pinfunction "IO_L15N_T2_DQS_16")
			(pintype "bidirectional")
		)
		(pad "E10" smd circle
			(at -1.5 -6.5 270)
			(size 0.51 0.51)
			(layers "F.Cu" "F.Mask" "F.Paste")
			(net 5 "GND")
			(pinfunction "GND")
			(pintype "passive")
		)
		(pad "E11" smd circle
			(at -0.5 -6.5 270)
			(size 0.51 0.51)
			(layers "F.Cu" "F.Mask" "F.Paste")
			(net 322 "unconnected-(U3F-IO_L12P_T1_MRCC_16-PadE11)")
			(pinfunction "IO_L12P_T1_MRCC_16")
			(pintype "bidirectional+no_connect")
		)
		(pad "E12" smd circle
			(at 0.5 -6.5 270)
			(size 0.51 0.51)
			(layers "F.Cu" "F.Mask" "F.Paste")
			(net 323 "unconnected-(U3F-IO_L10N_T1_16-PadE12)")
			(pinfunction "IO_L10N_T1_16")
			(pintype "bidirectional+no_connect")
		)
		(pad "E13" smd circle
			(at 1.5 -6.5 270)
			(size 0.51 0.51)
			(layers "F.Cu" "F.Mask" "F.Paste")
			(net 324 "unconnected-(U3F-IO_L10P_T1_16-PadE13)")
			(pinfunction "IO_L10P_T1_16")
			(pintype "bidirectional+no_connect")
		)
		(pad "E14" smd circle
			(at 2.5 -6.5 270)
			(size 0.51 0.51)
			(layers "F.Cu" "F.Mask" "F.Paste")
			(net 325 "unconnected-(U3G-IO_L6P_T0_15-PadE14)")
			(pinfunction "IO_L6P_T0_15")
			(pintype "bidirectional+no_connect")
		)
		(pad "E15" smd circle
			(at 3.5 -6.5 270)
			(size 0.51 0.51)
			(layers "F.Cu" "F.Mask" "F.Paste")
			(net 459 "3V3_SYS")
			(pinfunction "VCCO_15")
			(pintype "passive")
		)
		(pad "E16" smd circle
			(at 4.5 -6.5 270)
			(size 0.51 0.51)
			(layers "F.Cu" "F.Mask" "F.Paste")
			(net 24 "ETH_RSTN")
			(pinfunction "IO_L14P_T2_SRCC_15")
			(pintype "bidirectional")
		)
		(pad "E17" smd circle
			(at 5.5 -6.5 270)
			(size 0.51 0.51)
			(layers "F.Cu" "F.Mask" "F.Paste")
			(net 30 "ETH_TX_CLK")
			(pinfunction "IO_L13P_T2_MRCC_15")
			(pintype "bidirectional")
		)
		(pad "E18" smd circle
			(at 6.5 -6.5 270)
			(size 0.51 0.51)
			(layers "F.Cu" "F.Mask" "F.Paste")
			(net 326 "unconnected-(U3G-IO_L13N_T2_MRCC_15-PadE18)")
			(pinfunction "IO_L13N_T2_MRCC_15")
			(pintype "bidirectional+no_connect")
		)
		(pad "E19" smd circle
			(at 7.5 -6.5 270)
			(size 0.51 0.51)
			(layers "F.Cu" "F.Mask" "F.Paste")
			(net 327 "unconnected-(U3G-IO_L17N_T2_A25_15-PadE19)")
			(pinfunction "IO_L17N_T2_A25_15")
			(pintype "bidirectional+no_connect")
		)
		(pad "E20" smd circle
			(at 8.5 -6.5 270)
			(size 0.51 0.51)
			(layers "F.Cu" "F.Mask" "F.Paste")
			(net 5 "GND")
			(pinfunction "GND")
			(pintype "passive")
		)
		(pad "E21" smd circle
			(at 9.5 -6.5 270)
			(size 0.51 0.51)
			(layers "F.Cu" "F.Mask" "F.Paste")
			(net 328 "unconnected-(U3H-IO_L7P_T1_D09_14-PadE21)")
			(pinfunction "IO_L7P_T1_D09_14")
			(pintype "bidirectional+no_connect")
		)
		(pad "E22" smd circle
			(at 10.5 -6.5 270)
			(size 0.51 0.51)
			(layers "F.Cu" "F.Mask" "F.Paste")
			(net 329 "unconnected-(U3H-IO_L7N_T1_D10_14-PadE22)")
			(pinfunction "IO_L7N_T1_D10_14")
			(pintype "bidirectional+no_connect")
		)
		(pad "F1" smd circle
			(at -10.5 -5.5 270)
			(size 0.51 0.51)
			(layers "F.Cu" "F.Mask" "F.Paste")
			(net 330 "unconnected-(U3C-MGTXTXN0_115-PadF1)")
			(pinfunction "MGTXTXN0_115")
			(pintype "bidirectional+no_connect")
		)
		(pad "F2" smd circle
			(at -9.5 -5.5 270)
			(size 0.51 0.51)
			(layers "F.Cu" "F.Mask" "F.Paste")
			(net 331 "unconnected-(U3C-MGTXTXP0_115-PadF2)")
			(pinfunction "MGTXTXP0_115")
			(pintype "bidirectional+no_connect")
		)
		(pad "F3" smd circle
			(at -8.5 -5.5 270)
			(size 0.51 0.51)
			(layers "F.Cu" "F.Mask" "F.Paste")
			(net 5 "GND")
			(pinfunction "GND")
			(pintype "passive")
		)
		(pad "F4" smd circle
			(at -7.5 -5.5 270)
			(size 0.51 0.51)
			(layers "F.Cu" "F.Mask" "F.Paste")
			(net 5 "GND")
			(pinfunction "GND")
			(pintype "passive")
		)
		(pad "F5" smd circle
			(at -6.5 -5.5 270)
			(size 0.51 0.51)
			(layers "F.Cu" "F.Mask" "F.Paste")
			(net 337 "unconnected-(U3C-MGTREFCLK1N_115-PadF5)")
			(pinfunction "MGTREFCLK1N_115")
			(pintype "bidirectional+no_connect")
		)
		(pad "F6" smd circle
			(at -5.5 -5.5 270)
			(size 0.51 0.51)
			(layers "F.Cu" "F.Mask" "F.Paste")
			(net 342 "unconnected-(U3C-MGTREFCLK1P_115-PadF6)")
			(pinfunction "MGTREFCLK1P_115")
			(pintype "bidirectional+no_connect")
		)
		(pad "F7" smd circle
			(at -4.5 -5.5 270)
			(size 0.51 0.51)
			(layers "F.Cu" "F.Mask" "F.Paste")
			(net 5 "GND")
			(pinfunction "GND")
			(pintype "passive")
		)
		(pad "F8" smd circle
			(at -3.5 -5.5 270)
			(size 0.51 0.51)
			(layers "F.Cu" "F.Mask" "F.Paste")
			(net 56 "USR_LED1")
			(pinfunction "IO_L17N_T2_16")
			(pintype "bidirectional")
		)
		(pad "F9" smd circle
			(at -2.5 -5.5 270)
			(size 0.51 0.51)
			(layers "F.Cu" "F.Mask" "F.Paste")
			(net 63 "USR_LED5")
			(pinfunction "IO_L15P_T2_DQS_16")
			(pintype "bidirectional")
		)
		(pad "F10" smd circle
			(at -1.5 -5.5 270)
			(size 0.51 0.51)
			(layers "F.Cu" "F.Mask" "F.Paste")
			(net 354 "unconnected-(U3F-IO_L11N_T1_SRCC_16-PadF10)")
			(pinfunction "IO_L11N_T1_SRCC_16")
			(pintype "bidirectional+no_connect")
		)
		(pad "F11" smd circle
			(at -0.5 -5.5 270)
			(size 0.51 0.51)
			(layers "F.Cu" "F.Mask" "F.Paste")
			(net 355 "unconnected-(U3F-IO_L11P_T1_SRCC_16-PadF11)")
			(pinfunction "IO_L11P_T1_SRCC_16")
			(pintype "bidirectional+no_connect")
		)
		(pad "F12" smd circle
			(at 0.5 -5.5 270)
			(size 0.51 0.51)
			(layers "F.Cu" "F.Mask" "F.Paste")
			(net 459 "3V3_SYS")
			(pinfunction "VCCO_16")
			(pintype "passive")
		)
		(pad "F13" smd circle
			(at 1.5 -5.5 270)
			(size 0.51 0.51)
			(layers "F.Cu" "F.Mask" "F.Paste")
			(net 356 "unconnected-(U3F-IO_L8N_T1_16-PadF13)")
			(pinfunction "IO_L8N_T1_16")
			(pintype "bidirectional+no_connect")
		)
		(pad "F14" smd circle
			(at 2.5 -5.5 270)
			(size 0.51 0.51)
			(layers "F.Cu" "F.Mask" "F.Paste")
			(net 357 "unconnected-(U3F-IO_6_T0_VREF_16-PadF14)")
			(pinfunction "IO_6_T0_VREF_16")
			(pintype "bidirectional+no_connect")
		)
		(pad "F15" smd circle
			(at 3.5 -5.5 270)
			(size 0.51 0.51)
			(layers "F.Cu" "F.Mask" "F.Paste")
			(net 358 "unconnected-(U3G-IO_L3P_T0_DQS_AD1P_15-PadF15)")
			(pinfunction "IO_L3P_T0_DQS_AD1P_15")
			(pintype "bidirectional+no_connect")
		)
		(pad "F16" smd circle
			(at 4.5 -5.5 270)
			(size 0.51 0.51)
			(layers "F.Cu" "F.Mask" "F.Paste")
			(net 359 "unconnected-(U3G-IO_L3N_T0_DQS_AD1N_15-PadF16)")
			(pinfunction "IO_L3N_T0_DQS_AD1N_15")
			(pintype "bidirectional+no_connect")
		)
		(pad "F17" smd circle
			(at 5.5 -5.5 270)
			(size 0.51 0.51)
			(layers "F.Cu" "F.Mask" "F.Paste")
			(net 5 "GND")
			(pinfunction "GND")
			(pintype "passive")
		)
		(pad "F18" smd circle
			(at 6.5 -5.5 270)
			(size 0.51 0.51)
			(layers "F.Cu" "F.Mask" "F.Paste")
			(net 360 "unconnected-(U3G-IO_L17P_T2_A26_15-PadF18)")
			(pinfunction "IO_L17P_T2_A26_15")
			(pintype "bidirectional+no_connect")
		)
		(pad "F19" smd circle
			(at 7.5 -5.5 270)
			(size 0.51 0.51)
			(layers "F.Cu" "F.Mask" "F.Paste")
			(net 18 "QSPI_DQ3")
			(pinfunction "IO_L2N_T0_D03_14")
			(pintype "bidirectional")
		)
		(pad "F20" smd circle
			(at 8.5 -5.5 270)
			(size 0.51 0.51)
			(layers "F.Cu" "F.Mask" "F.Paste")
			(net 361 "unconnected-(U3H-IO_L4N_T0_D05_14-PadF20)")
			(pinfunction "IO_L4N_T0_D05_14")
			(pintype "bidirectional+no_connect")
		)
		(pad "F21" smd circle
			(at 9.5 -5.5 270)
			(size 0.51 0.51)
			(layers "F.Cu" "F.Mask" "F.Paste")
			(net 362 "unconnected-(U3H-IO_L9N_T1_DQS_D13_14-PadF21)")
			(pinfunction "IO_L9N_T1_DQS_D13_14")
			(pintype "bidirectional+no_connect")
		)
		(pad "F22" smd circle
			(at 10.5 -5.5 270)
			(size 0.51 0.51)
			(layers "F.Cu" "F.Mask" "F.Paste")
			(net 459 "3V3_SYS")
			(pinfunction "VCCO_14")
			(pintype "power_in")
		)
		(pad "G1" smd circle
			(at -10.5 -4.5 270)
			(size 0.51 0.51)
			(layers "F.Cu" "F.Mask" "F.Paste")
			(net 5 "GND")
			(pinfunction "GND")
			(pintype "passive")
		)
		(pad "G2" smd circle
			(at -9.5 -4.5 270)
			(size 0.51 0.51)
			(layers "F.Cu" "F.Mask" "F.Paste")
			(net 271 "unconnected-(U3A-MGTAVTT-PadA2)")
			(pinfunction "MGTAVTT")
			(pintype "passive+no_connect")
		)
		(pad "G3" smd circle
			(at -8.5 -4.5 270)
			(size 0.51 0.51)
			(layers "F.Cu" "F.Mask" "F.Paste")
			(net 363 "unconnected-(U3C-MGTXRXN0_115-PadG3)")
			(pinfunction "MGTXRXN0_115")
			(pintype "bidirectional+no_connect")
		)
		(pad "G4" smd circle
			(at -7.5 -4.5 270)
			(size 0.51 0.51)
			(layers "F.Cu" "F.Mask" "F.Paste")
			(net 364 "unconnected-(U3C-MGTXRXP0_115-PadG4)")
			(pinfunction "MGTXRXP0_115")
			(pintype "bidirectional+no_connect")
		)
		(pad "G5" smd circle
			(at -6.5 -4.5 270)
			(size 0.51 0.51)
			(layers "F.Cu" "F.Mask" "F.Paste")
			(net 5 "GND")
			(pinfunction "GND")
			(pintype "passive")
		)
		(pad "G6" smd circle
			(at -5.5 -4.5 270)
			(size 0.51 0.51)
			(layers "F.Cu" "F.Mask" "F.Paste")
			(net 275 "unconnected-(U3A-MGTAVCC-PadA6)")
			(pinfunction "MGTAVCC")
			(pintype "passive+no_connect")
		)
		(pad "G7" smd circle
			(at -4.5 -4.5 270)
			(size 0.51 0.51)
			(layers "F.Cu" "F.Mask" "F.Paste")
			(net 213 "CCLK")
			(pinfunction "CCLK_0")
			(pintype "bidirectional")
		)
		(pad "G8" smd circle
			(at -3.5 -4.5 270)
			(size 0.51 0.51)
			(layers "F.Cu" "F.Mask" "F.Paste")
			(net 365 "unconnected-(U3F-IO_L17P_T2_16-PadG8)")
			(pinfunction "IO_L17P_T2_16")
			(pintype "bidirectional+no_connect")
		)
		(pad "G9" smd circle
			(at -2.5 -4.5 270)
			(size 0.51 0.51)
			(layers "F.Cu" "F.Mask" "F.Paste")
			(net 459 "3V3_SYS")
			(pinfunction "VCCO_16")
			(pintype "passive")
		)
		(pad "G10" smd circle
			(at -1.5 -4.5 270)
			(size 0.51 0.51)
			(layers "F.Cu" "F.Mask" "F.Paste")
			(net 366 "unconnected-(U3F-IO_L13N_T2_MRCC_16-PadG10)")
			(pinfunction "IO_L13N_T2_MRCC_16")
			(pintype "bidirectional+no_connect")
		)
		(pad "G11" smd circle
			(at -0.5 -4.5 270)
			(size 0.51 0.51)
			(layers "F.Cu" "F.Mask" "F.Paste")
			(net 367 "unconnected-(U3F-IO_L13P_T2_MRCC_16-PadG11)")
			(pinfunction "IO_L13P_T2_MRCC_16")
			(pintype "bidirectional+no_connect")
		)
		(pad "G12" smd circle
			(at 0.5 -4.5 270)
			(size 0.51 0.51)
			(layers "F.Cu" "F.Mask" "F.Paste")
			(net 368 "unconnected-(U3F-IO_L14N_T2_SRCC_16-PadG12)")
			(pinfunction "IO_L14N_T2_SRCC_16")
			(pintype "bidirectional+no_connect")
		)
		(pad "G13" smd circle
			(at 1.5 -4.5 270)
			(size 0.51 0.51)
			(layers "F.Cu" "F.Mask" "F.Paste")
			(net 369 "unconnected-(U3F-IO_L8P_T1_16-PadG13)")
			(pinfunction "IO_L8P_T1_16")
			(pintype "bidirectional+no_connect")
		)
		(pad "G14" smd circle
			(at 2.5 -4.5 270)
			(size 0.51 0.51)
			(layers "F.Cu" "F.Mask" "F.Paste")
			(net 5 "GND")
			(pinfunction "GND")
			(pintype "passive")
		)
		(pad "G15" smd circle
			(at 3.5 -4.5 270)
			(size 0.51 0.51)
			(layers "F.Cu" "F.Mask" "F.Paste")
			(net 370 "unconnected-(U3G-IO_L1P_T0_AD0P_15-PadG15)")
			(pinfunction "IO_L1P_T0_AD0P_15")
			(pintype "bidirectional+no_connect")
		)
		(pad "G16" smd circle
			(at 4.5 -4.5 270)
			(size 0.51 0.51)
			(layers "F.Cu" "F.Mask" "F.Paste")
			(net 371 "unconnected-(U3G-IO_L1N_T0_AD0N_15-PadG16)")
			(pinfunction "IO_L1N_T0_AD0N_15")
			(pintype "bidirectional+no_connect")
		)
		(pad "G17" smd circle
			(at 5.5 -4.5 270)
			(size 0.51 0.51)
			(layers "F.Cu" "F.Mask" "F.Paste")
			(net 372 "unconnected-(U3G-IO_L15N_T2_DQS_ADV_B_15-PadG17)")
			(pinfunction "IO_L15N_T2_DQS_ADV_B_15")
			(pintype "bidirectional+no_connect")
		)
		(pad "G18" smd circle
			(at 6.5 -4.5 270)
			(size 0.51 0.51)
			(layers "F.Cu" "F.Mask" "F.Paste")
			(net 17 "QSPI_DQ2")
			(pinfunction "IO_L2P_T0_D02_14")
			(pintype "bidirectional")
		)
		(pad "G19" smd circle
			(at 7.5 -4.5 270)
			(size 0.51 0.51)
			(layers "F.Cu" "F.Mask" "F.Paste")
			(net 459 "3V3_SYS")
			(pinfunction "VCCO_14")
			(pintype "passive")
		)
		(pad "G20" smd circle
			(at 8.5 -4.5 270)
			(size 0.51 0.51)
			(layers "F.Cu" "F.Mask" "F.Paste")
			(net 373 "unconnected-(U3H-IO_L4P_T0_D04_14-PadG20)")
			(pinfunction "IO_L4P_T0_D04_14")
			(pintype "bidirectional+no_connect")
		)
		(pad "G21" smd circle
			(at 9.5 -4.5 270)
			(size 0.51 0.51)
			(layers "F.Cu" "F.Mask" "F.Paste")
			(net 374 "unconnected-(U3H-IO_L9P_T1_DQS_14-PadG21)")
			(pinfunction "IO_L9P_T1_DQS_14")
			(pintype "bidirectional+no_connect")
		)
		(pad "G22" smd circle
			(at 10.5 -4.5 270)
			(size 0.51 0.51)
			(layers "F.Cu" "F.Mask" "F.Paste")
			(net 375 "unconnected-(U3H-IO_L8N_T1_D12_14-PadG22)")
			(pinfunction "IO_L8N_T1_D12_14")
			(pintype "bidirectional+no_connect")
		)
		(pad "H1" smd circle
			(at -10.5 -3.5 270)
			(size 0.51 0.51)
			(layers "F.Cu" "F.Mask" "F.Paste")
			(net 376 "unconnected-(U3A-MGTAVTTRCAL_115-PadH1)")
			(pinfunction "MGTAVTTRCAL_115")
			(pintype "power_in+no_connect")
		)
		(pad "H2" smd circle
			(at -9.5 -3.5 270)
			(size 0.51 0.51)
			(layers "F.Cu" "F.Mask" "F.Paste")
			(net 377 "unconnected-(U3A-MGTRREF_115-PadH2)")
			(pinfunction "MGTRREF_115")
			(pintype "power_in+no_connect")
		)
		(pad "H3" smd circle
			(at -8.5 -3.5 270)
			(size 0.51 0.51)
			(layers "F.Cu" "F.Mask" "F.Paste")
			(net 5 "GND")
			(pinfunction "GND")
			(pintype "passive")
		)
		(pad "H4" smd circle
			(at -7.5 -3.5 270)
			(size 0.51 0.51)
			(layers "F.Cu" "F.Mask" "F.Paste")
			(net 5 "GND")
			(pinfunction "GND")
			(pintype "passive")
		)
		(pad "H5" smd circle
			(at -6.5 -3.5 270)
			(size 0.51 0.51)
			(layers "F.Cu" "F.Mask" "F.Paste")
			(net 5 "GND")
			(pinfunction "GND")
			(pintype "passive")
		)
		(pad "H6" smd circle
			(at -5.5 -3.5 270)
			(size 0.51 0.51)
			(layers "F.Cu" "F.Mask" "F.Paste")
			(net 20 "MODE1")
			(pinfunction "M1_0")
			(pintype "bidirectional")
		)
		(pad "H7" smd circle
			(at -4.5 -3.5 270)
			(size 0.51 0.51)
			(layers "F.Cu" "F.Mask" "F.Paste")
			(net 19 "MODE0")
			(pinfunction "M0_0")
			(pintype "bidirectional")
		)
		(pad "H8" smd circle
			(at -3.5 -3.5 270)
			(size 0.51 0.51)
			(layers "F.Cu" "F.Mask" "F.Paste")
			(net 378 "unconnected-(U3F-IO_L16N_T2_16-PadH8)")
			(pinfunction "IO_L16N_T2_16")
			(pintype "bidirectional+no_connect")
		)
		(pad "H9" smd circle
			(at -2.5 -3.5 270)
			(size 0.51 0.51)
			(layers "F.Cu" "F.Mask" "F.Paste")
			(net 379 "unconnected-(U3F-IO_L16P_T2_16-PadH9)")
			(pinfunction "IO_L16P_T2_16")
			(pintype "bidirectional+no_connect")
		)
		(pad "H10" smd circle
			(at -1.5 -3.5 270)
			(size 0.51 0.51)
			(layers "F.Cu" "F.Mask" "F.Paste")
			(net 380 "unconnected-(U3F-IO_18_T2_16-PadH10)")
			(pinfunction "IO_18_T2_16")
			(pintype "bidirectional+no_connect")
		)
		(pad "H11" smd circle
			(at -0.5 -3.5 270)
			(size 0.51 0.51)
			(layers "F.Cu" "F.Mask" "F.Paste")
			(net 5 "GND")
			(pinfunction "GND")
			(pintype "passive")
		)
		(pad "H12" smd circle
			(at 0.5 -3.5 270)
			(size 0.51 0.51)
			(layers "F.Cu" "F.Mask" "F.Paste")
			(net 381 "unconnected-(U3F-IO_L14P_T2_SRCC_16-PadH12)")
			(pinfunction "IO_L14P_T2_SRCC_16")
			(pintype "bidirectional+no_connect")
		)
		(pad "H13" smd circle
			(at 1.5 -3.5 270)
			(size 0.51 0.51)
			(layers "F.Cu" "F.Mask" "F.Paste")
			(net 382 "unconnected-(U3F-IO_L9N_T1_DQS_16-PadH13)")
			(pinfunction "IO_L9N_T1_DQS_16")
			(pintype "bidirectional+no_connect")
		)
		(pad "H14" smd circle
			(at 2.5 -3.5 270)
			(size 0.51 0.51)
			(layers "F.Cu" "F.Mask" "F.Paste")
			(net 383 "unconnected-(U3F-IO_L9P_T1_DQS_16-PadH14)")
			(pinfunction "IO_L9P_T1_DQS_16")
			(pintype "bidirectional+no_connect")
		)
		(pad "H15" smd circle
			(at 3.5 -3.5 270)
			(size 0.51 0.51)
			(layers "F.Cu" "F.Mask" "F.Paste")
			(net 384 "unconnected-(U3G-IO_25_15-PadH15)")
			(pinfunction "IO_25_15")
			(pintype "bidirectional+no_connect")
		)
		(pad "H16" smd circle
			(at 4.5 -3.5 270)
			(size 0.51 0.51)
			(layers "F.Cu" "F.Mask" "F.Paste")
			(net 459 "3V3_SYS")
			(pinfunction "VCCO_15")
			(pintype "passive")
		)
		(pad "H17" smd circle
			(at 5.5 -3.5 270)
			(size 0.51 0.51)
			(layers "F.Cu" "F.Mask" "F.Paste")
			(net 385 "unconnected-(U3G-IO_L15P_T2_DQS_15-PadH17)")
			(pinfunction "IO_L15P_T2_DQS_15")
			(pintype "bidirectional+no_connect")
		)
		(pad "H18" smd circle
			(at 6.5 -3.5 270)
			(size 0.51 0.51)
			(layers "F.Cu" "F.Mask" "F.Paste")
			(net 15 "QSPI_DQ0")
			(pinfunction "IO_L1P_T0_D00_MOSI_14")
			(pintype "bidirectional")
		)
		(pad "H19" smd circle
			(at 7.5 -3.5 270)
			(size 0.51 0.51)
			(layers "F.Cu" "F.Mask" "F.Paste")
			(net 16 "QSPI_DQ1")
			(pinfunction "IO_L1N_T0_D01_DIN_14")
			(pintype "bidirectional")
		)
		(pad "H20" smd circle
			(at 8.5 -3.5 270)
			(size 0.51 0.51)
			(layers "F.Cu" "F.Mask" "F.Paste")
			(net 386 "unconnected-(U3H-IO_L11N_T1_SRCC_14-PadH20)")
			(pinfunction "IO_L11N_T1_SRCC_14")
			(pintype "bidirectional+no_connect")
		)
		(pad "H21" smd circle
			(at 9.5 -3.5 270)
			(size 0.51 0.51)
			(layers "F.Cu" "F.Mask" "F.Paste")
			(net 5 "GND")
			(pinfunction "GND")
			(pintype "passive")
		)
		(pad "H22" smd circle
			(at 10.5 -3.5 270)
			(size 0.51 0.51)
			(layers "F.Cu" "F.Mask" "F.Paste")
			(net 387 "unconnected-(U3H-IO_L8P_T1_D11_14-PadH22)")
			(pinfunction "IO_L8P_T1_D11_14")
			(pintype "bidirectional+no_connect")
		)
		(pad "J1" smd circle
			(at -10.5 -2.5 270)
			(size 0.51 0.51)
			(layers "F.Cu" "F.Mask" "F.Paste")
			(net 5 "GND")
			(pinfunction "GND")
			(pintype "passive")
		)
		(pad "J2" smd circle
			(at -9.5 -2.5 270)
			(size 0.51 0.51)
			(layers "F.Cu" "F.Mask" "F.Paste")
			(net 5 "GND")
			(pinfunction "GND")
			(pintype "passive")
		)
		(pad "J3" smd circle
			(at -8.5 -2.5 270)
			(size 0.51 0.51)
			(layers "F.Cu" "F.Mask" "F.Paste")
			(net 5 "GND")
			(pinfunction "GND")
			(pintype "passive")
		)
		(pad "J4" smd circle
			(at -7.5 -2.5 270)
			(size 0.51 0.51)
			(layers "F.Cu" "F.Mask" "F.Paste")
			(net 388 "unconnected-(U3A-MGTVCCAUX-PadJ4)")
			(pinfunction "MGTVCCAUX")
			(pintype "power_in+no_connect")
		)
		(pad "J5" smd circle
			(at -6.5 -2.5 270)
			(size 0.51 0.51)
			(layers "F.Cu" "F.Mask" "F.Paste")
			(net 14 "MODE2")
			(pinfunction "M2_0")
			(pintype "bidirectional")
		)
		(pad "J6" smd circle
			(at -5.5 -2.5 270)
			(size 0.51 0.51)
			(layers "F.Cu" "F.Mask" "F.Paste")
			(net 11 "TDO_JTAG")
			(pinfunction "TDO_0")
			(pintype "bidirectional")
		)
		(pad "J7" smd circle
			(at -4.5 -2.5 270)
			(size 0.51 0.51)
			(layers "F.Cu" "F.Mask" "F.Paste")
			(net 459 "3V3_SYS")
			(pinfunction "VCCO_0")
			(pintype "power_in")
		)
		(pad "J8" smd circle
			(at -3.5 -2.5 270)
			(size 0.51 0.51)
			(layers "F.Cu" "F.Mask" "F.Paste")
			(net 5 "GND")
			(pinfunction "GND")
			(pintype "passive")
		)
		(pad "J9" smd circle
			(at -2.5 -2.5 270)
			(size 0.51 0.51)
			(layers "F.Cu" "F.Mask" "F.Paste")
			(net 465 "1V0_SYS")
			(pinfunction "VCCINT")
			(pintype "passive")
		)
		(pad "J10" smd circle
			(at -1.5 -2.5 270)
			(size 0.51 0.51)
			(layers "F.Cu" "F.Mask" "F.Paste")
			(net 5 "GND")
			(pinfunction "GND")
			(pintype "passive")
		)
		(pad "J11" smd circle
			(at -0.5 -2.5 270)
			(size 0.51 0.51)
			(layers "F.Cu" "F.Mask" "F.Paste")
			(net 465 "1V0_SYS")
			(pinfunction "VCCINT")
			(pintype "power_in")
		)
		(pad "J12" smd circle
			(at 0.5 -2.5 270)
			(size 0.51 0.51)
			(layers "F.Cu" "F.Mask" "F.Paste")
			(net 5 "GND")
			(pinfunction "GND")
			(pintype "passive")
		)
		(pad "J13" smd circle
			(at 1.5 -2.5 270)
			(size 0.51 0.51)
			(layers "F.Cu" "F.Mask" "F.Paste")
			(net 465 "1V0_SYS")
			(pinfunction "VCCINT")
			(pintype "passive")
		)
		(pad "J14" smd circle
			(at 2.5 -2.5 270)
			(size 0.51 0.51)
			(layers "F.Cu" "F.Mask" "F.Paste")
			(net 5 "GND")
			(pinfunction "GND")
			(pintype "passive")
		)
		(pad "J15" smd circle
			(at 3.5 -2.5 270)
			(size 0.51 0.51)
			(layers "F.Cu" "F.Mask" "F.Paste")
			(net 465 "1V0_SYS")
			(pinfunction "VCCINT")
			(pintype "passive")
		)
		(pad "J16" smd circle
			(at 4.5 -2.5 270)
			(size 0.51 0.51)
			(layers "F.Cu" "F.Mask" "F.Paste")
			(net 389 "unconnected-(U3G-IO_L16P_T2_A28_15-PadJ16)")
			(pinfunction "IO_L16P_T2_A28_15")
			(pintype "bidirectional+no_connect")
		)
		(pad "J17" smd circle
			(at 5.5 -2.5 270)
			(size 0.51 0.51)
			(layers "F.Cu" "F.Mask" "F.Paste")
			(net 408 "unconnected-(U3G-IO_L16N_T2_A27_15-PadJ17)")
			(pinfunction "IO_L16N_T2_A27_15")
			(pintype "bidirectional+no_connect")
		)
		(pad "J18" smd circle
			(at 6.5 -2.5 270)
			(size 0.51 0.51)
			(layers "F.Cu" "F.Mask" "F.Paste")
			(net 5 "GND")
			(pinfunction "GND")
			(pintype "passive")
		)
		(pad "J19" smd circle
			(at 7.5 -2.5 270)
			(size 0.51 0.51)
			(layers "F.Cu" "F.Mask" "F.Paste")
			(net 217 "EMCCLK")
			(pinfunction "IO_L3N_T0_DQS_EMCCLK_14")
			(pintype "bidirectional")
		)
		(pad "J20" smd circle
			(at 8.5 -2.5 270)
			(size 0.51 0.51)
			(layers "F.Cu" "F.Mask" "F.Paste")
			(net 409 "unconnected-(U3H-IO_L11P_T1_SRCC_14-PadJ20)")
			(pinfunction "IO_L11P_T1_SRCC_14")
			(pintype "bidirectional+no_connect")
		)
		(pad "J21" smd circle
			(at 9.5 -2.5 270)
			(size 0.51 0.51)
			(layers "F.Cu" "F.Mask" "F.Paste")
			(net 50 "TMDS_D2_P")
			(pinfunction "IO_L10P_T1_D14_14")
			(pintype "bidirectional")
		)
		(pad "J22" smd circle
			(at 10.5 -2.5 270)
			(size 0.51 0.51)
			(layers "F.Cu" "F.Mask" "F.Paste")
			(net 51 "TMDS_D2_N")
			(pinfunction "IO_L10N_T1_D15_14")
			(pintype "bidirectional")
		)
		(pad "K1" smd circle
			(at -10.5 -1.5 270)
			(size 0.51 0.51)
			(layers "F.Cu" "F.Mask" "F.Paste")
			(net 349 "DQ02_A")
			(pinfunction "IO_L2P_T0_34")
			(pintype "bidirectional")
		)
		(pad "K2" smd circle
			(at -9.5 -1.5 270)
			(size 0.51 0.51)
			(layers "F.Cu" "F.Mask" "F.Paste")
			(net 350 "DQ01_A")
			(pinfunction "IO_L4N_T0_34")
			(pintype "bidirectional")
		)
		(pad "K3" smd circle
			(at -8.5 -1.5 270)
			(size 0.51 0.51)
			(layers "F.Cu" "F.Mask" "F.Paste")
			(net 348 "DQ03_A")
			(pinfunction "IO_L4P_T0_34")
			(pintype "bidirectional")
		)
		(pad "K4" smd circle
			(at -7.5 -1.5 270)
			(size 0.51 0.51)
			(layers "F.Cu" "F.Mask" "F.Paste")
			(net 511 "VRN")
			(pinfunction "IO_0_VRN_34")
			(pintype "bidirectional")
		)
		(pad "K5" smd circle
			(at -6.5 -1.5 270)
			(size 0.51 0.51)
			(layers "F.Cu" "F.Mask" "F.Paste")
			(net 5 "GND")
			(pinfunction "GND")
			(pintype "passive")
		)
		(pad "K6" smd circle
			(at -5.5 -1.5 270)
			(size 0.51 0.51)
			(layers "F.Cu" "F.Mask" "F.Paste")
			(net 10 "TDI_JTAG")
			(pinfunction "TDI_0")
			(pintype "bidirectional")
		)
		(pad "K7" smd circle
			(at -4.5 -1.5 270)
			(size 0.51 0.51)
			(layers "F.Cu" "F.Mask" "F.Paste")
			(net 8 "TCK_JTAG")
			(pinfunction "TCK_0")
			(pintype "bidirectional")
		)
		(pad "K8" smd circle
			(at -3.5 -1.5 270)
			(size 0.51 0.51)
			(layers "F.Cu" "F.Mask" "F.Paste")
			(net 465 "1V0_SYS")
			(pinfunction "VCCINT")
			(pintype "passive")
		)
		(pad "K9" smd circle
			(at -2.5 -1.5 270)
			(size 0.51 0.51)
			(layers "F.Cu" "F.Mask" "F.Paste")
			(net 5 "GND")
			(pinfunction "GND")
			(pintype "passive")
		)
		(pad "K10" smd circle
			(at -1.5 -1.5 270)
			(size 0.51 0.51)
			(layers "F.Cu" "F.Mask" "F.Paste")
			(net 460 "1V8_SYS")
			(pinfunction "VCCAUX")
			(pintype "power_in")
		)
		(pad "K11" smd circle
			(at -0.5 -1.5 270)
			(size 0.51 0.51)
			(layers "F.Cu" "F.Mask" "F.Paste")
			(net 5 "GND")
			(pinfunction "GNDADC_0")
			(pintype "power_in")
		)
		(pad "K12" smd circle
			(at 0.5 -1.5 270)
			(size 0.51 0.51)
			(layers "F.Cu" "F.Mask" "F.Paste")
			(net 460 "1V8_SYS")
			(pinfunction "VCCADC_0")
			(pintype "power_in")
		)
		(pad "K13" smd circle
			(at 1.5 -1.5 270)
			(size 0.51 0.51)
			(layers "F.Cu" "F.Mask" "F.Paste")
			(net 5 "GND")
			(pinfunction "GND")
			(pintype "passive")
		)
		(pad "K14" smd circle
			(at 2.5 -1.5 270)
			(size 0.51 0.51)
			(layers "F.Cu" "F.Mask" "F.Paste")
			(net 465 "1V0_SYS")
			(pinfunction "VCCINT")
			(pintype "passive")
		)
		(pad "K15" smd circle
			(at 3.5 -1.5 270)
			(size 0.51 0.51)
			(layers "F.Cu" "F.Mask" "F.Paste")
			(net 5 "GND")
			(pinfunction "GND")
			(pintype "passive")
		)
		(pad "K16" smd circle
			(at 4.5 -1.5 270)
			(size 0.51 0.51)
			(layers "F.Cu" "F.Mask" "F.Paste")
			(net 410 "unconnected-(U3H-IO_0_14-PadK16)")
			(pinfunction "IO_0_14")
			(pintype "bidirectional+no_connect")
		)
		(pad "K17" smd circle
			(at 5.5 -1.5 270)
			(size 0.51 0.51)
			(layers "F.Cu" "F.Mask" "F.Paste")
			(net 411 "unconnected-(U3H-IO_L6N_T0_D08_VREF_14-PadK17)")
			(pinfunction "IO_L6N_T0_D08_VREF_14")
			(pintype "bidirectional+no_connect")
		)
		(pad "K18" smd circle
			(at 6.5 -1.5 270)
			(size 0.51 0.51)
			(layers "F.Cu" "F.Mask" "F.Paste")
			(net 95 "PUDC_B")
			(pinfunction "IO_L3P_T0_DQS_PUDC_B_14")
			(pintype "bidirectional")
		)
		(pad "K19" smd circle
			(at 7.5 -1.5 270)
			(size 0.51 0.51)
			(layers "F.Cu" "F.Mask" "F.Paste")
			(net 412 "unconnected-(U3H-IO_L5N_T0_D07_14-PadK19)")
			(pinfunction "IO_L5N_T0_D07_14")
			(pintype "bidirectional+no_connect")
		)
		(pad "K20" smd circle
			(at 8.5 -1.5 270)
			(size 0.51 0.51)
			(layers "F.Cu" "F.Mask" "F.Paste")
			(net 459 "3V3_SYS")
			(pinfunction "VCCO_14")
			(pintype "passive")
		)
		(pad "K21" smd circle
			(at 9.5 -1.5 270)
			(size 0.51 0.51)
			(layers "F.Cu" "F.Mask" "F.Paste")
			(net 48 "TMDS_D1_P")
			(pinfunction "IO_L16P_T2_CSI_B_14")
			(pintype "bidirectional")
		)
		(pad "K22" smd circle
			(at 10.5 -1.5 270)
			(size 0.51 0.51)
			(layers "F.Cu" "F.Mask" "F.Paste")
			(net 49 "TMDS_D1_N")
			(pinfunction "IO_L16N_T2_A15_D31_14")
			(pintype "bidirectional")
		)
		(pad "L1" smd circle
			(at -10.5 -0.5 270)
			(size 0.51 0.51)
			(layers "F.Cu" "F.Mask" "F.Paste")
			(net 351 "DQ00_A")
			(pinfunction "IO_L2N_T0_34")
			(pintype "bidirectional")
		)
		(pad "L2" smd circle
			(at -9.5 -0.5 270)
			(size 0.51 0.51)
			(layers "F.Cu" "F.Mask" "F.Paste")
			(net 5 "GND")
			(pinfunction "GND")
			(pintype "passive")
		)
		(pad "L3" smd circle
			(at -8.5 -0.5 270)
			(size 0.51 0.51)
			(layers "F.Cu" "F.Mask" "F.Paste")
			(net 394 "CA_0A")
			(pinfunction "IO_L1P_T0_34")
			(pintype "bidirectional")
		)
		(pad "L4" smd circle
			(at -7.5 -0.5 270)
			(size 0.51 0.51)
			(layers "F.Cu" "F.Mask" "F.Paste")
			(net 510 "VREF_34")
			(pinfunction "IO_L6N_T0_VREF_34")
			(pintype "bidirectional")
		)
		(pad "L5" smd circle
			(at -6.5 -0.5 270)
			(size 0.51 0.51)
			(layers "F.Cu" "F.Mask" "F.Paste")
			(net 393 "CA_1A")
			(pinfunction "IO_L6P_T0_34")
			(pintype "bidirectional")
		)
		(pad "L6" smd circle
			(at -5.5 -0.5 270)
			(size 0.51 0.51)
			(layers "F.Cu" "F.Mask" "F.Paste")
			(net 9 "TMS_JTAG")
			(pinfunction "TMS_0")
			(pintype "bidirectional")
		)
		(pad "L7" smd circle
			(at -4.5 -0.5 270)
			(size 0.51 0.51)
			(layers "F.Cu" "F.Mask" "F.Paste")
			(net 210 "INIT_B")
			(pinfunction "INIT_B_0")
			(pintype "bidirectional")
		)
		(pad "L8" smd circle
			(at -3.5 -0.5 270)
			(size 0.51 0.51)
			(layers "F.Cu" "F.Mask" "F.Paste")
			(net 5 "GND")
			(pinfunction "GND")
			(pintype "passive")
		)
		(pad "L9" smd circle
			(at -2.5 -0.5 270)
			(size 0.51 0.51)
			(layers "F.Cu" "F.Mask" "F.Paste")
			(net 465 "1V0_SYS")
			(pinfunction "VCCINT")
			(pintype "passive")
		)
		(pad "L10" smd circle
			(at -1.5 -0.5 270)
			(size 0.51 0.51)
			(layers "F.Cu" "F.Mask" "F.Paste")
			(net 5 "GND")
			(pinfunction "GND")
			(pintype "passive")
		)
		(pad "L11" smd circle
			(at -0.5 -0.5 270)
			(size 0.51 0.51)
			(layers "F.Cu" "F.Mask" "F.Paste")
			(net 5 "GND")
			(pinfunction "VREFN_0")
			(pintype "bidirectional")
		)
		(pad "L12" smd circle
			(at 0.5 -0.5 270)
			(size 0.51 0.51)
			(layers "F.Cu" "F.Mask" "F.Paste")
			(net 5 "GND")
			(pinfunction "VP_0")
			(pintype "bidirectional")
		)
		(pad "L13" smd circle
			(at 1.5 -0.5 270)
			(size 0.51 0.51)
			(layers "F.Cu" "F.Mask" "F.Paste")
			(net 465 "1V0_SYS")
			(pinfunction "VCCBRAM")
			(pintype "power_in")
		)
		(pad "L14" smd circle
			(at 2.5 -0.5 270)
			(size 0.51 0.51)
			(layers "F.Cu" "F.Mask" "F.Paste")
			(net 5 "GND")
			(pinfunction "GND")
			(pintype "passive")
		)
		(pad "L15" smd circle
			(at 3.5 -0.5 270)
			(size 0.51 0.51)
			(layers "F.Cu" "F.Mask" "F.Paste")
			(net 465 "1V0_SYS")
			(pinfunction "VCCINT")
			(pintype "passive")
		)
		(pad "L16" smd circle
			(at 4.5 -0.5 270)
			(size 0.51 0.51)
			(layers "F.Cu" "F.Mask" "F.Paste")
			(net 212 "FCS_B")
			(pinfunction "IO_L6P_T0_FCS_B_14")
			(pintype "bidirectional")
		)
		(pad "L17" smd circle
			(at 5.5 -0.5 270)
			(size 0.51 0.51)
			(layers "F.Cu" "F.Mask" "F.Paste")
			(net 459 "3V3_SYS")
			(pinfunction "VCCO_14")
			(pintype "passive")
		)
		(pad "L18" smd circle
			(at 6.5 -0.5 270)
			(size 0.51 0.51)
			(layers "F.Cu" "F.Mask" "F.Paste")
			(net 413 "unconnected-(U3H-IO_L5P_T0_D06_14-PadL18)")
			(pinfunction "IO_L5P_T0_D06_14")
			(pintype "bidirectional+no_connect")
		)
		(pad "L19" smd circle
			(at 7.5 -0.5 270)
			(size 0.51 0.51)
			(layers "F.Cu" "F.Mask" "F.Paste")
			(net 38 "GCLK100")
			(pinfunction "IO_L12P_T1_MRCC_14")
			(pintype "bidirectional")
		)
		(pad "L20" smd circle
			(at 8.5 -0.5 270)
			(size 0.51 0.51)
			(layers "F.Cu" "F.Mask" "F.Paste")
			(net 414 "unconnected-(U3H-IO_L12N_T1_MRCC_14-PadL20)")
			(pinfunction "IO_L12N_T1_MRCC_14")
			(pintype "bidirectional+no_connect")
		)
		(pad "L21" smd circle
			(at 9.5 -0.5 270)
			(size 0.51 0.51)
			(layers "F.Cu" "F.Mask" "F.Paste")
			(net 415 "unconnected-(U3H-IO_L18N_T2_A11_D27_14-PadL21)")
			(pinfunction "IO_L18N_T2_A11_D27_14")
			(pintype "bidirectional+no_connect")
		)
		(pad "L22" smd circle
			(at 10.5 -0.5 270)
			(size 0.51 0.51)
			(layers "F.Cu" "F.Mask" "F.Paste")
			(net 5 "GND")
			(pinfunction "GND")
			(pintype "passive")
		)
		(pad "M1" smd circle
			(at -10.5 0.5 270)
			(size 0.51 0.51)
			(layers "F.Cu" "F.Mask" "F.Paste")
			(net 650 "DQ_S0_N")
			(pinfunction "IO_L3N_T0_DQS_34")
			(pintype "bidirectional")
		)
		(pad "M2" smd circle
			(at -9.5 0.5 270)
			(size 0.51 0.51)
			(layers "F.Cu" "F.Mask" "F.Paste")
			(net 651 "DQ_S0_P")
			(pinfunction "IO_L3P_T0_DQS_34")
			(pintype "bidirectional")
		)
		(pad "M3" smd circle
			(at -8.5 0.5 270)
			(size 0.51 0.51)
			(layers "F.Cu" "F.Mask" "F.Paste")
			(net 347 "DMI_0A")
			(pinfunction "IO_L1N_T0_34")
			(pintype "bidirectional")
		)
		(pad "M4" smd circle
			(at -7.5 0.5 270)
			(size 0.51 0.51)
			(layers "F.Cu" "F.Mask" "F.Paste")
			(net 66 "VDDQ")
			(pinfunction "VCCO_34")
			(pintype "passive")
		)
		(pad "M5" smd circle
			(at -6.5 0.5 270)
			(size 0.51 0.51)
			(layers "F.Cu" "F.Mask" "F.Paste")
			(net 397 "IO_M5")
			(pinfunction "IO_L9P_T1_DQS_34")
			(pintype "bidirectional")
		)
		(pad "M6" smd circle
			(at -5.5 0.5 270)
			(size 0.51 0.51)
			(layers "F.Cu" "F.Mask" "F.Paste")
			(net 208 "PROGRAM_B")
			(pinfunction "PROGRAM_B_0")
			(pintype "bidirectional")
		)
		(pad "M7" smd circle
			(at -4.5 0.5 270)
			(size 0.51 0.51)
			(layers "F.Cu" "F.Mask" "F.Paste")
			(net 219 "CFGBVS")
			(pinfunction "CFGBVS_0")
			(pintype "bidirectional")
		)
		(pad "M8" smd circle
			(at -3.5 0.5 270)
			(size 0.51 0.51)
			(layers "F.Cu" "F.Mask" "F.Paste")
			(net 465 "1V0_SYS")
			(pinfunction "VCCINT")
			(pintype "passive")
		)
		(pad "M9" smd circle
			(at -2.5 0.5 270)
			(size 0.51 0.51)
			(layers "F.Cu" "F.Mask" "F.Paste")
			(net 5 "GND")
			(pinfunction "GND")
			(pintype "passive")
		)
		(pad "M10" smd circle
			(at -1.5 0.5 270)
			(size 0.51 0.51)
			(layers "F.Cu" "F.Mask" "F.Paste")
			(net 460 "1V8_SYS")
			(pinfunction "VCCAUX")
			(pintype "passive")
		)
		(pad "M11" smd circle
			(at -0.5 0.5 270)
			(size 0.51 0.51)
			(layers "F.Cu" "F.Mask" "F.Paste")
			(net 5 "GND")
			(pinfunction "VN_0")
			(pintype "bidirectional")
		)
		(pad "M12" smd circle
			(at 0.5 0.5 270)
			(size 0.51 0.51)
			(layers "F.Cu" "F.Mask" "F.Paste")
			(net 5 "GND")
			(pinfunction "VREFP_0")
			(pintype "bidirectional")
		)
		(pad "M13" smd circle
			(at 1.5 0.5 270)
			(size 0.51 0.51)
			(layers "F.Cu" "F.Mask" "F.Paste")
			(net 5 "GND")
			(pinfunction "GND")
			(pintype "passive")
		)
		(pad "M14" smd circle
			(at 2.5 0.5 270)
			(size 0.51 0.51)
			(layers "F.Cu" "F.Mask" "F.Paste")
			(net 465 "1V0_SYS")
			(pinfunction "VCCINT")
			(pintype "passive")
		)
		(pad "M15" smd circle
			(at 3.5 0.5 270)
			(size 0.51 0.51)
			(layers "F.Cu" "F.Mask" "F.Paste")
			(net 5 "GND")
			(pinfunction "GND")
			(pintype "passive")
		)
		(pad "M16" smd circle
			(at 4.5 0.5 270)
			(size 0.51 0.51)
			(layers "F.Cu" "F.Mask" "F.Paste")
			(net 416 "unconnected-(U3H-IO_25_14-PadM16)")
			(pinfunction "IO_25_14")
			(pintype "bidirectional+no_connect")
		)
		(pad "M17" smd circle
			(at 5.5 0.5 270)
			(size 0.51 0.51)
			(layers "F.Cu" "F.Mask" "F.Paste")
			(net 417 "unconnected-(U3H-IO_L14P_T2_SRCC_14-PadM17)")
			(pinfunction "IO_L14P_T2_SRCC_14")
			(pintype "bidirectional+no_connect")
		)
		(pad "M18" smd circle
			(at 6.5 0.5 270)
			(size 0.51 0.51)
			(layers "F.Cu" "F.Mask" "F.Paste")
			(net 418 "unconnected-(U3H-IO_L14N_T2_SRCC_14-PadM18)")
			(pinfunction "IO_L14N_T2_SRCC_14")
			(pintype "bidirectional+no_connect")
		)
		(pad "M19" smd circle
			(at 7.5 0.5 270)
			(size 0.51 0.51)
			(layers "F.Cu" "F.Mask" "F.Paste")
			(net 5 "GND")
			(pinfunction "GND")
			(pintype "passive")
		)
		(pad "M20" smd circle
			(at 8.5 0.5 270)
			(size 0.51 0.51)
			(layers "F.Cu" "F.Mask" "F.Paste")
			(net 419 "unconnected-(U3H-IO_L18P_T2_A12_D28_14-PadM20)")
			(pinfunction "IO_L18P_T2_A12_D28_14")
			(pintype "bidirectional+no_connect")
		)
		(pad "M21" smd circle
			(at 9.5 0.5 270)
			(size 0.51 0.51)
			(layers "F.Cu" "F.Mask" "F.Paste")
			(net 420 "unconnected-(U3H-IO_L17N_T2_A13_D29_14-PadM21)")
			(pinfunction "IO_L17N_T2_A13_D29_14")
			(pintype "bidirectional+no_connect")
		)
		(pad "M22" smd circle
			(at 10.5 0.5 270)
			(size 0.51 0.51)
			(layers "F.Cu" "F.Mask" "F.Paste")
			(net 421 "unconnected-(U3H-IO_L15N_T2_DQS_DOUT_CSO_B_14-PadM22)")
			(pinfunction "IO_L15N_T2_DQS_DOUT_CSO_B_14")
			(pintype "bidirectional+no_connect")
		)
		(pad "N1" smd circle
			(at -10.5 1.5 270)
			(size 0.51 0.51)
			(layers "F.Cu" "F.Mask" "F.Paste")
			(net 66 "VDDQ")
			(pinfunction "VCCO_34")
			(pintype "passive")
		)
		(pad "N2" smd circle
			(at -9.5 1.5 270)
			(size 0.51 0.51)
			(layers "F.Cu" "F.Mask" "F.Paste")
			(net 346 "DQ07_A")
			(pinfunction "IO_L5N_T0_34")
			(pintype "bidirectional")
		)
		(pad "N3" smd circle
			(at -8.5 1.5 270)
			(size 0.51 0.51)
			(layers "F.Cu" "F.Mask" "F.Paste")
			(net 395 "CS0_A")
			(pinfunction "IO_L5P_T0_34")
			(pintype "bidirectional")
		)
		(pad "N4" smd circle
			(at -7.5 1.5 270)
			(size 0.51 0.51)
			(layers "F.Cu" "F.Mask" "F.Paste")
			(net 396 "CKE0_A")
			(pinfunction "IO_L9N_T1_DQS_34")
			(pintype "bidirectional")
		)
		(pad "N5" smd circle
			(at -6.5 1.5 270)
			(size 0.51 0.51)
			(layers "F.Cu" "F.Mask" "F.Paste")
			(net 406 "IO_N5")
			(pinfunction "IO_L18P_T2_34")
			(pintype "bidirectional")
		)
		(pad "N6" smd circle
			(at -5.5 1.5 270)
			(size 0.51 0.51)
			(layers "F.Cu" "F.Mask" "F.Paste")
			(net 5 "GND")
			(pinfunction "GND")
			(pintype "passive")
		)
		(pad "N7" smd circle
			(at -4.5 1.5 270)
			(size 0.51 0.51)
			(layers "F.Cu" "F.Mask" "F.Paste")
			(net 459 "3V3_SYS")
			(pinfunction "VCCO_0")
			(pintype "passive")
		)
		(pad "N8" smd circle
			(at -3.5 1.5 270)
			(size 0.51 0.51)
			(layers "F.Cu" "F.Mask" "F.Paste")
			(net 5 "GND")
			(pinfunction "GND")
			(pintype "passive")
		)
		(pad "N9" smd circle
			(at -2.5 1.5 270)
			(size 0.51 0.51)
			(layers "F.Cu" "F.Mask" "F.Paste")
			(net 465 "1V0_SYS")
			(pinfunction "VCCINT")
			(pintype "passive")
		)
		(pad "N10" smd circle
			(at -1.5 1.5 270)
			(size 0.51 0.51)
			(layers "F.Cu" "F.Mask" "F.Paste")
			(net 5 "GND")
			(pinfunction "GND")
			(pintype "passive")
		)
		(pad "N11" smd circle
			(at -0.5 1.5 270)
			(size 0.51 0.51)
			(layers "F.Cu" "F.Mask" "F.Paste")
			(net 5 "GND")
			(pinfunction "DXN_0")
			(pintype "bidirectional")
		)
		(pad "N12" smd circle
			(at 0.5 1.5 270)
			(size 0.51 0.51)
			(layers "F.Cu" "F.Mask" "F.Paste")
			(net 5 "GND")
			(pinfunction "DXP_0")
			(pintype "bidirectional")
		)
		(pad "N13" smd circle
			(at 1.5 1.5 270)
			(size 0.51 0.51)
			(layers "F.Cu" "F.Mask" "F.Paste")
			(net 465 "1V0_SYS")
			(pinfunction "VCCBRAM")
			(pintype "passive")
		)
		(pad "N14" smd circle
			(at 2.5 1.5 270)
			(size 0.51 0.51)
			(layers "F.Cu" "F.Mask" "F.Paste")
			(net 5 "GND")
			(pinfunction "GND")
			(pintype "passive")
		)
		(pad "N15" smd circle
			(at 3.5 1.5 270)
			(size 0.51 0.51)
			(layers "F.Cu" "F.Mask" "F.Paste")
			(net 465 "1V0_SYS")
			(pinfunction "VCCINT")
			(pintype "passive")
		)
		(pad "N16" smd circle
			(at 4.5 1.5 270)
			(size 0.51 0.51)
			(layers "F.Cu" "F.Mask" "F.Paste")
			(net 5 "GND")
			(pinfunction "GND")
			(pintype "passive")
		)
		(pad "N17" smd circle
			(at 5.5 1.5 270)
			(size 0.51 0.51)
			(layers "F.Cu" "F.Mask" "F.Paste")
			(net 422 "unconnected-(U3H-IO_L23N_T3_A02_D18_14-PadN17)")
			(pinfunction "IO_L23N_T3_A02_D18_14")
			(pintype "bidirectional+no_connect")
		)
		(pad "N18" smd circle
			(at 6.5 1.5 270)
			(size 0.51 0.51)
			(layers "F.Cu" "F.Mask" "F.Paste")
			(net 423 "unconnected-(U3H-IO_L13P_T2_MRCC_14-PadN18)")
			(pinfunction "IO_L13P_T2_MRCC_14")
			(pintype "bidirectional+no_connect")
		)
		(pad "N19" smd circle
			(at 7.5 1.5 270)
			(size 0.51 0.51)
			(layers "F.Cu" "F.Mask" "F.Paste")
			(net 424 "unconnected-(U3H-IO_L13N_T2_MRCC_14-PadN19)")
			(pinfunction "IO_L13N_T2_MRCC_14")
			(pintype "bidirectional+no_connect")
		)
		(pad "N20" smd circle
			(at 8.5 1.5 270)
			(size 0.51 0.51)
			(layers "F.Cu" "F.Mask" "F.Paste")
			(net 425 "unconnected-(U3H-IO_L17P_T2_A14_D30_14-PadN20)")
			(pinfunction "IO_L17P_T2_A14_D30_14")
			(pintype "bidirectional+no_connect")
		)
		(pad "N21" smd circle
			(at 9.5 1.5 270)
			(size 0.51 0.51)
			(layers "F.Cu" "F.Mask" "F.Paste")
			(net 459 "3V3_SYS")
			(pinfunction "VCCO_14")
			(pintype "passive")
		)
		(pad "N22" smd circle
			(at 10.5 1.5 270)
			(size 0.51 0.51)
			(layers "F.Cu" "F.Mask" "F.Paste")
			(net 426 "unconnected-(U3H-IO_L15P_T2_DQS_RDWR_B_14-PadN22)")
			(pinfunction "IO_L15P_T2_DQS_RDWR_B_14")
			(pintype "bidirectional+no_connect")
		)
		(pad "P1" smd circle
			(at -10.5 2.5 270)
			(size 0.51 0.51)
			(layers "F.Cu" "F.Mask" "F.Paste")
			(net 345 "DQ06_A")
			(pinfunction "IO_L8P_T1_34")
			(pintype "bidirectional")
		)
		(pad "P2" smd circle
			(at -9.5 2.5 270)
			(size 0.51 0.51)
			(layers "F.Cu" "F.Mask" "F.Paste")
			(net 344 "DQ05_A")
			(pinfunction "IO_L7P_T1_34")
			(pintype "bidirectional")
		)
		(pad "P3" smd circle
			(at -8.5 2.5 270)
			(size 0.51 0.51)
			(layers "F.Cu" "F.Mask" "F.Paste")
			(net 5 "GND")
			(pinfunction "GND")
			(pintype "passive")
		)
		(pad "P4" smd circle
			(at -7.5 2.5 270)
			(size 0.51 0.51)
			(layers "F.Cu" "F.Mask" "F.Paste")
			(net 402 "IO_P4")
			(pinfunction "IO_L11P_T1_SRCC_34")
			(pintype "bidirectional")
		)
		(pad "P5" smd circle
			(at -6.5 2.5 270)
			(size 0.51 0.51)
			(layers "F.Cu" "F.Mask" "F.Paste")
			(net 427 "unconnected-(U3D-IO_L18N_T2_34-PadP5)")
			(pinfunction "IO_L18N_T2_34")
			(pintype "bidirectional+no_connect")
		)
		(pad "P6" smd circle
			(at -5.5 2.5 270)
			(size 0.51 0.51)
			(layers "F.Cu" "F.Mask" "F.Paste")
			(net 21 "DONE")
			(pinfunction "DONE_0")
			(pintype "bidirectional")
		)
		(pad "P7" smd circle
			(at -4.5 2.5 270)
			(size 0.51 0.51)
			(layers "F.Cu" "F.Mask" "F.Paste")
			(net 460 "1V8_SYS")
			(pinfunction "VCCBATT_0")
			(pintype "power_in")
		)
		(pad "P8" smd circle
			(at -3.5 2.5 270)
			(size 0.51 0.51)
			(layers "F.Cu" "F.Mask" "F.Paste")
			(net 460 "1V8_SYS")
			(pinfunction "VCCAUX")
			(pintype "passive")
		)
		(pad "P9" smd circle
			(at -2.5 2.5 270)
			(size 0.51 0.51)
			(layers "F.Cu" "F.Mask" "F.Paste")
			(net 5 "GND")
			(pinfunction "GND")
			(pintype "passive")
		)
		(pad "P10" smd circle
			(at -1.5 2.5 270)
			(size 0.51 0.51)
			(layers "F.Cu" "F.Mask" "F.Paste")
			(net 460 "1V8_SYS")
			(pinfunction "VCCAUX")
			(pintype "passive")
		)
		(pad "P11" smd circle
			(at -0.5 2.5 270)
			(size 0.51 0.51)
			(layers "F.Cu" "F.Mask" "F.Paste")
			(net 5 "GND")
			(pinfunction "GND")
			(pintype "passive")
		)
		(pad "P12" smd circle
			(at 0.5 2.5 270)
			(size 0.51 0.51)
			(layers "F.Cu" "F.Mask" "F.Paste")
			(net 460 "1V8_SYS")
			(pinfunction "VCCAUX")
			(pintype "passive")
		)
		(pad "P13" smd circle
			(at 1.5 2.5 270)
			(size 0.51 0.51)
			(layers "F.Cu" "F.Mask" "F.Paste")
			(net 5 "GND")
			(pinfunction "GND")
			(pintype "passive")
		)
		(pad "P14" smd circle
			(at 2.5 2.5 270)
			(size 0.51 0.51)
			(layers "F.Cu" "F.Mask" "F.Paste")
			(net 465 "1V0_SYS")
			(pinfunction "VCCINT")
			(pintype "passive")
		)
		(pad "P15" smd circle
			(at 3.5 2.5 270)
			(size 0.51 0.51)
			(layers "F.Cu" "F.Mask" "F.Paste")
			(net 5 "GND")
			(pinfunction "GND")
			(pintype "passive")
		)
		(pad "P16" smd circle
			(at 4.5 2.5 270)
			(size 0.51 0.51)
			(layers "F.Cu" "F.Mask" "F.Paste")
			(net 428 "unconnected-(U3H-IO_L23P_T3_A03_D19_14-PadP16)")
			(pinfunction "IO_L23P_T3_A03_D19_14")
			(pintype "bidirectional+no_connect")
		)
		(pad "P17" smd circle
			(at 5.5 2.5 270)
			(size 0.51 0.51)
			(layers "F.Cu" "F.Mask" "F.Paste")
			(net 429 "unconnected-(U3H-IO_L21N_T3_DQS_A06_D22_14-PadP17)")
			(pinfunction "IO_L21N_T3_DQS_A06_D22_14")
			(pintype "bidirectional+no_connect")
		)
		(pad "P18" smd circle
			(at 6.5 2.5 270)
			(size 0.51 0.51)
			(layers "F.Cu" "F.Mask" "F.Paste")
			(net 459 "3V3_SYS")
			(pinfunction "VCCO_14")
			(pintype "passive")
		)
		(pad "P19" smd circle
			(at 7.5 2.5 270)
			(size 0.51 0.51)
			(layers "F.Cu" "F.Mask" "F.Paste")
			(net 430 "unconnected-(U3H-IO_L20P_T3_A08_D24_14-PadP19)")
			(pinfunction "IO_L20P_T3_A08_D24_14")
			(pintype "bidirectional+no_connect")
		)
		(pad "P20" smd circle
			(at 8.5 2.5 270)
			(size 0.51 0.51)
			(layers "F.Cu" "F.Mask" "F.Paste")
			(net 431 "unconnected-(U3H-IO_L20N_T3_A07_D23_14-PadP20)")
			(pinfunction "IO_L20N_T3_A07_D23_14")
			(pintype "bidirectional+no_connect")
		)
		(pad "P21" smd circle
			(at 9.5 2.5 270)
			(size 0.51 0.51)
			(layers "F.Cu" "F.Mask" "F.Paste")
			(net 46 "TMDS_D0_P")
			(pinfunction "IO_L22P_T3_A05_D21_14")
			(pintype "bidirectional")
		)
		(pad "P22" smd circle
			(at 10.5 2.5 270)
			(size 0.51 0.51)
			(layers "F.Cu" "F.Mask" "F.Paste")
			(net 47 "TMDS_D0_N")
			(pinfunction "IO_L22N_T3_A04_D20_14")
			(pintype "bidirectional")
		)
		(pad "R1" smd circle
			(at -10.5 3.5 270)
			(size 0.51 0.51)
			(layers "F.Cu" "F.Mask" "F.Paste")
			(net 343 "DQ04_A")
			(pinfunction "IO_L8N_T1_34")
			(pintype "bidirectional")
		)
		(pad "R2" smd circle
			(at -9.5 3.5 270)
			(size 0.51 0.51)
			(layers "F.Cu" "F.Mask" "F.Paste")
			(net 341 "DQ12_A")
			(pinfunction "IO_L7N_T1_34")
			(pintype "bidirectional")
		)
		(pad "R3" smd circle
			(at -8.5 3.5 270)
			(size 0.51 0.51)
			(layers "F.Cu" "F.Mask" "F.Paste")
			(net 432 "unconnected-(U3D-IO_L12P_T1_MRCC_34-PadR3)")
			(pinfunction "IO_L12P_T1_MRCC_34")
			(pintype "bidirectional+no_connect")
		)
		(pad "R4" smd circle
			(at -7.5 3.5 270)
			(size 0.51 0.51)
			(layers "F.Cu" "F.Mask" "F.Paste")
			(net 401 "IO_R4")
			(pinfunction "IO_L11N_T1_SRCC_34")
			(pintype "bidirectional")
		)
		(pad "R5" smd circle
			(at -6.5 3.5 270)
			(size 0.51 0.51)
			(layers "F.Cu" "F.Mask" "F.Paste")
			(net 66 "VDDQ")
			(pinfunction "VCCO_34")
			(pintype "passive")
		)
		(pad "R6" smd circle
			(at -5.5 3.5 270)
			(size 0.51 0.51)
			(layers "F.Cu" "F.Mask" "F.Paste")
			(net 433 "unconnected-(U3E-IO_L8N_T1_33-PadR6)")
			(pinfunction "IO_L8N_T1_33")
			(pintype "bidirectional+no_connect")
		)
		(pad "R7" smd circle
			(at -4.5 3.5 270)
			(size 0.51 0.51)
			(layers "F.Cu" "F.Mask" "F.Paste")
			(net 434 "unconnected-(U3E-IO_L8P_T1_33-PadR7)")
			(pinfunction "IO_L8P_T1_33")
			(pintype "bidirectional+no_connect")
		)
		(pad "R8" smd circle
			(at -3.5 3.5 270)
			(size 0.51 0.51)
			(layers "F.Cu" "F.Mask" "F.Paste")
			(net 5 "GND")
			(pinfunction "GND")
			(pintype "passive")
		)
		(pad "R9" smd circle
			(at -2.5 3.5 270)
			(size 0.51 0.51)
			(layers "F.Cu" "F.Mask" "F.Paste")
			(net 460 "1V8_SYS")
			(pinfunction "VCCAUX")
			(pintype "passive")
		)
		(pad "R10" smd circle
			(at -1.5 3.5 270)
			(size 0.51 0.51)
			(layers "F.Cu" "F.Mask" "F.Paste")
			(net 5 "GND")
			(pinfunction "GND")
			(pintype "passive")
		)
		(pad "R11" smd circle
			(at -0.5 3.5 270)
			(size 0.51 0.51)
			(layers "F.Cu" "F.Mask" "F.Paste")
			(net 460 "1V8_SYS")
			(pinfunction "VCCAUX")
			(pintype "passive")
		)
		(pad "R12" smd circle
			(at 0.5 3.5 270)
			(size 0.51 0.51)
			(layers "F.Cu" "F.Mask" "F.Paste")
			(net 5 "GND")
			(pinfunction "GND")
			(pintype "passive")
		)
		(pad "R13" smd circle
			(at 1.5 3.5 270)
			(size 0.51 0.51)
			(layers "F.Cu" "F.Mask" "F.Paste")
			(net 465 "1V0_SYS")
			(pinfunction "VCCBRAM")
			(pintype "passive")
		)
		(pad "R14" smd circle
			(at 2.5 3.5 270)
			(size 0.51 0.51)
			(layers "F.Cu" "F.Mask" "F.Paste")
			(net 5 "GND")
			(pinfunction "GND")
			(pintype "passive")
		)
		(pad "R15" smd circle
			(at 3.5 3.5 270)
			(size 0.51 0.51)
			(layers "F.Cu" "F.Mask" "F.Paste")
			(net 465 "1V0_SYS")
			(pinfunction "VCCINT")
			(pintype "passive")
		)
		(pad "R16" smd circle
			(at 4.5 3.5 270)
			(size 0.51 0.51)
			(layers "F.Cu" "F.Mask" "F.Paste")
			(net 435 "unconnected-(U3I-IO_L20P_T3_13-PadR16)")
			(pinfunction "IO_L20P_T3_13")
			(pintype "bidirectional+no_connect")
		)
		(pad "R17" smd circle
			(at 5.5 3.5 270)
			(size 0.51 0.51)
			(layers "F.Cu" "F.Mask" "F.Paste")
			(net 437 "unconnected-(U3H-IO_L21P_T3_DQS_14-PadR17)")
			(pinfunction "IO_L21P_T3_DQS_14")
			(pintype "bidirectional+no_connect")
		)
		(pad "R18" smd circle
			(at 6.5 3.5 270)
			(size 0.51 0.51)
			(layers "F.Cu" "F.Mask" "F.Paste")
			(net 438 "unconnected-(U3H-IO_L19P_T3_A10_D26_14-PadR18)")
			(pinfunction "IO_L19P_T3_A10_D26_14")
			(pintype "bidirectional+no_connect")
		)
		(pad "R19" smd circle
			(at 7.5 3.5 270)
			(size 0.51 0.51)
			(layers "F.Cu" "F.Mask" "F.Paste")
			(net 439 "unconnected-(U3H-IO_L19N_T3_A09_D25_VREF_14-PadR19)")
			(pinfunction "IO_L19N_T3_A09_D25_VREF_14")
			(pintype "bidirectional+no_connect")
		)
		(pad "R20" smd circle
			(at 8.5 3.5 270)
			(size 0.51 0.51)
			(layers "F.Cu" "F.Mask" "F.Paste")
			(net 5 "GND")
			(pinfunction "GND")
			(pintype "passive")
		)
		(pad "R21" smd circle
			(at 9.5 3.5 270)
			(size 0.51 0.51)
			(layers "F.Cu" "F.Mask" "F.Paste")
			(net 44 "TMDS_CLK_P")
			(pinfunction "IO_L24P_T3_A01_D17_14")
			(pintype "bidirectional")
		)
		(pad "R22" smd circle
			(at 10.5 3.5 270)
			(size 0.51 0.51)
			(layers "F.Cu" "F.Mask" "F.Paste")
			(net 45 "TMDS_CLK_N")
			(pinfunction "IO_L24N_T3_A00_D16_14")
			(pintype "bidirectional")
		)
		(pad "T1" smd circle
			(at -10.5 4.5 270)
			(size 0.51 0.51)
			(layers "F.Cu" "F.Mask" "F.Paste")
			(net 340 "DQ13_A")
			(pinfunction "IO_L10P_T1_34")
			(pintype "bidirectional")
		)
		(pad "T2" smd circle
			(at -9.5 4.5 270)
			(size 0.51 0.51)
			(layers "F.Cu" "F.Mask" "F.Paste")
			(net 66 "VDDQ")
			(pinfunction "VCCO_34")
			(pintype "passive")
		)
		(pad "T3" smd circle
			(at -8.5 4.5 270)
			(size 0.51 0.51)
			(layers "F.Cu" "F.Mask" "F.Paste")
			(net 339 "DQ14_A")
			(pinfunction "IO_L12N_T1_MRCC_34")
			(pintype "bidirectional")
		)
		(pad "T4" smd circle
			(at -7.5 4.5 270)
			(size 0.51 0.51)
			(layers "F.Cu" "F.Mask" "F.Paste")
			(net 400 "IO_T4")
			(pinfunction "IO_L13P_T2_MRCC_34")
			(pintype "bidirectional")
		)
		(pad "T5" smd circle
			(at -6.5 4.5 270)
			(size 0.51 0.51)
			(layers "F.Cu" "F.Mask" "F.Paste")
			(net 440 "unconnected-(U3D-IO_L16P_T2_34-PadT5)")
			(pinfunction "IO_L16P_T2_34")
			(pintype "bidirectional+no_connect")
		)
		(pad "T6" smd circle
			(at -5.5 4.5 270)
			(size 0.51 0.51)
			(layers "F.Cu" "F.Mask" "F.Paste")
			(net 441 "unconnected-(U3E-IO_0_VRN_33-PadT6)")
			(pinfunction "IO_0_VRN_33")
			(pintype "bidirectional+no_connect")
		)
		(pad "T7" smd circle
			(at -4.5 4.5 270)
			(size 0.51 0.51)
			(layers "F.Cu" "F.Mask" "F.Paste")
			(net 5 "GND")
			(pinfunction "GND")
			(pintype "passive")
		)
		(pad "T8" smd circle
			(at -3.5 4.5 270)
			(size 0.51 0.51)
			(layers "F.Cu" "F.Mask" "F.Paste")
			(net 443 "unconnected-(U3E-IO_L18N_T2_33-PadT8)")
			(pinfunction "IO_L18N_T2_33")
			(pintype "bidirectional+no_connect")
		)
		(pad "T9" smd circle
			(at -2.5 4.5 270)
			(size 0.51 0.51)
			(layers "F.Cu" "F.Mask" "F.Paste")
			(net 445 "unconnected-(U3E-IO_L18P_T2_33-PadT9)")
			(pinfunction "IO_L18P_T2_33")
			(pintype "bidirectional+no_connect")
		)
		(pad "T10" smd circle
			(at -1.5 4.5 270)
			(size 0.51 0.51)
			(layers "F.Cu" "F.Mask" "F.Paste")
			(net 446 "unconnected-(U3E-IO_L16N_T2_33-PadT10)")
			(pinfunction "IO_L16N_T2_33")
			(pintype "bidirectional+no_connect")
		)
		(pad "T11" smd circle
			(at -0.5 4.5 270)
			(size 0.51 0.51)
			(layers "F.Cu" "F.Mask" "F.Paste")
			(net 448 "unconnected-(U3E-IO_L16P_T2_33-PadT11)")
			(pinfunction "IO_L16P_T2_33")
			(pintype "bidirectional+no_connect")
		)
		(pad "T12" smd circle
			(at 0.5 4.5 270)
			(size 0.51 0.51)
			(layers "F.Cu" "F.Mask" "F.Paste")
			(net 66 "VDDQ")
			(pinfunction "VCCO_33")
			(pintype "passive")
		)
		(pad "T13" smd circle
			(at 1.5 4.5 270)
			(size 0.51 0.51)
			(layers "F.Cu" "F.Mask" "F.Paste")
			(net 450 "unconnected-(U3E-IO_L24P_T3_33-PadT13)")
			(pinfunction "IO_L24P_T3_33")
			(pintype "bidirectional+no_connect")
		)
		(pad "T14" smd circle
			(at 2.5 4.5 270)
			(size 0.51 0.51)
			(layers "F.Cu" "F.Mask" "F.Paste")
			(net 452 "unconnected-(U3E-IO_25_VRP_33-PadT14)")
			(pinfunction "IO_25_VRP_33")
			(pintype "bidirectional+no_connect")
		)
		(pad "T15" smd circle
			(at 3.5 4.5 270)
			(size 0.51 0.51)
			(layers "F.Cu" "F.Mask" "F.Paste")
			(net 454 "unconnected-(U3I-IO_L24P_T3_13-PadT15)")
			(pinfunction "IO_L24P_T3_13")
			(pintype "bidirectional+no_connect")
		)
		(pad "T16" smd circle
			(at 4.5 4.5 270)
			(size 0.51 0.51)
			(layers "F.Cu" "F.Mask" "F.Paste")
			(net 456 "unconnected-(U3I-IO_L20N_T3_13-PadT16)")
			(pinfunction "IO_L20N_T3_13")
			(pintype "bidirectional+no_connect")
		)
		(pad "T17" smd circle
			(at 5.5 4.5 270)
			(size 0.51 0.51)
			(layers "F.Cu" "F.Mask" "F.Paste")
			(net 5 "GND")
			(pinfunction "GND")
			(pintype "passive")
		)
		(pad "T18" smd circle
			(at 6.5 4.5 270)
			(size 0.51 0.51)
			(layers "F.Cu" "F.Mask" "F.Paste")
			(net 458 "unconnected-(U3I-IO_L3P_T0_DQS_13-PadT18)")
			(pinfunction "IO_L3P_T0_DQS_13")
			(pintype "bidirectional+no_connect")
		)
		(pad "T19" smd circle
			(at 7.5 4.5 270)
			(size 0.51 0.51)
			(layers "F.Cu" "F.Mask" "F.Paste")
			(net 462 "unconnected-(U3I-IO_0_13-PadT19)")
			(pinfunction "IO_0_13")
			(pintype "bidirectional+no_connect")
		)
		(pad "T20" smd circle
			(at 8.5 4.5 270)
			(size 0.51 0.51)
			(layers "F.Cu" "F.Mask" "F.Paste")
			(net 467 "unconnected-(U3I-IO_L6P_T0_13-PadT20)")
			(pinfunction "IO_L6P_T0_13")
			(pintype "bidirectional+no_connect")
		)
		(pad "T21" smd circle
			(at 9.5 4.5 270)
			(size 0.51 0.51)
			(layers "F.Cu" "F.Mask" "F.Paste")
			(net 471 "unconnected-(U3I-IO_L1P_T0_13-PadT21)")
			(pinfunction "IO_L1P_T0_13")
			(pintype "bidirectional+no_connect")
		)
		(pad "T22" smd circle
			(at 10.5 4.5 270)
			(size 0.51 0.51)
			(layers "F.Cu" "F.Mask" "F.Paste")
			(net 459 "3V3_SYS")
			(pinfunction "VCCO_13")
			(pintype "passive")
		)
		(pad "U1" smd circle
			(at -10.5 5.5 270)
			(size 0.51 0.51)
			(layers "F.Cu" "F.Mask" "F.Paste")
			(net 338 "DQ15_A")
			(pinfunction "IO_L10N_T1_34")
			(pintype "bidirectional")
		)
		(pad "U2" smd circle
			(at -9.5 5.5 270)
			(size 0.51 0.51)
			(layers "F.Cu" "F.Mask" "F.Paste")
			(net 649 "DQ_S1_P")
			(pinfunction "IO_L15P_T2_DQS_34")
			(pintype "bidirectional")
		)
		(pad "U3" smd circle
			(at -8.5 5.5 270)
			(size 0.51 0.51)
			(layers "F.Cu" "F.Mask" "F.Paste")
			(net 404 "IO_U3")
			(pinfunction "IO_L13N_T2_MRCC_34")
			(pintype "bidirectional")
		)
		(pad "U4" smd circle
			(at -7.5 5.5 270)
			(size 0.51 0.51)
			(layers "F.Cu" "F.Mask" "F.Paste")
			(net 5 "GND")
			(pinfunction "GND")
			(pintype "passive")
		)
		(pad "U5" smd circle
			(at -6.5 5.5 270)
			(size 0.51 0.51)
			(layers "F.Cu" "F.Mask" "F.Paste")
			(net 405 "IO_U5")
			(pinfunction "IO_L16N_T2_34")
			(pintype "bidirectional")
		)
		(pad "U6" smd circle
			(at -5.5 5.5 270)
			(size 0.51 0.51)
			(layers "F.Cu" "F.Mask" "F.Paste")
			(net 472 "unconnected-(U3E-IO_L10N_T1_33-PadU6)")
			(pinfunction "IO_L10N_T1_33")
			(pintype "bidirectional+no_connect")
		)
		(pad "U7" smd circle
			(at -4.5 5.5 270)
			(size 0.51 0.51)
			(layers "F.Cu" "F.Mask" "F.Paste")
			(net 473 "unconnected-(U3E-IO_L10P_T1_33-PadU7)")
			(pinfunction "IO_L10P_T1_33")
			(pintype "bidirectional+no_connect")
		)
		(pad "U8" smd circle
			(at -3.5 5.5 270)
			(size 0.51 0.51)
			(layers "F.Cu" "F.Mask" "F.Paste")
			(net 474 "unconnected-(U3E-IO_L9P_T1_DQS_33-PadU8)")
			(pinfunction "IO_L9P_T1_DQS_33")
			(pintype "bidirectional+no_connect")
		)
		(pad "U9" smd circle
			(at -2.5 5.5 270)
			(size 0.51 0.51)
			(layers "F.Cu" "F.Mask" "F.Paste")
			(net 66 "VDDQ")
			(pinfunction "VCCO_33")
			(pintype "passive")
		)
		(pad "U10" smd circle
			(at -1.5 5.5 270)
			(size 0.51 0.51)
			(layers "F.Cu" "F.Mask" "F.Paste")
			(net 475 "unconnected-(U3E-IO_L14P_T2_SRCC_33-PadU10)")
			(pinfunction "IO_L14P_T2_SRCC_33")
			(pintype "bidirectional+no_connect")
		)
		(pad "U11" smd circle
			(at -0.5 5.5 270)
			(size 0.51 0.51)
			(layers "F.Cu" "F.Mask" "F.Paste")
			(net 476 "unconnected-(U3E-IO_L17N_T2_33-PadU11)")
			(pinfunction "IO_L17N_T2_33")
			(pintype "bidirectional+no_connect")
		)
		(pad "U12" smd circle
			(at 0.5 5.5 270)
			(size 0.51 0.51)
			(layers "F.Cu" "F.Mask" "F.Paste")
			(net 487 "IO_U12")
			(pinfunction "IO_L17P_T2_33")
			(pintype "bidirectional")
		)
		(pad "U13" smd circle
			(at 1.5 5.5 270)
			(size 0.51 0.51)
			(layers "F.Cu" "F.Mask" "F.Paste")
			(net 477 "unconnected-(U3E-IO_L24N_T3_33-PadU13)")
			(pinfunction "IO_L24N_T3_33")
			(pintype "bidirectional+no_connect")
		)
		(pad "U14" smd circle
			(at 2.5 5.5 270)
			(size 0.51 0.51)
			(layers "F.Cu" "F.Mask" "F.Paste")
			(net 5 "GND")
			(pinfunction "GND")
			(pintype "passive")
		)
		(pad "U15" smd circle
			(at 3.5 5.5 270)
			(size 0.51 0.51)
			(layers "F.Cu" "F.Mask" "F.Paste")
			(net 478 "unconnected-(U3I-IO_L24N_T3_13-PadU15)")
			(pinfunction "IO_L24N_T3_13")
			(pintype "bidirectional+no_connect")
		)
		(pad "U16" smd circle
			(at 4.5 5.5 270)
			(size 0.51 0.51)
			(layers "F.Cu" "F.Mask" "F.Paste")
			(net 501 "unconnected-(U3I-IO_L19P_T3_13-PadU16)")
			(pinfunction "IO_L19P_T3_13")
			(pintype "bidirectional+no_connect")
		)
		(pad "U17" smd circle
			(at 5.5 5.5 270)
			(size 0.51 0.51)
			(layers "F.Cu" "F.Mask" "F.Paste")
			(net 502 "unconnected-(U3I-IO_L5P_T0_13-PadU17)")
			(pinfunction "IO_L5P_T0_13")
			(pintype "bidirectional+no_connect")
		)
		(pad "U18" smd circle
			(at 6.5 5.5 270)
			(size 0.51 0.51)
			(layers "F.Cu" "F.Mask" "F.Paste")
			(net 503 "unconnected-(U3I-IO_L3N_T0_DQS_13-PadU18)")
			(pinfunction "IO_L3N_T0_DQS_13")
			(pintype "bidirectional+no_connect")
		)
		(pad "U19" smd circle
			(at 7.5 5.5 270)
			(size 0.51 0.51)
			(layers "F.Cu" "F.Mask" "F.Paste")
			(net 459 "3V3_SYS")
			(pinfunction "VCCO_13")
			(pintype "passive")
		)
		(pad "U20" smd circle
			(at 8.5 5.5 270)
			(size 0.51 0.51)
			(layers "F.Cu" "F.Mask" "F.Paste")
			(net 504 "unconnected-(U3I-IO_L6N_T0_VREF_13-PadU20)")
			(pinfunction "IO_L6N_T0_VREF_13")
			(pintype "bidirectional+no_connect")
		)
		(pad "U21" smd circle
			(at 9.5 5.5 270)
			(size 0.51 0.51)
			(layers "F.Cu" "F.Mask" "F.Paste")
			(net 505 "unconnected-(U3I-IO_L1N_T0_13-PadU21)")
			(pinfunction "IO_L1N_T0_13")
			(pintype "bidirectional+no_connect")
		)
		(pad "U22" smd circle
			(at 10.5 5.5 270)
			(size 0.51 0.51)
			(layers "F.Cu" "F.Mask" "F.Paste")
			(net 506 "unconnected-(U3I-IO_L2P_T0_13-PadU22)")
			(pinfunction "IO_L2P_T0_13")
			(pintype "bidirectional+no_connect")
		)
		(pad "V1" smd circle
			(at -10.5 6.5 270)
			(size 0.51 0.51)
			(layers "F.Cu" "F.Mask" "F.Paste")
			(net 5 "GND")
			(pinfunction "GND")
			(pintype "passive")
		)
		(pad "V2" smd circle
			(at -9.5 6.5 270)
			(size 0.51 0.51)
			(layers "F.Cu" "F.Mask" "F.Paste")
			(net 648 "DQ_S1_N")
			(pinfunction "IO_L15N_T2_DQS_34")
			(pintype "bidirectional")
		)
		(pad "V3" smd circle
			(at -8.5 6.5 270)
			(size 0.51 0.51)
			(layers "F.Cu" "F.Mask" "F.Paste")
			(net 403 "IO_V3")
			(pinfunction "IO_L17P_T2_34")
			(pintype "bidirectional")
		)
		(pad "V4" smd circle
			(at -7.5 6.5 270)
			(size 0.51 0.51)
			(layers "F.Cu" "F.Mask" "F.Paste")
			(net 399 "IO_V4")
			(pinfunction "IO_L14P_T2_SRCC_34")
			(pintype "bidirectional")
		)
		(pad "V5" smd circle
			(at -6.5 6.5 270)
			(size 0.51 0.51)
			(layers "F.Cu" "F.Mask" "F.Paste")
			(net 512 "VRP")
			(pinfunction "IO_25_VRP_34")
			(pintype "bidirectional")
		)
		(pad "V6" smd circle
			(at -5.5 6.5 270)
			(size 0.51 0.51)
			(layers "F.Cu" "F.Mask" "F.Paste")
			(net 66 "VDDQ")
			(pinfunction "VCCO_33")
			(pintype "passive")
		)
		(pad "V7" smd circle
			(at -4.5 6.5 270)
			(size 0.51 0.51)
			(layers "F.Cu" "F.Mask" "F.Paste")
			(net 507 "unconnected-(U3E-IO_L11P_T1_SRCC_33-PadV7)")
			(pinfunction "IO_L11P_T1_SRCC_33")
			(pintype "bidirectional+no_connect")
		)
		(pad "V8" smd circle
			(at -3.5 6.5 270)
			(size 0.51 0.51)
			(layers "F.Cu" "F.Mask" "F.Paste")
			(net 508 "unconnected-(U3E-IO_L9N_T1_DQS_33-PadV8)")
			(pinfunction "IO_L9N_T1_DQS_33")
			(pintype "bidirectional+no_connect")
		)
		(pad "V9" smd circle
			(at -2.5 6.5 270)
			(size 0.51 0.51)
			(layers "F.Cu" "F.Mask" "F.Paste")
			(net 509 "unconnected-(U3E-IO_L14N_T2_SRCC_33-PadV9)")
			(pinfunction "IO_L14N_T2_SRCC_33")
			(pintype "bidirectional+no_connect")
		)
		(pad "V10" smd circle
			(at -1.5 6.5 270)
			(size 0.51 0.51)
			(layers "F.Cu" "F.Mask" "F.Paste")
			(net 513 "unconnected-(U3E-IO_L15P_T2_DQS_33-PadV10)")
			(pinfunction "IO_L15P_T2_DQS_33")
			(pintype "bidirectional+no_connect")
		)
		(pad "V11" smd circle
			(at -0.5 6.5 270)
			(size 0.51 0.51)
			(layers "F.Cu" "F.Mask" "F.Paste")
			(net 5 "GND")
			(pinfunction "GND")
			(pintype "passive")
		)
		(pad "V12" smd circle
			(at 0.5 6.5 270)
			(size 0.51 0.51)
			(layers "F.Cu" "F.Mask" "F.Paste")
			(net 486 "IO_V12")
			(pinfunction "IO_L23N_T3_33")
			(pintype "bidirectional")
		)
		(pad "V13" smd circle
			(at 1.5 6.5 270)
			(size 0.51 0.51)
			(layers "F.Cu" "F.Mask" "F.Paste")
			(net 515 "unconnected-(U3E-IO_L23P_T3_33-PadV13)")
			(pinfunction "IO_L23P_T3_33")
			(pintype "bidirectional+no_connect")
		)
		(pad "V14" smd circle
			(at 2.5 6.5 270)
			(size 0.51 0.51)
			(layers "F.Cu" "F.Mask" "F.Paste")
			(net 516 "unconnected-(U3I-IO_25_13-PadV14)")
			(pinfunction "IO_25_13")
			(pintype "bidirectional+no_connect")
		)
		(pad "V15" smd circle
			(at 3.5 6.5 270)
			(size 0.51 0.51)
			(layers "F.Cu" "F.Mask" "F.Paste")
			(net 494 "HR_DQ5")
			(pinfunction "IO_L23P_T3_13")
			(pintype "bidirectional")
		)
		(pad "V16" smd circle
			(at 4.5 6.5 270)
			(size 0.51 0.51)
			(layers "F.Cu" "F.Mask" "F.Paste")
			(net 459 "3V3_SYS")
			(pinfunction "VCCO_13")
			(pintype "passive")
		)
		(pad "V17" smd circle
			(at 5.5 6.5 270)
			(size 0.51 0.51)
			(layers "F.Cu" "F.Mask" "F.Paste")
			(net 488 "HR_RST")
			(pinfunction "IO_L19N_T3_VREF_13")
			(pintype "bidirectional")
		)
		(pad "V18" smd circle
			(at 6.5 6.5 270)
			(size 0.51 0.51)
			(layers "F.Cu" "F.Mask" "F.Paste")
			(net 517 "unconnected-(U3I-IO_L5N_T0_13-PadV18)")
			(pinfunction "IO_L5N_T0_13")
			(pintype "bidirectional+no_connect")
		)
		(pad "V19" smd circle
			(at 7.5 6.5 270)
			(size 0.51 0.51)
			(layers "F.Cu" "F.Mask" "F.Paste")
			(net 518 "unconnected-(U3I-IO_L12P_T1_MRCC_13-PadV19)")
			(pinfunction "IO_L12P_T1_MRCC_13")
			(pintype "bidirectional+no_connect")
		)
		(pad "V20" smd circle
			(at 8.5 6.5 270)
			(size 0.51 0.51)
			(layers "F.Cu" "F.Mask" "F.Paste")
			(net 528 "unconnected-(U3I-IO_L11P_T1_SRCC_13-PadV20)")
			(pinfunction "IO_L11P_T1_SRCC_13")
			(pintype "bidirectional+no_connect")
		)
		(pad "V21" smd circle
			(at 9.5 6.5 270)
			(size 0.51 0.51)
			(layers "F.Cu" "F.Mask" "F.Paste")
			(net 5 "GND")
			(pinfunction "GND")
			(pintype "passive")
		)
		(pad "V22" smd circle
			(at 10.5 6.5 270)
			(size 0.51 0.51)
			(layers "F.Cu" "F.Mask" "F.Paste")
			(net 532 "unconnected-(U3I-IO_L2N_T0_13-PadV22)")
			(pinfunction "IO_L2N_T0_13")
			(pintype "bidirectional+no_connect")
		)
		(pad "W1" smd circle
			(at -10.5 7.5 270)
			(size 0.51 0.51)
			(layers "F.Cu" "F.Mask" "F.Paste")
			(net 336 "DMI_1A")
			(pinfunction "IO_L20P_T3_34")
			(pintype "bidirectional")
		)
		(pad "W2" smd circle
			(at -9.5 7.5 270)
			(size 0.51 0.51)
			(layers "F.Cu" "F.Mask" "F.Paste")
			(net 335 "DQ08_A")
			(pinfunction "IO_L17N_T2_34")
			(pintype "bidirectional")
		)
		(pad "W3" smd circle
			(at -8.5 7.5 270)
			(size 0.51 0.51)
			(layers "F.Cu" "F.Mask" "F.Paste")
			(net 66 "VDDQ")
			(pinfunction "VCCO_34")
			(pintype "passive")
		)
		(pad "W4" smd circle
			(at -7.5 7.5 270)
			(size 0.51 0.51)
			(layers "F.Cu" "F.Mask" "F.Paste")
			(net 398 "IO_W4")
			(pinfunction "IO_L14N_T2_SRCC_34")
			(pintype "bidirectional")
		)
		(pad "W5" smd circle
			(at -6.5 7.5 270)
			(size 0.51 0.51)
			(layers "F.Cu" "F.Mask" "F.Paste")
			(net 533 "unconnected-(U3D-IO_L19P_T3_34-PadW5)")
			(pinfunction "IO_L19P_T3_34")
			(pintype "bidirectional+no_connect")
		)
		(pad "W6" smd circle
			(at -5.5 7.5 270)
			(size 0.51 0.51)
			(layers "F.Cu" "F.Mask" "F.Paste")
			(net 534 "unconnected-(U3E-IO_L7P_T1_33-PadW6)")
			(pinfunction "IO_L7P_T1_33")
			(pintype "bidirectional+no_connect")
		)
		(pad "W7" smd circle
			(at -4.5 7.5 270)
			(size 0.51 0.51)
			(layers "F.Cu" "F.Mask" "F.Paste")
			(net 535 "unconnected-(U3E-IO_L11N_T1_SRCC_33-PadW7)")
			(pinfunction "IO_L11N_T1_SRCC_33")
			(pintype "bidirectional+no_connect")
		)
		(pad "W8" smd circle
			(at -3.5 7.5 270)
			(size 0.51 0.51)
			(layers "F.Cu" "F.Mask" "F.Paste")
			(net 5 "GND")
			(pinfunction "GND")
			(pintype "passive")
		)
		(pad "W9" smd circle
			(at -2.5 7.5 270)
			(size 0.51 0.51)
			(layers "F.Cu" "F.Mask" "F.Paste")
			(net 536 "unconnected-(U3E-IO_L13P_T2_MRCC_33-PadW9)")
			(pinfunction "IO_L13P_T2_MRCC_33")
			(pintype "bidirectional+no_connect")
		)
		(pad "W10" smd circle
			(at -1.5 7.5 270)
			(size 0.51 0.51)
			(layers "F.Cu" "F.Mask" "F.Paste")
			(net 537 "unconnected-(U3E-IO_L15N_T2_DQS_33-PadW10)")
			(pinfunction "IO_L15N_T2_DQS_33")
			(pintype "bidirectional+no_connect")
		)
		(pad "W11" smd circle
			(at -0.5 7.5 270)
			(size 0.51 0.51)
			(layers "F.Cu" "F.Mask" "F.Paste")
			(net 483 "IO_W11")
			(pinfunction "IO_L6P_T0_33")
			(pintype "bidirectional")
		)
		(pad "W12" smd circle
			(at 0.5 7.5 270)
			(size 0.51 0.51)
			(layers "F.Cu" "F.Mask" "F.Paste")
			(net 485 "IO_W12")
			(pinfunction "IO_L19P_T3_33")
			(pintype "bidirectional")
		)
		(pad "W13" smd circle
			(at 1.5 7.5 270)
			(size 0.51 0.51)
			(layers "F.Cu" "F.Mask" "F.Paste")
			(net 66 "VDDQ")
			(pinfunction "VCCO_33")
			(pintype "passive")
		)
		(pad "W14" smd circle
			(at 2.5 7.5 270)
			(size 0.51 0.51)
			(layers "F.Cu" "F.Mask" "F.Paste")
			(net 499 "HR_DQ3")
			(pinfunction "IO_L22P_T3_13")
			(pintype "bidirectional")
		)
		(pad "W15" smd circle
			(at 3.5 7.5 270)
			(size 0.51 0.51)
			(layers "F.Cu" "F.Mask" "F.Paste")
			(net 491 "HR_DQ0")
			(pinfunction "IO_L23N_T3_13")
			(pintype "bidirectional")
		)
		(pad "W16" smd circle
			(at 4.5 7.5 270)
			(size 0.51 0.51)
			(layers "F.Cu" "F.Mask" "F.Paste")
			(net 538 "unconnected-(U3I-IO_L21P_T3_DQS_13-PadW16)")
			(pinfunction "IO_L21P_T3_DQS_13")
			(pintype "bidirectional+no_connect")
		)
		(pad "W17" smd circle
			(at 5.5 7.5 270)
			(size 0.51 0.51)
			(layers "F.Cu" "F.Mask" "F.Paste")
			(net 496 "HR_DQ7")
			(pinfunction "IO_L14P_T2_SRCC_13")
			(pintype "bidirectional")
		)
		(pad "W18" smd circle
			(at 6.5 7.5 270)
			(size 0.51 0.51)
			(layers "F.Cu" "F.Mask" "F.Paste")
			(net 5 "GND")
			(pinfunction "GND")
			(pintype "passive")
		)
		(pad "W19" smd circle
			(at 7.5 7.5 270)
			(size 0.51 0.51)
			(layers "F.Cu" "F.Mask" "F.Paste")
			(net 539 "unconnected-(U3I-IO_L12N_T1_MRCC_13-PadW19)")
			(pinfunction "IO_L12N_T1_MRCC_13")
			(pintype "bidirectional+no_connect")
		)
		(pad "W20" smd circle
			(at 8.5 7.5 270)
			(size 0.51 0.51)
			(layers "F.Cu" "F.Mask" "F.Paste")
			(net 444 "AUX_JTAG_TDI")
			(pinfunction "IO_L11N_T1_SRCC_13")
			(pintype "bidirectional")
		)
		(pad "W21" smd circle
			(at 9.5 7.5 270)
			(size 0.51 0.51)
			(layers "F.Cu" "F.Mask" "F.Paste")
			(net 464 "AUX_JTAG_TDO")
			(pinfunction "IO_L4P_T0_13")
			(pintype "bidirectional")
		)
		(pad "W22" smd circle
			(at 10.5 7.5 270)
			(size 0.51 0.51)
			(layers "F.Cu" "F.Mask" "F.Paste")
			(net 442 "AUX_JTAG_TCK")
			(pinfunction "IO_L4N_T0_13")
			(pintype "bidirectional")
		)
		(pad "Y1" smd circle
			(at -10.5 8.5 270)
			(size 0.51 0.51)
			(layers "F.Cu" "F.Mask" "F.Paste")
			(net 334 "DQ09_A")
			(pinfunction "IO_L20N_T3_34")
			(pintype "bidirectional")
		)
		(pad "Y2" smd circle
			(at -9.5 8.5 270)
			(size 0.51 0.51)
			(layers "F.Cu" "F.Mask" "F.Paste")
			(net 352 "CK_A_N")
			(pinfunction "IO_L21N_T3_DQS_34")
			(pintype "bidirectional")
		)
		(pad "Y3" smd circle
			(at -8.5 8.5 270)
			(size 0.51 0.51)
			(layers "F.Cu" "F.Mask" "F.Paste")
			(net 353 "CK_A_P")
			(pinfunction "IO_L21P_T3_DQS_34")
			(pintype "bidirectional")
		)
		(pad "Y4" smd circle
			(at -7.5 8.5 270)
			(size 0.51 0.51)
			(layers "F.Cu" "F.Mask" "F.Paste")
			(net 510 "VREF_34")
			(pinfunction "IO_L19N_T3_VREF_34")
			(pintype "bidirectional")
		)
		(pad "Y5" smd circle
			(at -6.5 8.5 270)
			(size 0.51 0.51)
			(layers "F.Cu" "F.Mask" "F.Paste")
			(net 5 "GND")
			(pinfunction "GND")
			(pintype "passive")
		)
		(pad "Y6" smd circle
			(at -5.5 8.5 270)
			(size 0.51 0.51)
			(layers "F.Cu" "F.Mask" "F.Paste")
			(net 540 "unconnected-(U3E-IO_L7N_T1_33-PadY6)")
			(pinfunction "IO_L7N_T1_33")
			(pintype "bidirectional+no_connect")
		)
		(pad "Y7" smd circle
			(at -4.5 8.5 270)
			(size 0.51 0.51)
			(layers "F.Cu" "F.Mask" "F.Paste")
			(net 542 "unconnected-(U3E-IO_L12N_T1_MRCC_33-PadY7)")
			(pinfunction "IO_L12N_T1_MRCC_33")
			(pintype "bidirectional+no_connect")
		)
		(pad "Y8" smd circle
			(at -3.5 8.5 270)
			(size 0.51 0.51)
			(layers "F.Cu" "F.Mask" "F.Paste")
			(net 543 "unconnected-(U3E-IO_L12P_T1_MRCC_33-PadY8)")
			(pinfunction "IO_L12P_T1_MRCC_33")
			(pintype "bidirectional+no_connect")
		)
		(pad "Y9" smd circle
			(at -2.5 8.5 270)
			(size 0.51 0.51)
			(layers "F.Cu" "F.Mask" "F.Paste")
			(net 544 "unconnected-(U3E-IO_L13N_T2_MRCC_33-PadY9)")
			(pinfunction "IO_L13N_T2_MRCC_33")
			(pintype "bidirectional+no_connect")
		)
		(pad "Y10" smd circle
			(at -1.5 8.5 270)
			(size 0.51 0.51)
			(layers "F.Cu" "F.Mask" "F.Paste")
			(net 66 "VDDQ")
			(pinfunction "VCCO_33")
			(pintype "passive")
		)
		(pad "Y11" smd circle
			(at -0.5 8.5 270)
			(size 0.51 0.51)
			(layers "F.Cu" "F.Mask" "F.Paste")
			(net 482 "IO_Y11")
			(pinfunction "IO_L6N_T0_VREF_33")
			(pintype "bidirectional")
		)
		(pad "Y12" smd circle
			(at 0.5 8.5 270)
			(size 0.51 0.51)
			(layers "F.Cu" "F.Mask" "F.Paste")
			(net 484 "IO_Y12")
			(pinfunction "IO_L19N_T3_VREF_33")
			(pintype "bidirectional")
		)
		(pad "Y13" smd circle
			(at 1.5 8.5 270)
			(size 0.51 0.51)
			(layers "F.Cu" "F.Mask" "F.Paste")
			(net 545 "unconnected-(U3E-IO_L21P_T3_DQS_33-PadY13)")
			(pinfunction "IO_L21P_T3_DQS_33")
			(pintype "bidirectional+no_connect")
		)
		(pad "Y14" smd circle
			(at 2.5 8.5 270)
			(size 0.51 0.51)
			(layers "F.Cu" "F.Mask" "F.Paste")
			(net 495 "HR_DQ4")
			(pinfunction "IO_L22N_T3_13")
			(pintype "bidirectional")
		)
		(pad "Y15" smd circle
			(at 3.5 8.5 270)
			(size 0.51 0.51)
			(layers "F.Cu" "F.Mask" "F.Paste")
			(net 5 "GND")
			(pinfunction "GND")
			(pintype "passive")
		)
		(pad "Y16" smd circle
			(at 4.5 8.5 270)
			(size 0.51 0.51)
			(layers "F.Cu" "F.Mask" "F.Paste")
			(net 497 "HR_DQ6")
			(pinfunction "IO_L21N_T3_DQS_13")
			(pintype "bidirectional")
		)
		(pad "Y17" smd circle
			(at 5.5 8.5 270)
			(size 0.51 0.51)
			(layers "F.Cu" "F.Mask" "F.Paste")
			(net 492 "HR_RW")
			(pinfunction "IO_L14N_T2_SRCC_13")
			(pintype "bidirectional")
		)
		(pad "Y18" smd circle
			(at 6.5 8.5 270)
			(size 0.51 0.51)
			(layers "F.Cu" "F.Mask" "F.Paste")
			(net 546 "unconnected-(U3I-IO_L13P_T2_MRCC_13-PadY18)")
			(pinfunction "IO_L13P_T2_MRCC_13")
			(pintype "bidirectional+no_connect")
		)
		(pad "Y19" smd circle
			(at 7.5 8.5 270)
			(size 0.51 0.51)
			(layers "F.Cu" "F.Mask" "F.Paste")
			(net 547 "unconnected-(U3I-IO_L13N_T2_MRCC_13-PadY19)")
			(pinfunction "IO_L13N_T2_MRCC_13")
			(pintype "bidirectional+no_connect")
		)
		(pad "Y20" smd circle
			(at 8.5 8.5 270)
			(size 0.51 0.51)
			(layers "F.Cu" "F.Mask" "F.Paste")
			(net 459 "3V3_SYS")
			(pinfunction "VCCO_13")
			(pintype "passive")
		)
		(pad "Y21" smd circle
			(at 9.5 8.5 270)
			(size 0.51 0.51)
			(layers "F.Cu" "F.Mask" "F.Paste")
			(net 447 "AUX_JTAG_TMS")
			(pinfunction "IO_L7P_T1_13")
			(pintype "bidirectional")
		)
		(pad "Y22" smd circle
			(at 10.5 8.5 270)
			(size 0.51 0.51)
			(layers "F.Cu" "F.Mask" "F.Paste")
			(net 548 "unconnected-(U3I-IO_L7N_T1_13-PadY22)")
			(pinfunction "IO_L7N_T1_13")
			(pintype "bidirectional+no_connect")
		)
	)
	(footprint "antmicro-footprints:TP_SMD_1mm"
		(layer "F.Cu")
		(at 142.5 96.874)
		(property "Reference" "TP12"
			(at 0.4 0.326 0)
			(layer "F.SilkS")
			(effects
				(font
					(size 0.7 0.7)
					(thickness 0.15)
				)
				(justify left bottom)
			)
		)
		(property "Value" "TP_1mm_SMD"
			(at 0 1.4 0)
			(layer "F.Fab")
			(effects
				(font
					(size 0.7 0.7)
					(thickness 0.15)
				)
				(justify left bottom)
			)
		)
		(property "Description" "Test Point 1mm"
			(at 0 0 0)
			(layer "F.Fab")
			(hide yes)
			(effects
				(font
					(size 1.27 1.27)
					(thickness 0.15)
				)
			)
		)
		(property "Author" "Antmicro"
			(at 0 0 0)
			(layer "F.Fab")
			(hide yes)
			(effects
				(font
					(size 1 1)
					(thickness 0.15)
				)
			)
		)
		(property "License" "Apache-2.0"
			(at 0 0 0)
			(layer "F.Fab")
			(hide yes)
			(effects
				(font
					(size 1 1)
					(thickness 0.15)
				)
			)
		)
		(property "MPN" ""
			(at 0 0 0)
			(layer "F.Fab")
			(hide yes)
			(effects
				(font
					(size 1 1)
					(thickness 0.15)
				)
			)
		)
		(property "Manufacturer" ""
			(at 0 0 0)
			(layer "F.Fab")
			(hide yes)
			(effects
				(font
					(size 1 1)
					(thickness 0.15)
				)
			)
		)
		(sheetname "Supply")
		(sheetfile "supply.kicad_sch")
		(attr exclude_from_pos_files)
		(pad "1" smd circle
			(at 0 0)
			(size 1 1)
			(layers "F.Cu" "F.Mask")
			(net 470 "/Supply/VCC_IO_EN")
			(pinfunction "1")
			(pintype "passive")
		)
	)
	(footprint "antmicro-footprints:C_0402_1005Metric"
		(layer "F.Cu")
		(at 140.5 102.199 90)
		(descr "Capacitor SMD 0402")
		(tags "capacitor SMD 0402")
		(property "Reference" "C15"
			(at -1.101 -0.5 90)
			(layer "F.SilkS")
			(effects
				(font
					(size 0.7 0.7)
					(thickness 0.15)
				)
				(justify left bottom)
			)
		)
		(property "Value" "C_100n_6V3_0402"
			(at 0 1.4 90)
			(layer "F.Fab")
			(effects
				(font
					(size 0.7 0.7)
					(thickness 0.15)
				)
				(justify left bottom)
			)
		)
		(property "Description" " "
			(at 0 0 90)
			(layer "F.Fab")
			(hide yes)
			(effects
				(font
					(size 1.27 1.27)
					(thickness 0.15)
				)
			)
		)
		(property "Author" "Antmicro"
			(at 242.699 -38.301 0)
			(layer "F.Fab")
			(hide yes)
			(effects
				(font
					(size 1 1)
					(thickness 0.15)
				)
			)
		)
		(property "Dielectric" ""
			(at 242.699 -38.301 0)
			(layer "F.Fab")
			(hide yes)
			(effects
				(font
					(size 1 1)
					(thickness 0.15)
				)
			)
		)
		(property "License" "Apache-2.0"
			(at 242.699 -38.301 0)
			(layer "F.Fab")
			(hide yes)
			(effects
				(font
					(size 1 1)
					(thickness 0.15)
				)
			)
		)
		(property "MPN" "0402X104K6R3CT"
			(at 242.699 -38.301 0)
			(layer "F.Fab")
			(hide yes)
			(effects
				(font
					(size 1 1)
					(thickness 0.15)
				)
			)
		)
		(property "Manufacturer" "Walsin"
			(at 242.699 -38.301 0)
			(layer "F.Fab")
			(hide yes)
			(effects
				(font
					(size 1 1)
					(thickness 0.15)
				)
			)
		)
		(property "Val" "100n"
			(at 242.699 -38.301 0)
			(layer "F.Fab")
			(hide yes)
			(effects
				(font
					(size 1 1)
					(thickness 0.15)
				)
			)
		)
		(property "Voltage" ""
			(at 242.699 -38.301 0)
			(layer "F.Fab")
			(hide yes)
			(effects
				(font
					(size 1 1)
					(thickness 0.15)
				)
			)
		)
		(sheetname "Interfaces")
		(sheetfile "interfaces.kicad_sch")
		(attr smd)
		(fp_rect
			(start -0.94 -0.47)
			(end 0.94 0.47)
			(stroke
				(width 0.05)
				(type solid)
			)
			(fill no)
			(layer "F.CrtYd")
		)
		(fp_rect
			(start -0.499 -0.249)
			(end 0.499 0.249)
			(stroke
				(width 0.15)
				(type solid)
			)
			(fill no)
			(layer "F.Fab")
		)
		(pad "1" smd roundrect
			(at -0.484 0 90)
			(size 0.59 0.64)
			(layers "F.Cu" "F.Mask" "F.Paste")
			(roundrect_rratio 0.25)
			(net 459 "3V3_SYS")
			(pintype "passive")
		)
		(pad "2" smd roundrect
			(at 0.484 0 90)
			(size 0.59 0.64)
			(layers "F.Cu" "F.Mask" "F.Paste")
			(roundrect_rratio 0.25)
			(net 5 "GND")
			(pintype "passive")
		)
	)
	(footprint "antmicro-footprints:C_0603_1608Metric"
		(layer "F.Cu")
		(at 157.2 57.1 90)
		(descr "Capacitor SMD 0603")
		(tags "capacitor 0603")
		(property "Reference" "C139"
			(at -1.4 1.3 90)
			(layer "F.SilkS")
			(effects
				(font
					(size 0.7 0.7)
					(thickness 0.15)
				)
				(justify left bottom)
			)
		)
		(property "Value" "C_10n_0603"
			(at 0 1.6 90)
			(layer "F.Fab")
			(effects
				(font
					(size 0.7 0.7)
					(thickness 0.15)
				)
				(justify left bottom)
			)
		)
		(property "Description" " "
			(at 0 0 90)
			(layer "F.Fab")
			(hide yes)
			(effects
				(font
					(size 1.27 1.27)
					(thickness 0.15)
				)
			)
		)
		(property "Author" "Antmicro"
			(at 214.3 -100.1 0)
			(layer "F.Fab")
			(hide yes)
			(effects
				(font
					(size 1 1)
					(thickness 0.15)
				)
			)
		)
		(property "Dielectric" ""
			(at 214.3 -100.1 0)
			(layer "F.Fab")
			(hide yes)
			(effects
				(font
					(size 1 1)
					(thickness 0.15)
				)
			)
		)
		(property "License" "Apache-2.0"
			(at 214.3 -100.1 0)
			(layer "F.Fab")
			(hide yes)
			(effects
				(font
					(size 1 1)
					(thickness 0.15)
				)
			)
		)
		(property "MPN" "06031C103JAT2A"
			(at 214.3 -100.1 0)
			(layer "F.Fab")
			(hide yes)
			(effects
				(font
					(size 1 1)
					(thickness 0.15)
				)
			)
		)
		(property "Manufacturer" "AVX"
			(at 214.3 -100.1 0)
			(layer "F.Fab")
			(hide yes)
			(effects
				(font
					(size 1 1)
					(thickness 0.15)
				)
			)
		)
		(property "Val" "10n"
			(at 214.3 -100.1 0)
			(layer "F.Fab")
			(hide yes)
			(effects
				(font
					(size 1 1)
					(thickness 0.15)
				)
			)
		)
		(property "Voltage" ""
			(at 214.3 -100.1 0)
			(layer "F.Fab")
			(hide yes)
			(effects
				(font
					(size 1 1)
					(thickness 0.15)
				)
			)
		)
		(sheetname "Supply")
		(sheetfile "supply.kicad_sch")
		(attr smd)
		(fp_line
			(start -0.3 -0.3)
			(end 0.3 -0.3)
			(stroke
				(width 0.15)
				(type solid)
			)
			(layer "F.SilkS")
		)
		(fp_line
			(start -0.3 0.3)
			(end 0.3 0.3)
			(stroke
				(width 0.15)
				(type solid)
			)
			(layer "F.SilkS")
		)
		(fp_rect
			(start -1.24 -0.7)
			(end 1.24 0.7)
			(stroke
				(width 0.05)
				(type solid)
			)
			(fill no)
			(layer "F.CrtYd")
		)
		(fp_rect
			(start -0.8 -0.4)
			(end 0.8 0.4)
			(stroke
				(width 0.15)
				(type solid)
			)
			(fill no)
			(layer "F.Fab")
		)
		(pad "1" smd roundrect
			(at -0.7 0 90)
			(size 0.6 0.8)
			(layers "F.Cu" "F.Mask" "F.Paste")
			(roundrect_rratio 0.2)
			(net 66 "VDDQ")
			(pintype "passive")
		)
		(pad "2" smd roundrect
			(at 0.7 0 90)
			(size 0.6 0.8)
			(layers "F.Cu" "F.Mask" "F.Paste")
			(roundrect_rratio 0.2)
			(net 5 "GND")
			(pintype "passive")
		)
	)
	(footprint "antmicro-footprints:PinHeader_1x3_P2.54mm_Drill1.1mm"
		(layer "F.Cu")
		(at 213.196328 89.610008 90)
		(property "Reference" "MODE1"
			(at 0.710008 -1.868328 90)
			(layer "F.SilkS")
			(effects
				(font
					(size 0.7 0.7)
					(thickness 0.15)
				)
				(justify left bottom)
			)
		)
		(property "Value" "PinHeader_1x3_P2.54mm_Drill1.1mm"
			(at -1.6 2.7 90)
			(layer "F.Fab")
			(effects
				(font
					(size 0.7 0.7)
					(thickness 0.15)
				)
				(justify left bottom)
			)
		)
		(property "Description" "Pin Header, Vertical, Board-to-Board, 2.54 mm, 1 Rows, 3 Contacts, Through Hole Straight, WR-PHD"
			(at 0 0 90)
			(layer "F.Fab")
			(hide yes)
			(effects
				(font
					(size 1.27 1.27)
					(thickness 0.15)
				)
			)
		)
		(property "Author" "Antmicro"
			(at 302.806336 -123.58632 0)
			(layer "F.Fab")
			(hide yes)
			(effects
				(font
					(size 1 1)
					(thickness 0.15)
				)
			)
		)
		(property "License" "Apache-2.0"
			(at 302.806336 -123.58632 0)
			(layer "F.Fab")
			(hide yes)
			(effects
				(font
					(size 1 1)
					(thickness 0.15)
				)
			)
		)
		(property "MPN" "61300311121"
			(at 302.806336 -123.58632 0)
			(layer "F.Fab")
			(hide yes)
			(effects
				(font
					(size 1 1)
					(thickness 0.15)
				)
			)
		)
		(property "Manufacturer" "Würth Elektronik"
			(at 302.806336 -123.58632 0)
			(layer "F.Fab")
			(hide yes)
			(effects
				(font
					(size 1 1)
					(thickness 0.15)
				)
			)
		)
		(property "VSD_class" "IO Header"
			(at 302.806336 -123.58632 0)
			(layer "F.Fab")
			(hide yes)
			(effects
				(font
					(size 1 1)
					(thickness 0.15)
				)
			)
		)
		(sheetname "Config SPI flash")
		(sheetfile "config-spi.kicad_sch")
		(attr through_hole)
		(fp_line
			(start 6.499 -1.401)
			(end 5.999 -1.401)
			(stroke
				(width 0.15)
				(type solid)
			)
			(layer "F.SilkS")
		)
		(fp_line
			(start 6.499 -1.401)
			(end 6.499 -0.902)
			(stroke
				(width 0.15)
				(type solid)
			)
			(layer "F.SilkS")
		)
		(fp_line
			(start -1.401 -1.401)
			(end -0.902 -1.401)
			(stroke
				(width 0.15)
				(type solid)
			)
			(layer "F.SilkS")
		)
		(fp_line
			(start -1.401 -1.401)
			(end -1.401 -0.902)
			(stroke
				(width 0.15)
				(type solid)
			)
			(layer "F.SilkS")
		)
		(fp_line
			(start 6.499 1.398)
			(end 6.499 0.9)
			(stroke
				(width 0.15)
				(type solid)
			)
			(layer "F.SilkS")
		)
		(fp_line
			(start 6.499 1.398)
			(end 5.999 1.398)
			(stroke
				(width 0.15)
				(type solid)
			)
			(layer "F.SilkS")
		)
		(fp_line
			(start -1.401 1.398)
			(end -1.401 0.9)
			(stroke
				(width 0.15)
				(type solid)
			)
			(layer "F.SilkS")
		)
		(fp_line
			(start -1.401 1.398)
			(end -0.902 1.398)
			(stroke
				(width 0.15)
				(type solid)
			)
			(layer "F.SilkS")
		)
		(fp_line
			(start 6.58 -1.52)
			(end 6.58 1.5)
			(stroke
				(width 0.05)
				(type solid)
			)
			(layer "F.CrtYd")
		)
		(fp_line
			(start -1.52 -1.52)
			(end 6.58 -1.52)
			(stroke
				(width 0.05)
				(type solid)
			)
			(layer "F.CrtYd")
		)
		(fp_line
			(start -1.52 -1.52)
			(end -1.52 1.5)
			(stroke
				(width 0.05)
				(type solid)
			)
			(layer "F.CrtYd")
		)
		(fp_line
			(start -1.52 1.5)
			(end 6.58 1.5)
			(stroke
				(width 0.05)
				(type solid)
			)
			(layer "F.CrtYd")
		)
		(fp_line
			(start 6.349 -1.27)
			(end 6.349 1.269)
			(stroke
				(width 0.15)
				(type solid)
			)
			(layer "F.Fab")
		)
		(fp_line
			(start -1.27 -1.27)
			(end 6.349 -1.27)
			(stroke
				(width 0.15)
				(type solid)
			)
			(layer "F.Fab")
		)
		(fp_line
			(start -1.27 -1.27)
			(end -1.27 1.269)
			(stroke
				(width 0.15)
				(type solid)
			)
			(layer "F.Fab")
		)
		(fp_line
			(start -1.27 1.269)
			(end 6.349 1.269)
			(stroke
				(width 0.15)
				(type solid)
			)
			(layer "F.Fab")
		)
		(pad "1" thru_hole rect
			(at 0 0 90)
			(size 1.7 1.7)
			(drill 1.1)
			(layers "*.Cu" "*.Mask")
			(remove_unused_layers no)
			(net 5 "GND")
			(pintype "passive")
		)
		(pad "2" thru_hole circle
			(at 2.539 0 90)
			(size 1.7 1.7)
			(drill 1.1)
			(layers "*.Cu" "*.Mask")
			(remove_unused_layers no)
			(net 14 "MODE2")
			(pintype "passive")
		)
		(pad "3" thru_hole circle
			(at 5.078 0 90)
			(size 1.7 1.7)
			(drill 1.1)
			(layers "*.Cu" "*.Mask")
			(remove_unused_layers no)
			(net 459 "3V3_SYS")
			(pintype "passive")
		)
	)
	(footprint "antmicro-footprints:PinHeader_1x3_P2.54mm_Drill1.1mm"
		(layer "F.Cu")
		(at 164.936328 120.547157 90)
		(property "Reference" "J8"
			(at 5.485157 -1.8 90)
			(layer "F.SilkS")
			(effects
				(font
					(size 0.7 0.7)
					(thickness 0.15)
				)
				(justify left bottom)
			)
		)
		(property "Value" "PinHeader_1x3_P2.54mm_Drill1.1mm"
			(at -1.6 2.7 90)
			(layer "F.Fab")
			(effects
				(font
					(size 0.7 0.7)
					(thickness 0.15)
				)
				(justify left bottom)
			)
		)
		(property "Description" "Pin Header, Vertical, Board-to-Board, 2.54 mm, 1 Rows, 3 Contacts, Through Hole Straight, WR-PHD"
			(at 0 0 90)
			(layer "F.Fab")
			(hide yes)
			(effects
				(font
					(size 1.27 1.27)
					(thickness 0.15)
				)
			)
		)
		(property "Author" "Antmicro"
			(at 285.483485 -44.389171 0)
			(layer "F.Fab")
			(hide yes)
			(effects
				(font
					(size 1 1)
					(thickness 0.15)
				)
			)
		)
		(property "License" "Apache-2.0"
			(at 285.483485 -44.389171 0)
			(layer "F.Fab")
			(hide yes)
			(effects
				(font
					(size 1 1)
					(thickness 0.15)
				)
			)
		)
		(property "MPN" "61300311121"
			(at 285.483485 -44.389171 0)
			(layer "F.Fab")
			(hide yes)
			(effects
				(font
					(size 1 1)
					(thickness 0.15)
				)
			)
		)
		(property "Manufacturer" "Würth Elektronik"
			(at 285.483485 -44.389171 0)
			(layer "F.Fab")
			(hide yes)
			(effects
				(font
					(size 1 1)
					(thickness 0.15)
				)
			)
		)
		(property "VSD_class" "IO Header"
			(at 285.483485 -44.389171 0)
			(layer "F.Fab")
			(hide yes)
			(effects
				(font
					(size 1 1)
					(thickness 0.15)
				)
			)
		)
		(sheetname "Supply")
		(sheetfile "supply.kicad_sch")
		(attr through_hole)
		(fp_line
			(start 6.499 -1.401)
			(end 5.999 -1.401)
			(stroke
				(width 0.15)
				(type solid)
			)
			(layer "F.SilkS")
		)
		(fp_line
			(start 6.499 -1.401)
			(end 6.499 -0.902)
			(stroke
				(width 0.15)
				(type solid)
			)
			(layer "F.SilkS")
		)
		(fp_line
			(start -1.401 -1.401)
			(end -0.902 -1.401)
			(stroke
				(width 0.15)
				(type solid)
			)
			(layer "F.SilkS")
		)
		(fp_line
			(start -1.401 -1.401)
			(end -1.401 -0.902)
			(stroke
				(width 0.15)
				(type solid)
			)
			(layer "F.SilkS")
		)
		(fp_line
			(start 6.499 1.398)
			(end 6.499 0.9)
			(stroke
				(width 0.15)
				(type solid)
			)
			(layer "F.SilkS")
		)
		(fp_line
			(start 6.499 1.398)
			(end 5.999 1.398)
			(stroke
				(width 0.15)
				(type solid)
			)
			(layer "F.SilkS")
		)
		(fp_line
			(start -1.401 1.398)
			(end -1.401 0.9)
			(stroke
				(width 0.15)
				(type solid)
			)
			(layer "F.SilkS")
		)
		(fp_line
			(start -1.401 1.398)
			(end -0.902 1.398)
			(stroke
				(width 0.15)
				(type solid)
			)
			(layer "F.SilkS")
		)
		(fp_line
			(start 6.58 -1.52)
			(end 6.58 1.5)
			(stroke
				(width 0.05)
				(type solid)
			)
			(layer "F.CrtYd")
		)
		(fp_line
			(start -1.52 -1.52)
			(end 6.58 -1.52)
			(stroke
				(width 0.05)
				(type solid)
			)
			(layer "F.CrtYd")
		)
		(fp_line
			(start -1.52 -1.52)
			(end -1.52 1.5)
			(stroke
				(width 0.05)
				(type solid)
			)
			(layer "F.CrtYd")
		)
		(fp_line
			(start -1.52 1.5)
			(end 6.58 1.5)
			(stroke
				(width 0.05)
				(type solid)
			)
			(layer "F.CrtYd")
		)
		(fp_line
			(start 6.349 -1.27)
			(end 6.349 1.269)
			(stroke
				(width 0.15)
				(type solid)
			)
			(layer "F.Fab")
		)
		(fp_line
			(start -1.27 -1.27)
			(end 6.349 -1.27)
			(stroke
				(width 0.15)
				(type solid)
			)
			(layer "F.Fab")
		)
		(fp_line
			(start -1.27 -1.27)
			(end -1.27 1.269)
			(stroke
				(width 0.15)
				(type solid)
			)
			(layer "F.Fab")
		)
		(fp_line
			(start -1.27 1.269)
			(end 6.349 1.269)
			(stroke
				(width 0.15)
				(type solid)
			)
			(layer "F.Fab")
		)
		(pad "1" thru_hole rect
			(at 0 0 90)
			(size 1.7 1.7)
			(drill 1.1)
			(layers "*.Cu" "*.Mask")
			(remove_unused_layers no)
			(net 463 "VCC5V0_INT")
			(pintype "passive")
		)
		(pad "2" thru_hole circle
			(at 2.539 0 90)
			(size 1.7 1.7)
			(drill 1.1)
			(layers "*.Cu" "*.Mask")
			(remove_unused_layers no)
			(net 603 "unconnected-(J8-Pad2)")
			(pintype "passive+no_connect")
		)
		(pad "3" thru_hole circle
			(at 5.078 0 90)
			(size 1.7 1.7)
			(drill 1.1)
			(layers "*.Cu" "*.Mask")
			(remove_unused_layers no)
			(net 5 "GND")
			(pintype "passive")
		)
	)
	(footprint "antmicro-footprints:antmicro-logo"
		(layer "F.Cu")
		(at 198.886328 51.020008)
		(property "Reference" "N1"
			(at 0.05 -5.5 0)
			(layer "F.SilkS")
			(hide yes)
			(effects
				(font
					(size 0.7 0.7)
					(thickness 0.15)
				)
				(justify left bottom)
			)
		)
		(property "Value" "antmicro_logo"
			(at -0.101 5.099 0)
			(layer "F.SilkS")
			(hide yes)
			(effects
				(font
					(size 0.7 0.7)
					(thickness 0.15)
				)
				(justify left bottom)
			)
		)
		(property "Author" "Antmicro"
			(at 0 0 0)
			(layer "F.Fab")
			(hide yes)
			(effects
				(font
					(size 1 1)
					(thickness 0.15)
				)
			)
		)
		(property "License" "Apache-2.0"
			(at 0 0 0)
			(layer "F.Fab")
			(hide yes)
			(effects
				(font
					(size 1 1)
					(thickness 0.15)
				)
			)
		)
		(property "MPN" ""
			(at 0 0 0)
			(layer "F.Fab")
			(hide yes)
			(effects
				(font
					(size 1 1)
					(thickness 0.15)
				)
			)
		)
		(property "Manufacturer" ""
			(at 0 0 0)
			(layer "F.Fab")
			(hide yes)
			(effects
				(font
					(size 1 1)
					(thickness 0.15)
				)
			)
		)
		(sheetfile "lpddr4-test-board.kicad_sch")
		(fp_poly
			(pts
				(xy 5.212 0.944) (xy 4.834 0.944) (xy 4.834 -1.292) (xy 5.212 -1.292) (xy 5.212 0.944)
			)
			(stroke
				(width 0.00186)
				(type solid)
			)
			(fill yes)
			(layer "F.Cu")
		)
		(fp_poly
			(pts
				(xy 8.164 -1.321) (xy 8.193 -1.317) (xy 8.204 -1.31) (xy 8.204 -1.308) (xy 8.2 -1.285) (xy 8.188 -1.24)
				(xy 8.171 -1.181) (xy 8.163 -1.156) (xy 8.142 -1.092) (xy 8.126 -1.053) (xy 8.112 -1.034) (xy 8.097 -1.031)
				(xy 8.094 -1.032) (xy 7.996 -1.053) (xy 7.886 -1.06) (xy 7.778 -1.053) (xy 7.683 -1.032) (xy 7.665 -1.026)
				(xy 7.622 -1.009) (xy 7.622 0.944) (xy 7.244 0.944) (xy 7.244 -1.178) (xy 7.358 -1.219) (xy 7.457 -1.253)
				(xy 7.548 -1.277) (xy 7.639 -1.295) (xy 7.738 -1.307) (xy 7.856 -1.315) (xy 7.94 -1.319) (xy 8.042 -1.322)
				(xy 8.115 -1.322) (xy 8.164 -1.321)
			)
			(stroke
				(width 0.00186)
				(type solid)
			)
			(fill yes)
			(layer "F.Cu")
		)
		(fp_poly
			(pts
				(xy 0.795 -1.891) (xy 0.798 -1.849) (xy 0.8 -1.786) (xy 0.802 -1.705) (xy 0.803 -1.612) (xy 0.803 -1.599)
				(xy 0.803 -1.292) (xy 1.181 -1.292) (xy 1.181 -1.04) (xy 0.803 -1.04) (xy 0.803 0.498) (xy 0.838 0.566)
				(xy 0.885 0.631) (xy 0.944 0.671) (xy 1.021 0.688) (xy 1.082 0.689) (xy 1.181 0.685) (xy 1.181 0.806)
				(xy 1.178 0.88) (xy 1.17 0.926) (xy 1.161 0.939) (xy 1.138 0.945) (xy 1.09 0.95) (xy 1.028 0.954)
				(xy 0.984 0.956) (xy 0.897 0.957) (xy 0.832 0.953) (xy 0.778 0.942) (xy 0.743 0.931) (xy 0.647 0.886)
				(xy 0.571 0.823) (xy 0.508 0.737) (xy 0.488 0.701) (xy 0.433 0.593) (xy 0.428 -0.223) (xy 0.424 -1.04)
				(xy 0.173 -1.04) (xy 0.173 -1.292) (xy 0.425 -1.292) (xy 0.425 -1.795) (xy 0.603 -1.85) (xy 0.673 -1.872)
				(xy 0.733 -1.89) (xy 0.774 -1.902) (xy 0.792 -1.906) (xy 0.795 -1.891)
			)
			(stroke
				(width 0.00186)
				(type solid)
			)
			(fill yes)
			(layer "F.Cu")
		)
		(fp_poly
			(pts
				(xy -0.82 -1.315) (xy -0.737 -1.312) (xy -0.672 -1.308) (xy -0.621 -1.301) (xy -0.577 -1.291) (xy -0.56 -1.286)
				(xy -0.417 -1.232) (xy -0.302 -1.164) (xy -0.212 -1.082) (xy -0.154 -0.996) (xy -0.135 -0.961) (xy -0.119 -0.927)
				(xy -0.105 -0.893) (xy -0.094 -0.855) (xy -0.085 -0.811) (xy -0.078 -0.758) (xy -0.073 -0.693) (xy -0.069 -0.612)
				(xy -0.067 -0.515) (xy -0.065 -0.397) (xy -0.064 -0.256) (xy -0.064 -0.088) (xy -0.063 0.105) (xy -0.063 0.944)
				(xy -0.441 0.944) (xy -0.441 0.113) (xy -0.442 -0.083) (xy -0.442 -0.25) (xy -0.443 -0.391) (xy -0.445 -0.508)
				(xy -0.448 -0.604) (xy -0.452 -0.682) (xy -0.457 -0.744) (xy -0.465 -0.794) (xy -0.474 -0.833) (xy -0.486 -0.864)
				(xy -0.501 -0.89) (xy -0.518 -0.913) (xy -0.538 -0.937) (xy -0.539 -0.939) (xy -0.604 -0.997) (xy -0.684 -1.039)
				(xy -0.784 -1.066) (xy -0.822 -1.072) (xy -0.927 -1.078) (xy -1.044 -1.073) (xy -1.158 -1.056) (xy -1.24 -1.034)
				(xy -1.3 -1.013) (xy -1.304 -0.034) (xy -1.308 0.944) (xy -1.686 0.944) (xy -1.686 -1.178) (xy -1.54 -1.225)
				(xy -1.44 -1.257) (xy -1.354 -1.28) (xy -1.276 -1.297) (xy -1.195 -1.307) (xy -1.105 -1.313) (xy -0.995 -1.315)
				(xy -0.93 -1.315) (xy -0.82 -1.315)
			)
			(stroke
				(width 0.00186)
				(type solid)
			)
			(fill yes)
			(layer "F.Cu")
		)
		(fp_poly
			(pts
				(xy 3.757 -1.312) (xy 3.91 -1.278) (xy 4.043 -1.223) (xy 4.153 -1.146) (xy 4.24 -1.047) (xy 4.282 -0.977)
				(xy 4.299 -0.943) (xy 4.313 -0.91) (xy 4.325 -0.876) (xy 4.335 -0.837) (xy 4.343 -0.791) (xy 4.349 -0.734)
				(xy 4.353 -0.665) (xy 4.357 -0.581) (xy 4.359 -0.478) (xy 4.361 -0.354) (xy 4.361 -0.206) (xy 4.362 -0.031)
				(xy 4.362 0.111) (xy 4.362 0.944) (xy 3.985 0.944) (xy 3.98 0.074) (xy 3.976 -0.796) (xy 3.93 -0.879)
				(xy 3.867 -0.961) (xy 3.786 -1.022) (xy 3.691 -1.062) (xy 3.586 -1.079) (xy 3.476 -1.074) (xy 3.366 -1.045)
				(xy 3.26 -0.994) (xy 3.185 -0.938) (xy 3.118 -0.88) (xy 3.118 0.944) (xy 2.74 0.944) (xy 2.74 0.092)
				(xy 2.739 -0.122) (xy 2.739 -0.305) (xy 2.737 -0.459) (xy 2.735 -0.585) (xy 2.732 -0.683) (xy 2.729 -0.755)
				(xy 2.725 -0.802) (xy 2.722 -0.821) (xy 2.679 -0.91) (xy 2.613 -0.981) (xy 2.523 -1.034) (xy 2.413 -1.067)
				(xy 2.284 -1.079) (xy 2.154 -1.073) (xy 2.082 -1.064) (xy 2.031 -1.056) (xy 1.989 -1.046) (xy 1.944 -1.031)
				(xy 1.917 -1.021) (xy 1.874 -1.005) (xy 1.874 0.944) (xy 1.511 0.944) (xy 1.511 -1.18) (xy 1.661 -1.228)
				(xy 1.83 -1.276) (xy 1.988 -1.306) (xy 2.148 -1.319) (xy 2.314 -1.319) (xy 2.448 -1.311) (xy 2.557 -1.297)
				(xy 2.649 -1.272) (xy 2.732 -1.237) (xy 2.811 -1.189) (xy 2.843 -1.165) (xy 2.947 -1.087) (xy 3.012 -1.14)
				(xy 3.14 -1.224) (xy 3.283 -1.283) (xy 3.443 -1.315) (xy 3.582 -1.323) (xy 3.757 -1.312)
			)
			(stroke
				(width 0.00186)
				(type solid)
			)
			(fill yes)
			(layer "F.Cu")
		)
		(fp_poly
			(pts
				(xy 9.278 -1.313) (xy 9.419 -1.281) (xy 9.543 -1.225) (xy 9.656 -1.146) (xy 9.708 -1.097) (xy 9.808 -0.975)
				(xy 9.887 -0.831) (xy 9.945 -0.666) (xy 9.984 -0.476) (xy 9.998 -0.354) (xy 10.005 -0.134) (xy 9.992 0.072)
				(xy 9.96 0.262) (xy 9.908 0.434) (xy 9.837 0.585) (xy 9.749 0.714) (xy 9.643 0.819) (xy 9.578 0.867)
				(xy 9.475 0.918) (xy 9.352 0.956) (xy 9.219 0.98) (xy 9.087 0.986) (xy 8.966 0.975) (xy 8.81 0.933)
				(xy 8.673 0.864) (xy 8.553 0.771) (xy 8.452 0.653) (xy 8.371 0.511) (xy 8.31 0.346) (xy 8.277 0.202)
				(xy 8.249 -0.011) (xy 8.243 -0.182) (xy 8.619 -0.182) (xy 8.626 -0.007) (xy 8.647 0.163) (xy 8.682 0.318)
				(xy 8.73 0.449) (xy 8.792 0.552) (xy 8.87 0.633) (xy 8.961 0.69) (xy 9.06 0.721) (xy 9.164 0.724)
				(xy 9.268 0.699) (xy 9.303 0.683) (xy 9.391 0.625) (xy 9.465 0.546) (xy 9.524 0.443) (xy 9.569 0.315)
				(xy 9.601 0.162) (xy 9.62 0) (xy 9.628 -0.198) (xy 9.62 -0.382) (xy 9.597 -0.55) (xy 9.558 -0.698)
				(xy 9.505 -0.825) (xy 9.439 -0.927) (xy 9.397 -0.971) (xy 9.307 -1.035) (xy 9.21 -1.071) (xy 9.109 -1.079)
				(xy 9.009 -1.062) (xy 8.915 -1.019) (xy 8.831 -0.953) (xy 8.76 -0.863) (xy 8.733 -0.813) (xy 8.684 -0.68)
				(xy 8.648 -0.526) (xy 8.627 -0.358) (xy 8.619 -0.182) (xy 8.243 -0.182) (xy 8.242 -0.218) (xy 8.255 -0.417)
				(xy 8.288 -0.602) (xy 8.339 -0.772) (xy 8.41 -0.923) (xy 8.498 -1.051) (xy 8.524 -1.081) (xy 8.637 -1.182)
				(xy 8.765 -1.255) (xy 8.908 -1.302) (xy 9.068 -1.322) (xy 9.117 -1.323) (xy 9.278 -1.313)
			)
			(stroke
				(width 0.00186)
				(type solid)
			)
			(fill yes)
			(layer "F.Cu")
		)
		(fp_poly
			(pts
				(xy 6.48 -1.32) (xy 6.584 -1.31) (xy 6.642 -1.3) (xy 6.701 -1.282) (xy 6.765 -1.259) (xy 6.825 -1.233)
				(xy 6.873 -1.209) (xy 6.9 -1.189) (xy 6.902 -1.186) (xy 6.901 -1.166) (xy 6.889 -1.128) (xy 6.872 -1.079)
				(xy 6.852 -1.03) (xy 6.833 -0.989) (xy 6.818 -0.966) (xy 6.815 -0.963) (xy 6.795 -0.969) (xy 6.757 -0.985)
				(xy 6.717 -1.002) (xy 6.597 -1.044) (xy 6.478 -1.06) (xy 6.365 -1.05) (xy 6.267 -1.016) (xy 6.184 -0.957)
				(xy 6.109 -0.87) (xy 6.042 -0.76) (xy 5.988 -0.629) (xy 5.964 -0.554) (xy 5.946 -0.461) (xy 5.934 -0.347)
				(xy 5.929 -0.22) (xy 5.931 -0.091) (xy 5.938 0.032) (xy 5.953 0.138) (xy 5.965 0.191) (xy 6.018 0.347)
				(xy 6.085 0.476) (xy 6.166 0.576) (xy 6.262 0.649) (xy 6.269 0.653) (xy 6.318 0.678) (xy 6.36 0.692)
				(xy 6.409 0.698) (xy 6.476 0.7) (xy 6.48 0.7) (xy 6.551 0.697) (xy 6.613 0.686) (xy 6.676 0.665)
				(xy 6.75 0.631) (xy 6.805 0.602) (xy 6.811 0.606) (xy 6.823 0.627) (xy 6.842 0.667) (xy 6.868 0.73)
				(xy 6.904 0.819) (xy 6.907 0.827) (xy 6.898 0.844) (xy 6.866 0.868) (xy 6.818 0.895) (xy 6.759 0.922)
				(xy 6.697 0.945) (xy 6.68 0.95) (xy 6.596 0.968) (xy 6.494 0.98) (xy 6.388 0.984) (xy 6.292 0.98)
				(xy 6.251 0.975) (xy 6.192 0.96) (xy 6.121 0.935) (xy 6.055 0.906) (xy 5.924 0.825) (xy 5.811 0.718)
				(xy 5.717 0.586) (xy 5.641 0.431) (xy 5.585 0.252) (xy 5.566 0.164) (xy 5.552 0.061) (xy 5.545 -0.061)
				(xy 5.544 -0.193) (xy 5.549 -0.327) (xy 5.56 -0.453) (xy 5.576 -0.563) (xy 5.589 -0.623) (xy 5.65 -0.797)
				(xy 5.731 -0.949) (xy 5.831 -1.077) (xy 5.948 -1.181) (xy 6.081 -1.259) (xy 6.187 -1.298) (xy 6.27 -1.314)
				(xy 6.372 -1.322) (xy 6.48 -1.32)
			)
			(stroke
				(width 0.00186)
				(type solid)
			)
			(fill yes)
			(layer "F.Cu")
		)
		(fp_poly
			(pts
				(xy -2.763 -1.313) (xy -2.663 -1.294) (xy -2.55 -1.259) (xy -2.459 -1.216) (xy -2.38 -1.16) (xy -2.341 -1.124)
				(xy -2.284 -1.053) (xy -2.232 -0.961) (xy -2.192 -0.861) (xy -2.174 -0.79) (xy -2.17 -0.754) (xy -2.167 -0.69)
				(xy -2.164 -0.599) (xy -2.162 -0.485) (xy -2.16 -0.35) (xy -2.159 -0.196) (xy -2.158 -0.027) (xy -2.158 0.064)
				(xy -2.158 0.833) (xy -2.232 0.865) (xy -2.364 0.913) (xy -2.517 0.949) (xy -2.682 0.974) (xy -2.85 0.986)
				(xy -3.011 0.983) (xy -3.097 0.975) (xy -3.264 0.942) (xy -3.407 0.889) (xy -3.525 0.817) (xy -3.618 0.725)
				(xy -3.686 0.616) (xy -3.729 0.487) (xy -3.746 0.341) (xy -3.746 0.268) (xy -3.744 0.254) (xy -3.383 0.254)
				(xy -3.38 0.384) (xy -3.352 0.497) (xy -3.298 0.591) (xy -3.221 0.665) (xy -3.12 0.719) (xy -3.072 0.735)
				(xy -3.011 0.745) (xy -2.928 0.75) (xy -2.835 0.75) (xy -2.74 0.744) (xy -2.655 0.734) (xy -2.589 0.72)
				(xy -2.579 0.716) (xy -2.504 0.689) (xy -2.504 -0.302) (xy -2.595 -0.291) (xy -2.653 -0.282) (xy -2.728 -0.267)
				(xy -2.806 -0.25) (xy -2.831 -0.244) (xy -2.992 -0.194) (xy -3.125 -0.133) (xy -3.229 -0.06) (xy -3.306 0.026)
				(xy -3.357 0.125) (xy -3.381 0.238) (xy -3.383 0.254) (xy -3.744 0.254) (xy -3.725 0.126) (xy -3.678 0)
				(xy -3.602 -0.112) (xy -3.559 -0.158) (xy -3.465 -0.233) (xy -3.343 -0.303) (xy -3.198 -0.365) (xy -3.034 -0.417)
				(xy -2.856 -0.46) (xy -2.666 -0.49) (xy -2.663 -0.49) (xy -2.5 -0.51) (xy -2.51 -0.644) (xy -2.528 -0.77)
				(xy -2.564 -0.871) (xy -2.62 -0.949) (xy -2.697 -1.007) (xy -2.797 -1.045) (xy -2.845 -1.056) (xy -2.975 -1.067)
				(xy -3.12 -1.056) (xy -3.272 -1.024) (xy -3.426 -0.972) (xy -3.439 -0.967) (xy -3.488 -0.947) (xy -3.523 -0.936)
				(xy -3.537 -0.934) (xy -3.545 -0.95) (xy -3.56 -0.987) (xy -3.579 -1.035) (xy -3.598 -1.086) (xy -3.613 -1.129)
				(xy -3.622 -1.155) (xy -3.623 -1.159) (xy -3.609 -1.169) (xy -3.575 -1.188) (xy -3.537 -1.206) (xy -3.395 -1.257)
				(xy -3.239 -1.294) (xy -3.075 -1.316) (xy -2.914 -1.323) (xy -2.763 -1.313)
			)
			(stroke
				(width 0.00186)
				(type solid)
			)
			(fill yes)
			(layer "F.Cu")
		)
		(fp_poly
			(pts
				(xy -7.153 -3.366) (xy -7.087 -3.351) (xy -7.086 -3.351) (xy -7.066 -3.34) (xy -7.021 -3.315) (xy -6.953 -3.277)
				(xy -6.865 -3.227) (xy -6.759 -3.167) (xy -6.639 -3.099) (xy -6.505 -3.022) (xy -6.361 -2.94) (xy -6.209 -2.853)
				(xy -6.052 -2.762) (xy -5.891 -2.67) (xy -5.729 -2.577) (xy -5.569 -2.485) (xy -5.413 -2.395) (xy -5.264 -2.309)
				(xy -5.123 -2.227) (xy -4.994 -2.152) (xy -4.878 -2.085) (xy -4.778 -2.027) (xy -4.697 -1.979) (xy -4.636 -1.943)
				(xy -4.599 -1.921) (xy -4.595 -1.918) (xy -4.528 -1.863) (xy -4.476 -1.798) (xy -4.434 -1.725) (xy -4.429 -0.224)
				(xy -4.429 0.063) (xy -4.428 0.323) (xy -4.429 0.553) (xy -4.429 0.755) (xy -4.43 0.928) (xy -4.432 1.071)
				(xy -4.434 1.184) (xy -4.436 1.266) (xy -4.439 1.318) (xy -4.441 1.337) (xy -4.448 1.36) (xy -4.454 1.382)
				(xy -4.463 1.403) (xy -4.476 1.423) (xy -4.494 1.445) (xy -4.519 1.47) (xy -4.552 1.497) (xy -4.596 1.529)
				(xy -4.652 1.567) (xy -4.721 1.611) (xy -4.805 1.663) (xy -4.906 1.723) (xy -5.025 1.794) (xy -5.165 1.875)
				(xy -5.326 1.969) (xy -5.511 2.076) (xy -5.72 2.197) (xy -5.813 2.251) (xy -7.079 2.982) (xy -7.197 2.988)
				(xy -7.315 2.994) (xy -7.78 2.727) (xy -8.064 2.563) (xy -8.323 2.415) (xy -8.557 2.28) (xy -8.767 2.159)
				(xy -8.955 2.051) (xy -9.122 1.954) (xy -9.27 1.868) (xy -9.399 1.792) (xy -9.51 1.726) (xy -9.606 1.669)
				(xy -9.688 1.619) (xy -9.756 1.576) (xy -9.812 1.539) (xy -9.857 1.507) (xy -9.893 1.481) (xy -9.92 1.458)
				(xy -9.94 1.437) (xy -9.955 1.42) (xy -9.965 1.403) (xy -9.972 1.387) (xy -9.977 1.371) (xy -9.981 1.354)
				(xy -9.985 1.337) (xy -9.988 1.309) (xy -9.991 1.25) (xy -9.993 1.161) (xy -9.995 1.041) (xy -9.996 0.891)
				(xy -9.997 0.712) (xy -9.998 0.503) (xy -9.998 0.266) (xy -9.997 0) (xy -9.997 -0.189) (xy -9.024 -0.189)
				(xy -9.024 0.015) (xy -9.024 0.191) (xy -9.023 0.34) (xy -9.022 0.464) (xy -9.021 0.567) (xy -9.018 0.65)
				(xy -9.014 0.717) (xy -9.01 0.768) (xy -9.003 0.808) (xy -8.995 0.837) (xy -8.986 0.859) (xy -8.974 0.876)
				(xy -8.961 0.891) (xy -8.945 0.905) (xy -8.943 0.906) (xy -8.922 0.921) (xy -8.877 0.949) (xy -8.81 0.989)
				(xy -8.725 1.039) (xy -8.625 1.098) (xy -8.512 1.164) (xy -8.389 1.235) (xy -8.26 1.31) (xy -8.128 1.386)
				(xy -7.995 1.463) (xy -7.864 1.538) (xy -7.739 1.609) (xy -7.622 1.676) (xy -7.517 1.735) (xy -7.425 1.787)
				(xy -7.351 1.828) (xy -7.297 1.857) (xy -7.266 1.872) (xy -7.261 1.874) (xy -7.222 1.885) (xy -7.195 1.886)
				(xy -7.163 1.875) (xy -7.144 1.867) (xy -7.117 1.854) (xy -7.067 1.827) (xy -6.997 1.788) (xy -6.909 1.738)
				(xy -6.805 1.679) (xy -6.691 1.614) (xy -6.567 1.543) (xy -6.438 1.469) (xy -6.306 1.392) (xy -6.174 1.316)
				(xy -6.045 1.241) (xy -5.922 1.17) (xy -5.809 1.103) (xy -5.708 1.044) (xy -5.622 0.992) (xy -5.553 0.952)
				(xy -5.507 0.923) (xy -5.484 0.907) (xy -5.483 0.907) (xy -5.467 0.892) (xy -5.453 0.878) (xy -5.441 0.861)
				(xy -5.431 0.839) (xy -5.423 0.81) (xy -5.417 0.772) (xy -5.412 0.721) (xy -5.408 0.656) (xy -5.406 0.574)
				(xy -5.404 0.473) (xy -5.403 0.35) (xy -5.402 0.203) (xy -5.402 0.03) (xy -5.402 -0.172) (xy -5.402 -0.189)
				(xy -5.402 -0.395) (xy -5.402 -0.572) (xy -5.403 -0.721) (xy -5.404 -0.847) (xy -5.406 -0.95) (xy -5.408 -1.034)
				(xy -5.412 -1.101) (xy -5.418 -1.153) (xy -5.425 -1.193) (xy -5.434 -1.223) (xy -5.445 -1.245) (xy -5.458 -1.262)
				(xy -5.473 -1.276) (xy -5.491 -1.29) (xy -5.499 -1.295) (xy -5.522 -1.31) (xy -5.57 -1.339) (xy -5.64 -1.381)
				(xy -5.729 -1.433) (xy -5.835 -1.496) (xy -5.956 -1.566) (xy -6.088 -1.643) (xy -6.229 -1.725) (xy -6.348 -1.793)
				(xy -6.519 -1.891) (xy -6.664 -1.974) (xy -6.786 -2.044) (xy -6.888 -2.101) (xy -6.971 -2.147) (xy -7.038 -2.183)
				(xy -7.091 -2.21) (xy -7.132 -2.229) (xy -7.163 -2.242) (xy -7.187 -2.249) (xy -7.205 -2.252) (xy -7.211 -2.252)
				(xy -7.228 -2.251) (xy -7.249 -2.246) (xy -7.276 -2.236) (xy -7.312 -2.219) (xy -7.359 -2.196) (xy -7.419 -2.165)
				(xy -7.495 -2.123) (xy -7.587 -2.072) (xy -7.699 -2.008) (xy -7.832 -1.932) (xy -7.99 -1.842) (xy -8.1 -1.778)
				(xy -8.248 -1.693) (xy -8.388 -1.611) (xy -8.519 -1.535) (xy -8.637 -1.466) (xy -8.739 -1.406) (xy -8.825 -1.355)
				(xy -8.89 -1.316) (xy -8.933 -1.29) (xy -8.951 -1.278) (xy -8.966 -1.265) (xy -8.978 -1.251) (xy -8.989 -1.234)
				(xy -8.998 -1.212) (xy -9.005 -1.182) (xy -9.011 -1.141) (xy -9.015 -1.087) (xy -9.018 -1.019) (xy -9.021 -0.933)
				(xy -9.022 -0.827) (xy -9.023 -0.699) (xy -9.024 -0.546) (xy -9.024 -0.366) (xy -9.024 -0.189) (xy -9.997 -0.189)
				(xy -9.997 -0.224) (xy -9.996 -0.479) (xy -9.996 -0.705) (xy -9.995 -0.903) (xy -9.994 -1.075) (xy -9.993 -1.223)
				(xy -9.992 -1.35) (xy -9.99 -1.456) (xy -9.987 -1.545) (xy -9.984 -1.617) (xy -9.98 -1.675) (xy -9.974 -1.721)
				(xy -9.968 -1.757) (xy -9.961 -1.784) (xy -9.952 -1.805) (xy -9.941 -1.821) (xy -9.929 -1.834) (xy -9.915 -1.847)
				(xy -9.9 -1.86) (xy -9.893 -1.866) (xy -9.873 -1.88) (xy -9.828 -1.909) (xy -9.759 -1.951) (xy -9.669 -2.005)
				(xy -9.56 -2.07) (xy -9.433 -2.145) (xy -9.291 -2.228) (xy -9.136 -2.319) (xy -8.969 -2.416) (xy -8.793 -2.518)
				(xy -8.61 -2.624) (xy -8.59 -2.635) (xy -8.377 -2.759) (xy -8.189 -2.867) (xy -8.024 -2.962) (xy -7.882 -3.044)
				(xy -7.759 -3.114) (xy -7.656 -3.173) (xy -7.568 -3.221) (xy -7.496 -3.261) (xy -7.437 -3.293) (xy -7.389 -3.317)
				(xy -7.351 -3.336) (xy -7.321 -3.349) (xy -7.296 -3.357) (xy -7.276 -3.363) (xy -7.259 -3.366) (xy -7.242 -3.367)
				(xy -7.237 -3.368) (xy -7.153 -3.366)
			)
			(stroke
				(width 0.00186)
				(type solid)
			)
			(fill yes)
			(layer "F.Cu")
		)
		(fp_poly
			(pts
				(xy -7.128 -1.48) (xy -7.114 -1.475) (xy -7.042 -1.428) (xy -6.989 -1.361) (xy -6.96 -1.281) (xy -6.957 -1.196)
				(xy -6.961 -1.175) (xy -6.992 -1.094) (xy -7.046 -1.034) (xy -7.101 -1.001) (xy -7.166 -0.969) (xy -7.166 -0.599)
				(xy -6.891 -0.599) (xy -6.778 -0.711) (xy -6.665 -0.824) (xy -6.673 -0.905) (xy -6.673 -0.906) (xy -6.566 -0.906)
				(xy -6.549 -0.87) (xy -6.512 -0.853) (xy -6.467 -0.856) (xy -6.435 -0.876) (xy -6.412 -0.913) (xy -6.42 -0.95)
				(xy -6.441 -0.977) (xy -6.471 -1.002) (xy -6.496 -1.005) (xy -6.53 -0.986) (xy -6.532 -0.984) (xy -6.56 -0.949)
				(xy -6.566 -0.906) (xy -6.673 -0.906) (xy -6.676 -0.957) (xy -6.669 -0.992) (xy -6.648 -1.025) (xy -6.639 -1.036)
				(xy -6.582 -1.084) (xy -6.519 -1.106) (xy -6.456 -1.105) (xy -6.397 -1.084) (xy -6.349 -1.044) (xy -6.316 -0.99)
				(xy -6.304 -0.925) (xy -6.315 -0.859) (xy -6.351 -0.797) (xy -6.408 -0.757) (xy -6.484 -0.741) (xy -6.497 -0.741)
				(xy -6.529 -0.74) (xy -6.557 -0.734) (xy -6.585 -0.719) (xy -6.619 -0.693) (xy -6.667 -0.651) (xy -6.705 -0.615)
				(xy -6.84 -0.489) (xy -7.166 -0.489) (xy -7.166 -0.237) (xy -6.568 -0.237) (xy -6.545 -0.282) (xy -6.502 -0.333)
				(xy -6.443 -0.364) (xy -6.377 -0.373) (xy -6.311 -0.36) (xy -6.255 -0.322) (xy -6.249 -0.317) (xy -6.209 -0.253)
				(xy -6.195 -0.188) (xy -6.205 -0.126) (xy -6.234 -0.072) (xy -6.28 -0.03) (xy -6.337 -0.006) (xy -6.402 -0.002)
				(xy -6.472 -0.025) (xy -6.486 -0.033) (xy -6.523 -0.061) (xy -6.545 -0.091) (xy -6.547 -0.096) (xy -6.552 -0.106)
				(xy -6.561 -0.114) (xy -6.58 -0.12) (xy -6.613 -0.123) (xy -6.664 -0.125) (xy -6.737 -0.126) (xy -6.836 -0.126)
				(xy -6.861 -0.126) (xy -7.166 -0.126) (xy -7.166 0.11) (xy -6.842 0.11) (xy -6.581 0.373) (xy -6.507 0.366)
				(xy -6.428 0.372) (xy -6.367 0.402) (xy -6.325 0.457) (xy -6.314 0.486) (xy -6.304 0.561) (xy -6.322 0.626)
				(xy -6.361 0.678) (xy -6.422 0.72) (xy -6.487 0.736) (xy -6.55 0.727) (xy -6.605 0.697) (xy -6.648 0.648)
				(xy -6.671 0.583) (xy -6.672 0.536) (xy -6.564 0.536) (xy -6.559 0.575) (xy -6.544 0.597) (xy -6.508 0.625)
				(xy -6.474 0.623) (xy -6.441 0.598) (xy -6.414 0.56) (xy -6.417 0.525) (xy -6.44 0.497) (xy -6.48 0.476)
				(xy -6.518 0.48) (xy -6.549 0.502) (xy -6.564 0.536) (xy -6.672 0.536) (xy -6.673 0.52) (xy -6.664 0.445)
				(xy -6.891 0.22) (xy -7.166 0.22) (xy -7.166 0.593) (xy -7.101 0.622) (xy -7.033 0.668) (xy -6.986 0.732)
				(xy -6.96 0.805) (xy -6.956 0.883) (xy -6.973 0.959) (xy -7.013 1.026) (xy -7.074 1.079) (xy -7.088 1.087)
				(xy -7.171 1.112) (xy -7.258 1.112) (xy -7.34 1.087) (xy -7.341 1.086) (xy -7.406 1.036) (xy -7.448 0.97)
				(xy -7.469 0.895) (xy -7.468 0.858) (xy -7.361 0.858) (xy -7.355 0.905) (xy -7.331 0.942) (xy -7.31 0.962)
				(xy -7.252 0.999) (xy -7.195 1.005) (xy -7.137 0.979) (xy -7.116 0.962) (xy -7.08 0.923) (xy -7.066 0.883)
				(xy -7.065 0.858) (xy -7.079 0.801) (xy -7.116 0.751) (xy -7.167 0.718) (xy -7.213 0.708) (xy -7.27 0.722)
				(xy -7.319 0.76) (xy -7.352 0.812) (xy -7.361 0.858) (xy -7.468 0.858) (xy -7.468 0.817) (xy -7.445 0.742)
				(xy -7.401 0.677) (xy -7.336 0.628) (xy -7.325 0.622) (xy -7.26 0.593) (xy -7.26 0.22) (xy -7.535 0.22)
				(xy -7.762 0.445) (xy -7.753 0.52) (xy -7.757 0.595) (xy -7.785 0.658) (xy -7.83 0.703) (xy -7.887 0.73)
				(xy -7.951 0.735) (xy -8.015 0.715) (xy -8.065 0.678) (xy -8.109 0.617) (xy -8.123 0.551) (xy -8.12 0.532)
				(xy -8.012 0.532) (xy -8.009 0.566) (xy -7.985 0.598) (xy -7.946 0.625) (xy -7.912 0.623) (xy -7.883 0.599)
				(xy -7.863 0.558) (xy -7.868 0.517) (xy -7.896 0.486) (xy -7.915 0.478) (xy -7.961 0.48) (xy -7.985 0.496)
				(xy -8.012 0.532) (xy -8.12 0.532) (xy -8.112 0.486) (xy -8.079 0.422) (xy -8.025 0.381) (xy -7.953 0.365)
				(xy -7.919 0.366) (xy -7.845 0.373) (xy -7.584 0.11) (xy -7.26 0.11) (xy -7.26 -0.126) (xy -7.566 -0.126)
				(xy -7.672 -0.126) (xy -7.75 -0.126) (xy -7.805 -0.124) (xy -7.841 -0.121) (xy -7.863 -0.116) (xy -7.875 -0.108)
				(xy -7.881 -0.098) (xy -7.883 -0.094) (xy -7.908 -0.058) (xy -7.954 -0.026) (xy -8.009 -0.005) (xy -8.045 -0.001)
				(xy -8.117 -0.014) (xy -8.174 -0.049) (xy -8.213 -0.102) (xy -8.23 -0.164) (xy -8.228 -0.186) (xy -8.124 -0.186)
				(xy -8.12 -0.163) (xy -8.104 -0.143) (xy -8.063 -0.115) (xy -8.021 -0.117) (xy -7.994 -0.135) (xy -7.971 -0.176)
				(xy -7.976 -0.202) (xy -6.455 -0.202) (xy -6.449 -0.158) (xy -6.432 -0.135) (xy -6.392 -0.113) (xy -6.35 -0.121)
				(xy -6.322 -0.143) (xy -6.303 -0.169) (xy -6.304 -0.193) (xy -6.316 -0.218) (xy -6.35 -0.254) (xy -6.39 -0.265)
				(xy -6.429 -0.247) (xy -6.432 -0.244) (xy -6.455 -0.202) (xy -7.976 -0.202) (xy -7.979 -0.218) (xy -7.999 -0.244)
				(xy -8.04 -0.265) (xy -8.078 -0.255) (xy -8.11 -0.218) (xy -8.124 -0.186) (xy -8.228 -0.186) (xy -8.224 -0.232)
				(xy -8.192 -0.297) (xy -8.177 -0.317) (xy -8.121 -0.358) (xy -8.055 -0.374) (xy -7.988 -0.365) (xy -7.927 -0.333)
				(xy -7.885 -0.284) (xy -7.857 -0.237) (xy -7.26 -0.237) (xy -7.26 -0.489) (xy -7.586 -0.489) (xy -7.721 -0.615)
				(xy -7.779 -0.669) (xy -7.821 -0.704) (xy -7.852 -0.726) (xy -7.879 -0.737) (xy -7.908 -0.74) (xy -7.934 -0.741)
				(xy -8.011 -0.752) (xy -8.068 -0.787) (xy -8.105 -0.846) (xy -8.112 -0.866) (xy -8.119 -0.923) (xy -8.016 -0.923)
				(xy -8.003 -0.887) (xy -7.969 -0.862) (xy -7.928 -0.852) (xy -7.888 -0.861) (xy -7.878 -0.87) (xy -7.86 -0.907)
				(xy -7.866 -0.949) (xy -7.894 -0.984) (xy -7.924 -1.002) (xy -7.941 -1.008) (xy -7.964 -0.997) (xy -7.991 -0.969)
				(xy -8.011 -0.939) (xy -8.016 -0.923) (xy -8.119 -0.923) (xy -8.121 -0.94) (xy -8.105 -1.004) (xy -8.069 -1.055)
				(xy -8.018 -1.091) (xy -7.958 -1.108) (xy -7.894 -1.104) (xy -7.831 -1.076) (xy -7.787 -1.036) (xy -7.762 -1.001)
				(xy -7.751 -0.968) (xy -7.751 -0.923) (xy -7.753 -0.905) (xy -7.762 -0.824) (xy -7.648 -0.711) (xy -7.535 -0.599)
				(xy -7.26 -0.599) (xy -7.26 -0.971) (xy -7.323 -0.998) (xy -7.396 -1.046) (xy -7.446 -1.114) (xy -7.465 -1.166)
				(xy -7.472 -1.24) (xy -7.365 -1.24) (xy -7.359 -1.204) (xy -7.347 -1.177) (xy -7.307 -1.123) (xy -7.254 -1.093)
				(xy -7.194 -1.09) (xy -7.134 -1.116) (xy -7.127 -1.121) (xy -7.081 -1.171) (xy -7.065 -1.225) (xy -7.078 -1.283)
				(xy -7.116 -1.342) (xy -7.166 -1.375) (xy -7.222 -1.384) (xy -7.278 -1.368) (xy -7.326 -1.326) (xy -7.354 -1.278)
				(xy -7.365 -1.24) (xy -7.472 -1.24) (xy -7.474 -1.25) (xy -7.455 -1.328) (xy -7.416 -1.396) (xy -7.358 -1.449)
				(xy -7.288 -1.484) (xy -7.21 -1.495) (xy -7.128 -1.48)
			)
			(stroke
				(width 0.00186)
				(type solid)
			)
			(fill yes)
			(layer "F.Cu")
		)
		(fp_poly
			(pts
				(xy 5.212 0.944) (xy 4.834 0.944) (xy 4.834 -1.292) (xy 5.212 -1.292) (xy 5.212 0.944)
			)
			(stroke
				(width 0.00186)
				(type solid)
			)
			(fill yes)
			(layer "F.Mask")
		)
		(fp_poly
			(pts
				(xy 8.164 -1.321) (xy 8.193 -1.317) (xy 8.204 -1.31) (xy 8.204 -1.308) (xy 8.2 -1.285) (xy 8.188 -1.24)
				(xy 8.171 -1.181) (xy 8.163 -1.156) (xy 8.142 -1.092) (xy 8.126 -1.053) (xy 8.112 -1.034) (xy 8.097 -1.031)
				(xy 8.094 -1.032) (xy 7.996 -1.053) (xy 7.886 -1.06) (xy 7.778 -1.053) (xy 7.683 -1.032) (xy 7.665 -1.026)
				(xy 7.622 -1.009) (xy 7.622 0.944) (xy 7.244 0.944) (xy 7.244 -1.178) (xy 7.358 -1.219) (xy 7.457 -1.253)
				(xy 7.548 -1.277) (xy 7.639 -1.295) (xy 7.738 -1.307) (xy 7.856 -1.315) (xy 7.94 -1.319) (xy 8.042 -1.322)
				(xy 8.115 -1.322) (xy 8.164 -1.321)
			)
			(stroke
				(width 0.00186)
				(type solid)
			)
			(fill yes)
			(layer "F.Mask")
		)
		(fp_poly
			(pts
				(xy 0.795 -1.891) (xy 0.798 -1.849) (xy 0.8 -1.786) (xy 0.802 -1.705) (xy 0.803 -1.612) (xy 0.803 -1.599)
				(xy 0.803 -1.292) (xy 1.181 -1.292) (xy 1.181 -1.04) (xy 0.803 -1.04) (xy 0.803 0.498) (xy 0.838 0.566)
				(xy 0.885 0.631) (xy 0.944 0.671) (xy 1.021 0.688) (xy 1.082 0.689) (xy 1.181 0.685) (xy 1.181 0.806)
				(xy 1.178 0.88) (xy 1.17 0.926) (xy 1.161 0.939) (xy 1.138 0.945) (xy 1.09 0.95) (xy 1.028 0.954)
				(xy 0.984 0.956) (xy 0.897 0.957) (xy 0.832 0.953) (xy 0.778 0.942) (xy 0.743 0.931) (xy 0.647 0.886)
				(xy 0.571 0.823) (xy 0.508 0.737) (xy 0.488 0.701) (xy 0.433 0.593) (xy 0.428 -0.223) (xy 0.424 -1.04)
				(xy 0.173 -1.04) (xy 0.173 -1.292) (xy 0.425 -1.292) (xy 0.425 -1.795) (xy 0.603 -1.85) (xy 0.673 -1.872)
				(xy 0.733 -1.89) (xy 0.774 -1.902) (xy 0.792 -1.906) (xy 0.795 -1.891)
			)
			(stroke
				(width 0.00186)
				(type solid)
			)
			(fill yes)
			(layer "F.Mask")
		)
		(fp_poly
			(pts
				(xy -0.82 -1.315) (xy -0.737 -1.312) (xy -0.672 -1.308) (xy -0.621 -1.301) (xy -0.577 -1.291) (xy -0.56 -1.286)
				(xy -0.417 -1.232) (xy -0.302 -1.164) (xy -0.212 -1.082) (xy -0.154 -0.996) (xy -0.135 -0.961) (xy -0.119 -0.927)
				(xy -0.105 -0.893) (xy -0.094 -0.855) (xy -0.085 -0.811) (xy -0.078 -0.758) (xy -0.073 -0.693) (xy -0.069 -0.612)
				(xy -0.067 -0.515) (xy -0.065 -0.397) (xy -0.064 -0.256) (xy -0.064 -0.088) (xy -0.063 0.105) (xy -0.063 0.944)
				(xy -0.441 0.944) (xy -0.441 0.113) (xy -0.442 -0.083) (xy -0.442 -0.25) (xy -0.443 -0.391) (xy -0.445 -0.508)
				(xy -0.448 -0.604) (xy -0.452 -0.682) (xy -0.457 -0.744) (xy -0.465 -0.794) (xy -0.474 -0.833) (xy -0.486 -0.864)
				(xy -0.501 -0.89) (xy -0.518 -0.913) (xy -0.538 -0.937) (xy -0.539 -0.939) (xy -0.604 -0.997) (xy -0.684 -1.039)
				(xy -0.784 -1.066) (xy -0.822 -1.072) (xy -0.927 -1.078) (xy -1.044 -1.073) (xy -1.158 -1.056) (xy -1.24 -1.034)
				(xy -1.3 -1.013) (xy -1.304 -0.034) (xy -1.308 0.944) (xy -1.686 0.944) (xy -1.686 -1.178) (xy -1.54 -1.225)
				(xy -1.44 -1.257) (xy -1.354 -1.28) (xy -1.276 -1.297) (xy -1.195 -1.307) (xy -1.105 -1.313) (xy -0.995 -1.315)
				(xy -0.93 -1.315) (xy -0.82 -1.315)
			)
			(stroke
				(width 0.00186)
				(type solid)
			)
			(fill yes)
			(layer "F.Mask")
		)
		(fp_poly
			(pts
				(xy 3.757 -1.312) (xy 3.91 -1.278) (xy 4.043 -1.223) (xy 4.153 -1.146) (xy 4.24 -1.047) (xy 4.282 -0.977)
				(xy 4.299 -0.943) (xy 4.313 -0.91) (xy 4.325 -0.876) (xy 4.335 -0.837) (xy 4.343 -0.791) (xy 4.349 -0.734)
				(xy 4.353 -0.665) (xy 4.357 -0.581) (xy 4.359 -0.478) (xy 4.361 -0.354) (xy 4.361 -0.206) (xy 4.362 -0.031)
				(xy 4.362 0.111) (xy 4.362 0.944) (xy 3.985 0.944) (xy 3.98 0.074) (xy 3.976 -0.796) (xy 3.93 -0.879)
				(xy 3.867 -0.961) (xy 3.786 -1.022) (xy 3.691 -1.062) (xy 3.586 -1.079) (xy 3.476 -1.074) (xy 3.366 -1.045)
				(xy 3.26 -0.994) (xy 3.185 -0.938) (xy 3.118 -0.88) (xy 3.118 0.944) (xy 2.74 0.944) (xy 2.74 0.092)
				(xy 2.739 -0.122) (xy 2.739 -0.305) (xy 2.737 -0.459) (xy 2.735 -0.585) (xy 2.732 -0.683) (xy 2.729 -0.755)
				(xy 2.725 -0.802) (xy 2.722 -0.821) (xy 2.679 -0.91) (xy 2.613 -0.981) (xy 2.523 -1.034) (xy 2.413 -1.067)
				(xy 2.284 -1.079) (xy 2.154 -1.073) (xy 2.082 -1.064) (xy 2.031 -1.056) (xy 1.989 -1.046) (xy 1.944 -1.031)
				(xy 1.917 -1.021) (xy 1.874 -1.005) (xy 1.874 0.944) (xy 1.511 0.944) (xy 1.511 -1.18) (xy 1.661 -1.228)
				(xy 1.83 -1.276) (xy 1.988 -1.306) (xy 2.148 -1.319) (xy 2.314 -1.319) (xy 2.448 -1.311) (xy 2.557 -1.297)
				(xy 2.649 -1.272) (xy 2.732 -1.237) (xy 2.811 -1.189) (xy 2.843 -1.165) (xy 2.947 -1.087) (xy 3.012 -1.14)
				(xy 3.14 -1.224) (xy 3.283 -1.283) (xy 3.443 -1.315) (xy 3.582 -1.323) (xy 3.757 -1.312)
			)
			(stroke
				(width 0.00186)
				(type solid)
			)
			(fill yes)
			(layer "F.Mask")
		)
		(fp_poly
			(pts
				(xy 9.278 -1.313) (xy 9.419 -1.281) (xy 9.543 -1.225) (xy 9.656 -1.146) (xy 9.708 -1.097) (xy 9.808 -0.975)
				(xy 9.887 -0.831) (xy 9.945 -0.666) (xy 9.984 -0.476) (xy 9.998 -0.354) (xy 10.005 -0.134) (xy 9.992 0.072)
				(xy 9.96 0.262) (xy 9.908 0.434) (xy 9.837 0.585) (xy 9.749 0.714) (xy 9.643 0.819) (xy 9.578 0.867)
				(xy 9.475 0.918) (xy 9.352 0.956) (xy 9.219 0.98) (xy 9.087 0.986) (xy 8.966 0.975) (xy 8.81 0.933)
				(xy 8.673 0.864) (xy 8.553 0.771) (xy 8.452 0.653) (xy 8.371 0.511) (xy 8.31 0.346) (xy 8.277 0.202)
				(xy 8.249 -0.011) (xy 8.243 -0.182) (xy 8.619 -0.182) (xy 8.626 -0.007) (xy 8.647 0.163) (xy 8.682 0.318)
				(xy 8.73 0.449) (xy 8.792 0.552) (xy 8.87 0.633) (xy 8.961 0.69) (xy 9.06 0.721) (xy 9.164 0.724)
				(xy 9.268 0.699) (xy 9.303 0.683) (xy 9.391 0.625) (xy 9.465 0.546) (xy 9.524 0.443) (xy 9.569 0.315)
				(xy 9.601 0.162) (xy 9.62 0) (xy 9.628 -0.198) (xy 9.62 -0.382) (xy 9.597 -0.55) (xy 9.558 -0.698)
				(xy 9.505 -0.825) (xy 9.439 -0.927) (xy 9.397 -0.971) (xy 9.307 -1.035) (xy 9.21 -1.071) (xy 9.109 -1.079)
				(xy 9.009 -1.062) (xy 8.915 -1.019) (xy 8.831 -0.953) (xy 8.76 -0.863) (xy 8.733 -0.813) (xy 8.684 -0.68)
				(xy 8.648 -0.526) (xy 8.627 -0.358) (xy 8.619 -0.182) (xy 8.243 -0.182) (xy 8.242 -0.218) (xy 8.255 -0.417)
				(xy 8.288 -0.602) (xy 8.339 -0.772) (xy 8.41 -0.923) (xy 8.498 -1.051) (xy 8.524 -1.081) (xy 8.637 -1.182)
				(xy 8.765 -1.255) (xy 8.908 -1.302) (xy 9.068 -1.322) (xy 9.117 -1.323) (xy 9.278 -1.313)
			)
			(stroke
				(width 0.00186)
				(type solid)
			)
			(fill yes)
			(layer "F.Mask")
		)
		(fp_poly
			(pts
				(xy 6.48 -1.32) (xy 6.584 -1.31) (xy 6.642 -1.3) (xy 6.701 -1.282) (xy 6.765 -1.259) (xy 6.825 -1.233)
				(xy 6.873 -1.209) (xy 6.9 -1.189) (xy 6.902 -1.186) (xy 6.901 -1.166) (xy 6.889 -1.128) (xy 6.872 -1.079)
				(xy 6.852 -1.03) (xy 6.833 -0.989) (xy 6.818 -0.966) (xy 6.815 -0.963) (xy 6.795 -0.969) (xy 6.757 -0.985)
				(xy 6.717 -1.002) (xy 6.597 -1.044) (xy 6.478 -1.06) (xy 6.365 -1.05) (xy 6.267 -1.016) (xy 6.184 -0.957)
				(xy 6.109 -0.87) (xy 6.042 -0.76) (xy 5.988 -0.629) (xy 5.964 -0.554) (xy 5.946 -0.461) (xy 5.934 -0.347)
				(xy 5.929 -0.22) (xy 5.931 -0.091) (xy 5.938 0.032) (xy 5.953 0.138) (xy 5.965 0.191) (xy 6.018 0.347)
				(xy 6.085 0.476) (xy 6.166 0.576) (xy 6.262 0.649) (xy 6.269 0.653) (xy 6.318 0.678) (xy 6.36 0.692)
				(xy 6.409 0.698) (xy 6.476 0.7) (xy 6.48 0.7) (xy 6.551 0.697) (xy 6.613 0.686) (xy 6.676 0.665)
				(xy 6.75 0.631) (xy 6.805 0.602) (xy 6.811 0.606) (xy 6.823 0.627) (xy 6.842 0.667) (xy 6.868 0.73)
				(xy 6.904 0.819) (xy 6.907 0.827) (xy 6.898 0.844) (xy 6.866 0.868) (xy 6.818 0.895) (xy 6.759 0.922)
				(xy 6.697 0.945) (xy 6.68 0.95) (xy 6.596 0.968) (xy 6.494 0.98) (xy 6.388 0.984) (xy 6.292 0.98)
				(xy 6.251 0.975) (xy 6.192 0.96) (xy 6.121 0.935) (xy 6.055 0.906) (xy 5.924 0.825) (xy 5.811 0.718)
				(xy 5.717 0.586) (xy 5.641 0.431) (xy 5.585 0.252) (xy 5.566 0.164) (xy 5.552 0.061) (xy 5.545 -0.061)
				(xy 5.544 -0.193) (xy 5.549 -0.327) (xy 5.56 -0.453) (xy 5.576 -0.563) (xy 5.589 -0.623) (xy 5.65 -0.797)
				(xy 5.731 -0.949) (xy 5.831 -1.077) (xy 5.948 -1.181) (xy 6.081 -1.259) (xy 6.187 -1.298) (xy 6.27 -1.314)
				(xy 6.372 -1.322) (xy 6.48 -1.32)
			)
			(stroke
				(width 0.00186)
				(type solid)
			)
			(fill yes)
			(layer "F.Mask")
		)
		(fp_poly
			(pts
				(xy -2.763 -1.313) (xy -2.663 -1.294) (xy -2.55 -1.259) (xy -2.459 -1.216) (xy -2.38 -1.16) (xy -2.341 -1.124)
				(xy -2.284 -1.053) (xy -2.232 -0.961) (xy -2.192 -0.861) (xy -2.174 -0.79) (xy -2.17 -0.754) (xy -2.167 -0.69)
				(xy -2.164 -0.599) (xy -2.162 -0.485) (xy -2.16 -0.35) (xy -2.159 -0.196) (xy -2.158 -0.027) (xy -2.158 0.064)
				(xy -2.158 0.833) (xy -2.232 0.865) (xy -2.364 0.913) (xy -2.517 0.949) (xy -2.682 0.974) (xy -2.85 0.986)
				(xy -3.011 0.983) (xy -3.097 0.975) (xy -3.264 0.942) (xy -3.407 0.889) (xy -3.525 0.817) (xy -3.618 0.725)
				(xy -3.686 0.616) (xy -3.729 0.487) (xy -3.746 0.341) (xy -3.746 0.268) (xy -3.744 0.254) (xy -3.383 0.254)
				(xy -3.38 0.384) (xy -3.352 0.497) (xy -3.298 0.591) (xy -3.221 0.665) (xy -3.12 0.719) (xy -3.072 0.735)
				(xy -3.011 0.745) (xy -2.928 0.75) (xy -2.835 0.75) (xy -2.74 0.744) (xy -2.655 0.734) (xy -2.589 0.72)
				(xy -2.579 0.716) (xy -2.504 0.689) (xy -2.504 -0.302) (xy -2.595 -0.291) (xy -2.653 -0.282) (xy -2.728 -0.267)
				(xy -2.806 -0.25) (xy -2.831 -0.244) (xy -2.992 -0.194) (xy -3.125 -0.133) (xy -3.229 -0.06) (xy -3.306 0.026)
				(xy -3.357 0.125) (xy -3.381 0.238) (xy -3.383 0.254) (xy -3.744 0.254) (xy -3.725 0.126) (xy -3.678 0)
				(xy -3.602 -0.112) (xy -3.559 -0.158) (xy -3.465 -0.233) (xy -3.343 -0.303) (xy -3.198 -0.365) (xy -3.034 -0.417)
				(xy -2.856 -0.46) (xy -2.666 -0.49) (xy -2.663 -0.49) (xy -2.5 -0.51) (xy -2.51 -0.644) (xy -2.528 -0.77)
				(xy -2.564 -0.871) (xy -2.62 -0.949) (xy -2.697 -1.007) (xy -2.797 -1.045) (xy -2.845 -1.056) (xy -2.975 -1.067)
				(xy -3.12 -1.056) (xy -3.272 -1.024) (xy -3.426 -0.972) (xy -3.439 -0.967) (xy -3.488 -0.947) (xy -3.523 -0.936)
				(xy -3.537 -0.934) (xy -3.545 -0.95) (xy -3.56 -0.987) (xy -3.579 -1.035) (xy -3.598 -1.086) (xy -3.613 -1.129)
				(xy -3.622 -1.155) (xy -3.623 -1.159) (xy -3.609 -1.169) (xy -3.575 -1.188) (xy -3.537 -1.206) (xy -3.395 -1.257)
				(xy -3.239 -1.294) (xy -3.075 -1.316) (xy -2.914 -1.323) (xy -2.763 -1.313)
			)
			(stroke
				(width 0.00186)
				(type solid)
			)
			(fill yes)
			(layer "F.Mask")
		)
		(fp_poly
			(pts
				(xy -7.153 -3.366) (xy -7.087 -3.351) (xy -7.086 -3.351) (xy -7.066 -3.34) (xy -7.021 -3.315) (xy -6.953 -3.277)
				(xy -6.865 -3.227) (xy -6.759 -3.167) (xy -6.639 -3.099) (xy -6.505 -3.022) (xy -6.361 -2.94) (xy -6.209 -2.853)
				(xy -6.052 -2.762) (xy -5.891 -2.67) (xy -5.729 -2.577) (xy -5.569 -2.485) (xy -5.413 -2.395) (xy -5.264 -2.309)
				(xy -5.123 -2.227) (xy -4.994 -2.152) (xy -4.878 -2.085) (xy -4.778 -2.027) (xy -4.697 -1.979) (xy -4.636 -1.943)
				(xy -4.599 -1.921) (xy -4.595 -1.918) (xy -4.528 -1.863) (xy -4.476 -1.798) (xy -4.434 -1.725) (xy -4.429 -0.224)
				(xy -4.429 0.063) (xy -4.428 0.323) (xy -4.429 0.553) (xy -4.429 0.755) (xy -4.43 0.928) (xy -4.432 1.071)
				(xy -4.434 1.184) (xy -4.436 1.266) (xy -4.439 1.318) (xy -4.441 1.337) (xy -4.448 1.36) (xy -4.454 1.382)
				(xy -4.463 1.403) (xy -4.476 1.423) (xy -4.494 1.445) (xy -4.519 1.47) (xy -4.552 1.497) (xy -4.596 1.529)
				(xy -4.652 1.567) (xy -4.721 1.611) (xy -4.805 1.663) (xy -4.906 1.723) (xy -5.025 1.794) (xy -5.165 1.875)
				(xy -5.326 1.969) (xy -5.511 2.076) (xy -5.72 2.197) (xy -5.813 2.251) (xy -7.079 2.982) (xy -7.197 2.988)
				(xy -7.315 2.994) (xy -7.78 2.727) (xy -8.064 2.563) (xy -8.323 2.415) (xy -8.557 2.28) (xy -8.767 2.159)
				(xy -8.955 2.051) (xy -9.122 1.954) (xy -9.27 1.868) (xy -9.399 1.792) (xy -9.51 1.726) (xy -9.606 1.669)
				(xy -9.688 1.619) (xy -9.756 1.576) (xy -9.812 1.539) (xy -9.857 1.507) (xy -9.893 1.481) (xy -9.92 1.458)
				(xy -9.94 1.437) (xy -9.955 1.42) (xy -9.965 1.403) (xy -9.972 1.387) (xy -9.977 1.371) (xy -9.981 1.354)
				(xy -9.985 1.337) (xy -9.988 1.309) (xy -9.991 1.25) (xy -9.993 1.161) (xy -9.995 1.041) (xy -9.996 0.891)
				(xy -9.997 0.712) (xy -9.998 0.503) (xy -9.998 0.266) (xy -9.997 0) (xy -9.997 -0.189) (xy -9.024 -0.189)
				(xy -9.024 0.015) (xy -9.024 0.191) (xy -9.023 0.34) (xy -9.022 0.464) (xy -9.021 0.567) (xy -9.018 0.65)
				(xy -9.014 0.717) (xy -9.01 0.768) (xy -9.003 0.808) (xy -8.995 0.837) (xy -8.986 0.859) (xy -8.974 0.876)
				(xy -8.961 0.891) (xy -8.945 0.905) (xy -8.943 0.906) (xy -8.922 0.921) (xy -8.877 0.949) (xy -8.81 0.989)
				(xy -8.725 1.039) (xy -8.625 1.098) (xy -8.512 1.164) (xy -8.389 1.235) (xy -8.26 1.31) (xy -8.128 1.386)
				(xy -7.995 1.463) (xy -7.864 1.538) (xy -7.739 1.609) (xy -7.622 1.676) (xy -7.517 1.735) (xy -7.425 1.787)
				(xy -7.351 1.828) (xy -7.297 1.857) (xy -7.266 1.872) (xy -7.261 1.874) (xy -7.222 1.885) (xy -7.195 1.886)
				(xy -7.163 1.875) (xy -7.144 1.867) (xy -7.117 1.854) (xy -7.067 1.827) (xy -6.997 1.788) (xy -6.909 1.738)
				(xy -6.805 1.679) (xy -6.691 1.614) (xy -6.567 1.543) (xy -6.438 1.469) (xy -6.306 1.392) (xy -6.174 1.316)
				(xy -6.045 1.241) (xy -5.922 1.17) (xy -5.809 1.103) (xy -5.708 1.044) (xy -5.622 0.992) (xy -5.553 0.952)
				(xy -5.507 0.923) (xy -5.484 0.907) (xy -5.483 0.907) (xy -5.467 0.892) (xy -5.453 0.878) (xy -5.441 0.861)
				(xy -5.431 0.839) (xy -5.423 0.81) (xy -5.417 0.772) (xy -5.412 0.721) (xy -5.408 0.656) (xy -5.406 0.574)
				(xy -5.404 0.473) (xy -5.403 0.35) (xy -5.402 0.203) (xy -5.402 0.03) (xy -5.402 -0.172) (xy -5.402 -0.189)
				(xy -5.402 -0.395) (xy -5.402 -0.572) (xy -5.403 -0.721) (xy -5.404 -0.847) (xy -5.406 -0.95) (xy -5.408 -1.034)
				(xy -5.412 -1.101) (xy -5.418 -1.153) (xy -5.425 -1.193) (xy -5.434 -1.223) (xy -5.445 -1.245) (xy -5.458 -1.262)
				(xy -5.473 -1.276) (xy -5.491 -1.29) (xy -5.499 -1.295) (xy -5.522 -1.31) (xy -5.57 -1.339) (xy -5.64 -1.381)
				(xy -5.729 -1.433) (xy -5.835 -1.496) (xy -5.956 -1.566) (xy -6.088 -1.643) (xy -6.229 -1.725) (xy -6.348 -1.793)
				(xy -6.519 -1.891) (xy -6.664 -1.974) (xy -6.786 -2.044) (xy -6.888 -2.101) (xy -6.971 -2.147) (xy -7.038 -2.183)
				(xy -7.091 -2.21) (xy -7.132 -2.229) (xy -7.163 -2.242) (xy -7.187 -2.249) (xy -7.205 -2.252) (xy -7.211 -2.252)
				(xy -7.228 -2.251) (xy -7.249 -2.246) (xy -7.276 -2.236) (xy -7.312 -2.219) (xy -7.359 -2.196) (xy -7.419 -2.165)
				(xy -7.495 -2.123) (xy -7.587 -2.072) (xy -7.699 -2.008) (xy -7.832 -1.932) (xy -7.99 -1.842) (xy -8.1 -1.778)
				(xy -8.248 -1.693) (xy -8.388 -1.611) (xy -8.519 -1.535) (xy -8.637 -1.466) (xy -8.739 -1.406) (xy -8.825 -1.355)
				(xy -8.89 -1.316) (xy -8.933 -1.29) (xy -8.951 -1.278) (xy -8.966 -1.265) (xy -8.978 -1.251) (xy -8.989 -1.234)
				(xy -8.998 -1.212) (xy -9.005 -1.182) (xy -9.011 -1.141) (xy -9.015 -1.087) (xy -9.018 -1.019) (xy -9.021 -0.933)
				(xy -9.022 -0.827) (xy -9.023 -0.699) (xy -9.024 -0.546) (xy -9.024 -0.366) (xy -9.024 -0.189) (xy -9.997 -0.189)
				(xy -9.997 -0.224) (xy -9.996 -0.479) (xy -9.996 -0.705) (xy -9.995 -0.903) (xy -9.994 -1.075) (xy -9.993 -1.223)
				(xy -9.992 -1.35) (xy -9.99 -1.456) (xy -9.987 -1.545) (xy -9.984 -1.617) (xy -9.98 -1.675) (xy -9.974 -1.721)
				(xy -9.968 -1.757) (xy -9.961 -1.784) (xy -9.952 -1.805) (xy -9.941 -1.821) (xy -9.929 -1.834) (xy -9.915 -1.847)
				(xy -9.9 -1.86) (xy -9.893 -1.866) (xy -9.873 -1.88) (xy -9.828 -1.909) (xy -9.759 -1.951) (xy -9.669 -2.005)
				(xy -9.56 -2.07) (xy -9.433 -2.145) (xy -9.291 -2.228) (xy -9.136 -2.319) (xy -8.969 -2.416) (xy -8.793 -2.518)
				(xy -8.61 -2.624) (xy -8.59 -2.635) (xy -8.377 -2.759) (xy -8.189 -2.867) (xy -8.024 -2.962) (xy -7.882 -3.044)
				(xy -7.759 -3.114) (xy -7.656 -3.173) (xy -7.568 -3.221) (xy -7.496 -3.261) (xy -7.437 -3.293) (xy -7.389 -3.317)
				(xy -7.351 -3.336) (xy -7.321 -3.349) (xy -7.296 -3.357) (xy -7.276 -3.363) (xy -7.259 -3.366) (xy -7.242 -3.367)
				(xy -7.237 -3.368) (xy -7.153 -3.366)
			)
			(stroke
				(width 0.00186)
				(type solid)
			)
			(fill yes)
			(layer "F.Mask")
		)
		(fp_poly
			(pts
				(xy -7.128 -1.48) (xy -7.114 -1.475) (xy -7.042 -1.428) (xy -6.989 -1.361) (xy -6.96 -1.281) (xy -6.957 -1.196)
				(xy -6.961 -1.175) (xy -6.992 -1.094) (xy -7.046 -1.034) (xy -7.101 -1.001) (xy -7.166 -0.969) (xy -7.166 -0.599)
				(xy -6.891 -0.599) (xy -6.778 -0.711) (xy -6.665 -0.824) (xy -6.673 -0.905) (xy -6.673 -0.906) (xy -6.566 -0.906)
				(xy -6.549 -0.87) (xy -6.512 -0.853) (xy -6.467 -0.856) (xy -6.435 -0.876) (xy -6.412 -0.913) (xy -6.42 -0.95)
				(xy -6.441 -0.977) (xy -6.471 -1.002) (xy -6.496 -1.005) (xy -6.53 -0.986) (xy -6.532 -0.984) (xy -6.56 -0.949)
				(xy -6.566 -0.906) (xy -6.673 -0.906) (xy -6.676 -0.957) (xy -6.669 -0.992) (xy -6.648 -1.025) (xy -6.639 -1.036)
				(xy -6.582 -1.084) (xy -6.519 -1.106) (xy -6.456 -1.105) (xy -6.397 -1.084) (xy -6.349 -1.044) (xy -6.316 -0.99)
				(xy -6.304 -0.925) (xy -6.315 -0.859) (xy -6.351 -0.797) (xy -6.408 -0.757) (xy -6.484 -0.741) (xy -6.497 -0.741)
				(xy -6.529 -0.74) (xy -6.557 -0.734) (xy -6.585 -0.719) (xy -6.619 -0.693) (xy -6.667 -0.651) (xy -6.705 -0.615)
				(xy -6.84 -0.489) (xy -7.166 -0.489) (xy -7.166 -0.237) (xy -6.568 -0.237) (xy -6.545 -0.282) (xy -6.502 -0.333)
				(xy -6.443 -0.364) (xy -6.377 -0.373) (xy -6.311 -0.36) (xy -6.255 -0.322) (xy -6.249 -0.317) (xy -6.209 -0.253)
				(xy -6.195 -0.188) (xy -6.205 -0.126) (xy -6.234 -0.072) (xy -6.28 -0.03) (xy -6.337 -0.006) (xy -6.402 -0.002)
				(xy -6.472 -0.025) (xy -6.486 -0.033) (xy -6.523 -0.061) (xy -6.545 -0.091) (xy -6.547 -0.096) (xy -6.552 -0.106)
				(xy -6.561 -0.114) (xy -6.58 -0.12) (xy -6.613 -0.123) (xy -6.664 -0.125) (xy -6.737 -0.126) (xy -6.836 -0.126)
				(xy -6.861 -0.126) (xy -7.166 -0.126) (xy -7.166 0.11) (xy -6.842 0.11) (xy -6.581 0.373) (xy -6.507 0.366)
				(xy -6.428 0.372) (xy -6.367 0.402) (xy -6.325 0.457) (xy -6.314 0.486) (xy -6.304 0.561) (xy -6.322 0.626)
				(xy -6.361 0.678) (xy -6.422 0.72) (xy -6.487 0.736) (xy -6.55 0.727) (xy -6.605 0.697) (xy -6.648 0.648)
				(xy -6.671 0.583) (xy -6.672 0.536) (xy -6.564 0.536) (xy -6.559 0.575) (xy -6.544 0.597) (xy -6.508 0.625)
				(xy -6.474 0.623) (xy -6.441 0.598) (xy -6.414 0.56) (xy -6.417 0.525) (xy -6.44 0.497) (xy -6.48 0.476)
				(xy -6.518 0.48) (xy -6.549 0.502) (xy -6.564 0.536) (xy -6.672 0.536) (xy -6.673 0.52) (xy -6.664 0.445)
				(xy -6.891 0.22) (xy -7.166 0.22) (xy -7.166 0.593) (xy -7.101 0.622) (xy -7.033 0.668) (xy -6.986 0.732)
				(xy -6.96 0.805) (xy -6.956 0.883) (xy -6.973 0.959) (xy -7.013 1.026) (xy -7.074 1.079) (xy -7.088 1.087)
				(xy -7.171 1.112) (xy -7.258 1.112) (xy -7.34 1.087) (xy -7.341 1.086) (xy -7.406 1.036) (xy -7.448 0.97)
				(xy -7.469 0.895) (xy -7.468 0.858) (xy -7.361 0.858) (xy -7.355 0.905) (xy -7.331 0.942) (xy -7.31 0.962)
				(xy -7.252 0.999) (xy -7.195 1.005) (xy -7.137 0.979) (xy -7.116 0.962) (xy -7.08 0.923) (xy -7.066 0.883)
				(xy -7.065 0.858) (xy -7.079 0.801) (xy -7.116 0.751) (xy -7.167 0.718) (xy -7.213 0.708) (xy -7.27 0.722)
				(xy -7.319 0.76) (xy -7.352 0.812) (xy -7.361 0.858) (xy -7.468 0.858) (xy -7.468 0.817) (xy -7.445 0.742)
				(xy -7.401 0.677) (xy -7.336 0.628) (xy -7.325 0.622) (xy -7.26 0.593) (xy -7.26 0.22) (xy -7.535 0.22)
				(xy -7.762 0.445) (xy -7.753 0.52) (xy -7.757 0.595) (xy -7.785 0.658) (xy -7.83 0.703) (xy -7.887 0.73)
				(xy -7.951 0.735) (xy -8.015 0.715) (xy -8.065 0.678) (xy -8.109 0.617) (xy -8.123 0.551) (xy -8.12 0.532)
				(xy -8.012 0.532) (xy -8.009 0.566) (xy -7.985 0.598) (xy -7.946 0.625) (xy -7.912 0.623) (xy -7.883 0.599)
				(xy -7.863 0.558) (xy -7.868 0.517) (xy -7.896 0.486) (xy -7.915 0.478) (xy -7.961 0.48) (xy -7.985 0.496)
				(xy -8.012 0.532) (xy -8.12 0.532) (xy -8.112 0.486) (xy -8.079 0.422) (xy -8.025 0.381) (xy -7.953 0.365)
				(xy -7.919 0.366) (xy -7.845 0.373) (xy -7.584 0.11) (xy -7.26 0.11) (xy -7.26 -0.126) (xy -7.566 -0.126)
				(xy -7.672 -0.126) (xy -7.75 -0.126) (xy -7.805 -0.124) (xy -7.841 -0.121) (xy -7.863 -0.116) (xy -7.875 -0.108)
				(xy -7.881 -0.098) (xy -7.883 -0.094) (xy -7.908 -0.058) (xy -7.954 -0.026) (xy -8.009 -0.005) (xy -8.045 -0.001)
				(xy -8.117 -0.014) (xy -8.174 -0.049) (xy -8.213 -0.102) (xy -8.23 -0.164) (xy -8.228 -0.186) (xy -8.124 -0.186)
				(xy -8.12 -0.163) (xy -8.104 -0.143) (xy -8.063 -0.115) (xy -8.021 -0.117) (xy -7.994 -0.135) (xy -7.971 -0.176)
				(xy -7.976 -0.202) (xy -6.455 -0.202) (xy -6.449 -0.158) (xy -6.432 -0.135) (xy -6.392 -0.113) (xy -6.35 -0.121)
				(xy -6.322 -0.143) (xy -6.303 -0.169) (xy -6.304 -0.193) (xy -6.316 -0.218) (xy -6.35 -0.254) (xy -6.39 -0.265)
				(xy -6.429 -0.247) (xy -6.432 -0.244) (xy -6.455 -0.202) (xy -7.976 -0.202) (xy -7.979 -0.218) (xy -7.999 -0.244)
				(xy -8.04 -0.265) (xy -8.078 -0.255) (xy -8.11 -0.218) (xy -8.124 -0.186) (xy -8.228 -0.186) (xy -8.224 -0.232)
				(xy -8.192 -0.297) (xy -8.177 -0.317) (xy -8.121 -0.358) (xy -8.055 -0.374) (xy -7.988 -0.365) (xy -7.927 -0.333)
				(xy -7.885 -0.284) (xy -7.857 -0.237) (xy -7.26 -0.237) (xy -7.26 -0.489) (xy -7.586 -0.489) (xy -7.721 -0.615)
				(xy -7.779 -0.669) (xy -7.821 -0.704) (xy -7.852 -0.726) (xy -7.879 -0.737) (xy -7.908 -0.74) (xy -7.934 -0.741)
				(xy -8.011 -0.752) (xy -8.068 -0.787) (xy -8.105 -0.846) (xy -8.112 -0.866) (xy -8.119 -0.923) (xy -8.016 -0.923)
				(xy -8.003 -0.887) (xy -7.969 -0.862) (xy -7.928 -0.852) (xy -7.888 -0.861) (xy -7.878 -0.87) (xy -7.86 -0.907)
				(xy -7.866 -0.949) (xy -7.894 -0.984) (xy -7.924 -1.002) (xy -7.941 -1.008) (xy -7.964 -0.997) (xy -7.991 -0.969)
				(xy -8.011 -0.939) (xy -8.016 -0.923) (xy -8.119 -0.923) (xy -8.121 -0.94) (xy -8.105 -1.004) (xy -8.069 -1.055)
				(xy -8.018 -1.091) (xy -7.958 -1.108) (xy -7.894 -1.104) (xy -7.831 -1.076) (xy -7.787 -1.036) (xy -7.762 -1.001)
				(xy -7.751 -0.968) (xy -7.751 -0.923) (xy -7.753 -0.905) (xy -7.762 -0.824) (xy -7.648 -0.711) (xy -7.535 -0.599)
				(xy -7.26 -0.599) (xy -7.26 -0.971) (xy -7.323 -0.998) (xy -7.396 -1.046) (xy -7.446 -1.114) (xy -7.465 -1.166)
				(xy -7.472 -1.24) (xy -7.365 -1.24) (xy -7.359 -1.204) (xy -7.347 -1.177) (xy -7.307 -1.123) (xy -7.254 -1.093)
				(xy -7.194 -1.09) (xy -7.134 -1.116) (xy -7.127 -1.121) (xy -7.081 -1.171) (xy -7.065 -1.225) (xy -7.078 -1.283)
				(xy -7.116 -1.342) (xy -7.166 -1.375) (xy -7.222 -1.384) (xy -7.278 -1.368) (xy -7.326 -1.326) (xy -7.354 -1.278)
				(xy -7.365 -1.24) (xy -7.472 -1.24) (xy -7.474 -1.25) (xy -7.455 -1.328) (xy -7.416 -1.396) (xy -7.358 -1.449)
				(xy -7.288 -1.484) (xy -7.21 -1.495) (xy -7.128 -1.48)
			)
			(stroke
				(width 0.00186)
				(type solid)
			)
			(fill yes)
			(layer "F.Mask")
		)
	)
	(footprint "antmicro-footprints:RJ45_7499111121A_Horizontal"
		(layer "F.Cu")
		(at 195.721328 116.057157)
		(descr "WE-RJ45_Transformer-10/100/1000")
		(property "Reference" "J5"
			(at 4.978672 -2.457157 180)
			(layer "F.SilkS")
			(effects
				(font
					(size 0.7 0.7)
					(thickness 0.15)
				)
				(justify left bottom)
			)
		)
		(property "Value" "Bus_RJ45_7499111121A"
			(at 0 21.9 180)
			(layer "F.Fab")
			(effects
				(font
					(size 0.7 0.7)
					(thickness 0.15)
				)
				(justify left bottom)
			)
		)
		(property "Author" "Antmicro"
			(at 0 0 0)
			(layer "F.Fab")
			(hide yes)
			(effects
				(font
					(size 1 1)
					(thickness 0.15)
				)
			)
		)
		(property "License" "Apache-2.0"
			(at 0 0 0)
			(layer "F.Fab")
			(hide yes)
			(effects
				(font
					(size 1 1)
					(thickness 0.15)
				)
			)
		)
		(property "MPN" "7499111121A"
			(at 0 0 0)
			(layer "F.Fab")
			(hide yes)
			(effects
				(font
					(size 1 1)
					(thickness 0.15)
				)
			)
		)
		(property "Manufacturer" "Würth Elektronik"
			(at 0 0 0)
			(layer "F.Fab")
			(hide yes)
			(effects
				(font
					(size 1 1)
					(thickness 0.15)
				)
			)
		)
		(sheetname "Ethernet")
		(sheetfile "ethernet.kicad_sch")
		(attr through_hole)
		(fp_line
			(start -2.323 4.292)
			(end -2.323 -2.16)
			(stroke
				(width 0.15)
				(type solid)
			)
			(layer "F.SilkS")
		)
		(fp_line
			(start -2.323 19.7)
			(end -2.323 7.391)
			(stroke
				(width 0.15)
				(type solid)
			)
			(layer "F.SilkS")
		)
		(fp_line
			(start -2.323 19.7)
			(end 13.756 19.7)
			(stroke
				(width 0.15)
				(type solid)
			)
			(layer "F.SilkS")
		)
		(fp_line
			(start 13.756 -2.16)
			(end -2.323 -2.16)
			(stroke
				(width 0.15)
				(type solid)
			)
			(layer "F.SilkS")
		)
		(fp_line
			(start 13.756 4.292)
			(end 13.756 -2.16)
			(stroke
				(width 0.15)
				(type solid)
			)
			(layer "F.SilkS")
		)
		(fp_line
			(start 13.756 7.391)
			(end 13.756 19.7)
			(stroke
				(width 0.15)
				(type solid)
			)
			(layer "F.SilkS")
		)
		(fp_rect
			(start 14.838 20.181)
			(end -3.406 -3.059)
			(stroke
				(width 0.05)
				(type solid)
			)
			(fill no)
			(layer "F.CrtYd")
		)
		(fp_line
			(start -2.225 -2.059)
			(end -2.225 19.781)
			(stroke
				(width 0.15)
				(type solid)
			)
			(layer "F.Fab")
		)
		(fp_line
			(start -2.225 19.781)
			(end 13.657 19.781)
			(stroke
				(width 0.15)
				(type solid)
			)
			(layer "F.Fab")
		)
		(fp_line
			(start 13.657 -2.059)
			(end -2.225 -2.059)
			(stroke
				(width 0.15)
				(type solid)
			)
			(layer "F.Fab")
		)
		(fp_line
			(start 13.657 19.781)
			(end 13.657 -2.059)
			(stroke
				(width 0.15)
				(type solid)
			)
			(layer "F.Fab")
		)
		(pad "" np_thru_hole circle
			(at 0 8.891 180)
			(size 3.25 3.25)
			(drill 3.25)
			(layers "*.Cu" "*.Mask")
		)
		(pad "" np_thru_hole circle
			(at 11.43 8.891 180)
			(size 3.25 3.25)
			(drill 3.25)
			(layers "*.Cu" "*.Mask")
		)
		(pad "1" thru_hole circle
			(at 0 0 180)
			(size 1.408 1.408)
			(drill 0.9)
			(layers "*.Cu" "*.Mask")
			(remove_unused_layers no)
			(net 522 "/Ethernet/ETH1_P")
			(pinfunction "D1+")
			(pintype "bidirectional")
		)
		(pad "2" thru_hole circle
			(at 1.27 2.541 180)
			(size 1.408 1.408)
			(drill 0.9)
			(layers "*.Cu" "*.Mask")
			(remove_unused_layers no)
			(net 525 "/Ethernet/ETH1_N")
			(pinfunction "D1-")
			(pintype "bidirectional")
		)
		(pad "3" thru_hole circle
			(at 2.54 0 180)
			(size 1.408 1.408)
			(drill 0.9)
			(layers "*.Cu" "*.Mask")
			(remove_unused_layers no)
			(net 520 "/Ethernet/ETH2_P")
			(pinfunction "D2+")
			(pintype "bidirectional")
		)
		(pad "4" thru_hole circle
			(at 3.81 2.541 180)
			(size 1.408 1.408)
			(drill 0.9)
			(layers "*.Cu" "*.Mask")
			(remove_unused_layers no)
			(net 519 "/Ethernet/ETH3_P")
			(pinfunction "D3+")
			(pintype "bidirectional")
		)
		(pad "5" thru_hole circle
			(at 5.08 0 180)
			(size 1.408 1.408)
			(drill 0.9)
			(layers "*.Cu" "*.Mask")
			(remove_unused_layers no)
			(net 526 "/Ethernet/ETH3_N")
			(pinfunction "D3-")
			(pintype "bidirectional")
		)
		(pad "6" thru_hole circle
			(at 6.351 2.541 180)
			(size 1.408 1.408)
			(drill 0.9)
			(layers "*.Cu" "*.Mask")
			(remove_unused_layers no)
			(net 524 "/Ethernet/ETH2_N")
			(pinfunction "D2-")
			(pintype "bidirectional")
		)
		(pad "7" thru_hole circle
			(at 7.62 0 180)
			(size 1.408 1.408)
			(drill 0.9)
			(layers "*.Cu" "*.Mask")
			(remove_unused_layers no)
			(net 523 "/Ethernet/ETH4_P")
			(pinfunction "D4+")
			(pintype "bidirectional")
		)
		(pad "8" thru_hole circle
			(at 8.891 2.541 180)
			(size 1.408 1.408)
			(drill 0.9)
			(layers "*.Cu" "*.Mask")
			(remove_unused_layers no)
			(net 527 "/Ethernet/ETH4_N")
			(pinfunction "D4-")
			(pintype "bidirectional")
		)
		(pad "9" thru_hole circle
			(at 10.16 0 180)
			(size 1.408 1.408)
			(drill 0.9)
			(layers "*.Cu" "*.Mask")
			(remove_unused_layers no)
			(net 88 "unconnected-(J5-VCC-Pad9)")
			(pinfunction "VCC")
			(pintype "power_in+no_connect")
		)
		(pad "10" thru_hole circle
			(at 11.43 2.541 180)
			(size 1.408 1.408)
			(drill 0.9)
			(layers "*.Cu" "*.Mask")
			(remove_unused_layers no)
			(net 5 "GND")
			(pinfunction "GND")
			(pintype "power_in")
		)
		(pad "11" thru_hole circle
			(at -0.915 12.971 180)
			(size 1.53 1.53)
			(drill 1.02)
			(layers "*.Cu" "*.Mask")
			(remove_unused_layers no)
			(net 89 "Net-(J5-LED1_Y+)")
			(pinfunction "LED1_Y+")
			(pintype "passive")
		)
		(pad "12" thru_hole circle
			(at 1.625 12.971 180)
			(size 1.53 1.53)
			(drill 1.02)
			(layers "*.Cu" "*.Mask")
			(remove_unused_layers no)
			(net 12 "LED_LINK")
			(pinfunction "LED1_Y-")
			(pintype "passive")
		)
		(pad "13" thru_hole circle
			(at 9.805 12.971 180)
			(size 1.53 1.53)
			(drill 1.02)
			(layers "*.Cu" "*.Mask")
			(remove_unused_layers no)
			(net 90 "Net-(J5-LED2_G+)")
			(pinfunction "LED2_G+")
			(pintype "passive")
		)
		(pad "14" thru_hole circle
			(at 12.346 12.971 180)
			(size 1.53 1.53)
			(drill 1.02)
			(layers "*.Cu" "*.Mask")
			(remove_unused_layers no)
			(net 13 "LED_SPD")
			(pinfunction "LED2_G-")
			(pintype "passive")
		)
		(pad "SH" thru_hole circle
			(at -2.03 5.842 180)
			(size 2.4 2.4)
			(drill 1.6)
			(layers "*.Cu" "*.Mask")
			(remove_unused_layers no)
			(net 521 "Net-(FB7-Pad1)")
			(pintype "passive")
		)
		(pad "SH" thru_hole circle
			(at 13.462 5.842 180)
			(size 2.4 2.4)
			(drill 1.6)
			(layers "*.Cu" "*.Mask")
			(remove_unused_layers no)
			(net 521 "Net-(FB7-Pad1)")
			(pintype "passive")
		)
	)
	(footprint "antmicro-footprints:C_0402_1005Metric"
		(layer "F.Cu")
		(at 193.086328 98.874306 180)
		(descr "Capacitor SMD 0402")
		(tags "capacitor SMD 0402")
		(property "Reference" "C97"
			(at 1.172656 4.347612 180)
			(layer "F.SilkS")
			(effects
				(font
					(size 0.7 0.7)
					(thickness 0.15)
				)
				(justify left bottom)
			)
		)
		(property "Value" "C_4u7_0402"
			(at 0 1.4 180)
			(layer "F.Fab")
			(effects
				(font
					(size 0.7 0.7)
					(thickness 0.15)
				)
				(justify left bottom)
			)
		)
		(property "Description" " "
			(at 0 0 180)
			(layer "F.Fab")
			(hide yes)
			(effects
				(font
					(size 1.27 1.27)
					(thickness 0.15)
				)
			)
		)
		(property "Author" "Antmicro"
			(at 386.172656 197.748612 0)
			(layer "F.Fab")
			(hide yes)
			(effects
				(font
					(size 1 1)
					(thickness 0.15)
				)
			)
		)
		(property "Dielectric" ""
			(at 386.172656 197.748612 0)
			(layer "F.Fab")
			(hide yes)
			(effects
				(font
					(size 1 1)
					(thickness 0.15)
				)
			)
		)
		(property "License" "Apache-2.0"
			(at 386.172656 197.748612 0)
			(layer "F.Fab")
			(hide yes)
			(effects
				(font
					(size 1 1)
					(thickness 0.15)
				)
			)
		)
		(property "MPN" "GRM155R61A475MEAAD"
			(at 386.172656 197.748612 0)
			(layer "F.Fab")
			(hide yes)
			(effects
				(font
					(size 1 1)
					(thickness 0.15)
				)
			)
		)
		(property "Manufacturer" "Murata"
			(at 386.172656 197.748612 0)
			(layer "F.Fab")
			(hide yes)
			(effects
				(font
					(size 1 1)
					(thickness 0.15)
				)
			)
		)
		(property "Val" "4u7"
			(at 386.172656 197.748612 0)
			(layer "F.Fab")
			(hide yes)
			(effects
				(font
					(size 1 1)
					(thickness 0.15)
				)
			)
		)
		(property "Voltage" ""
			(at 386.172656 197.748612 0)
			(layer "F.Fab")
			(hide yes)
			(effects
				(font
					(size 1 1)
					(thickness 0.15)
				)
			)
		)
		(sheetname "Ethernet")
		(sheetfile "ethernet.kicad_sch")
		(attr smd)
		(fp_rect
			(start -0.94 -0.47)
			(end 0.94 0.47)
			(stroke
				(width 0.05)
				(type solid)
			)
			(fill no)
			(layer "F.CrtYd")
		)
		(fp_rect
			(start -0.499 -0.249)
			(end 0.499 0.249)
			(stroke
				(width 0.15)
				(type solid)
			)
			(fill no)
			(layer "F.Fab")
		)
		(pad "1" smd roundrect
			(at -0.484 0 180)
			(size 0.59 0.64)
			(layers "F.Cu" "F.Mask" "F.Paste")
			(roundrect_rratio 0.25)
			(net 602 "1V2_SYS")
			(pintype "passive")
		)
		(pad "2" smd roundrect
			(at 0.484 0 180)
			(size 0.59 0.64)
			(layers "F.Cu" "F.Mask" "F.Paste")
			(roundrect_rratio 0.25)
			(net 5 "GND")
			(pintype "passive")
		)
	)
	(footprint "antmicro-footprints:C_0402_1005Metric"
		(layer "F.Cu")
		(at 193.086328 99.874306 180)
		(descr "Capacitor SMD 0402")
		(tags "capacitor SMD 0402")
		(property "Reference" "C98"
			(at 1.172656 4.347612 180)
			(layer "F.SilkS")
			(effects
				(font
					(size 0.7 0.7)
					(thickness 0.15)
				)
				(justify left bottom)
			)
		)
		(property "Value" "C_470n_0402"
			(at 0 1.4 180)
			(layer "F.Fab")
			(effects
				(font
					(size 0.7 0.7)
					(thickness 0.15)
				)
				(justify left bottom)
			)
		)
		(property "Description" " "
			(at 0 0 180)
			(layer "F.Fab")
			(hide yes)
			(effects
				(font
					(size 1.27 1.27)
					(thickness 0.15)
				)
			)
		)
		(property "Author" "Antmicro"
			(at 386.172656 199.748612 0)
			(layer "F.Fab")
			(hide yes)
			(effects
				(font
					(size 1 1)
					(thickness 0.15)
				)
			)
		)
		(property "Dielectric" ""
			(at 386.172656 199.748612 0)
			(layer "F.Fab")
			(hide yes)
			(effects
				(font
					(size 1 1)
					(thickness 0.15)
				)
			)
		)
		(property "License" "Apache-2.0"
			(at 386.172656 199.748612 0)
			(layer "F.Fab")
			(hide yes)
			(effects
				(font
					(size 1 1)
					(thickness 0.15)
				)
			)
		)
		(property "MPN" "C1005X5R1E474M050BB"
			(at 386.172656 199.748612 0)
			(layer "F.Fab")
			(hide yes)
			(effects
				(font
					(size 1 1)
					(thickness 0.15)
				)
			)
		)
		(property "Manufacturer" "TDK"
			(at 386.172656 199.748612 0)
			(layer "F.Fab")
			(hide yes)
			(effects
				(font
					(size 1 1)
					(thickness 0.15)
				)
			)
		)
		(property "Val" "470n"
			(at 386.172656 199.748612 0)
			(layer "F.Fab")
			(hide yes)
			(effects
				(font
					(size 1 1)
					(thickness 0.15)
				)
			)
		)
		(property "Voltage" ""
			(at 386.172656 199.748612 0)
			(layer "F.Fab")
			(hide yes)
			(effects
				(font
					(size 1 1)
					(thickness 0.15)
				)
			)
		)
		(sheetname "Ethernet")
		(sheetfile "ethernet.kicad_sch")
		(attr smd)
		(fp_rect
			(start -0.94 -0.47)
			(end 0.94 0.47)
			(stroke
				(width 0.05)
				(type solid)
			)
			(fill no)
			(layer "F.CrtYd")
		)
		(fp_rect
			(start -0.499 -0.249)
			(end 0.499 0.249)
			(stroke
				(width 0.15)
				(type solid)
			)
			(fill no)
			(layer "F.Fab")
		)
		(pad "1" smd roundrect
			(at -0.484 0 180)
			(size 0.59 0.64)
			(layers "F.Cu" "F.Mask" "F.Paste")
			(roundrect_rratio 0.25)
			(net 602 "1V2_SYS")
			(pintype "passive")
		)
		(pad "2" smd roundrect
			(at 0.484 0 180)
			(size 0.59 0.64)
			(layers "F.Cu" "F.Mask" "F.Paste")
			(roundrect_rratio 0.25)
			(net 5 "GND")
			(pintype "passive")
		)
	)
	(footprint "antmicro-footprints:C_0402_1005Metric"
		(layer "F.Cu")
		(at 193.586328 101.374306 90)
		(descr "Capacitor SMD 0402")
		(tags "capacitor SMD 0402")
		(property "Reference" "C102"
			(at 2.974306 0.413672 90)
			(layer "F.SilkS")
			(effects
				(font
					(size 0.7 0.7)
					(thickness 0.15)
				)
				(justify left bottom)
			)
		)
		(property "Value" "C_4u7_0402"
			(at 0 1.4 90)
			(layer "F.Fab")
			(effects
				(font
					(size 0.7 0.7)
					(thickness 0.15)
				)
				(justify left bottom)
			)
		)
		(property "Description" " "
			(at 0 0 90)
			(layer "F.Fab")
			(hide yes)
			(effects
				(font
					(size 1.27 1.27)
					(thickness 0.15)
				)
			)
		)
		(property "Author" "Antmicro"
			(at 294.960634 -92.212022 0)
			(layer "F.Fab")
			(hide yes)
			(effects
				(font
					(size 1 1)
					(thickness 0.15)
				)
			)
		)
		(property "Dielectric" ""
			(at 294.960634 -92.212022 0)
			(layer "F.Fab")
			(hide yes)
			(effects
				(font
					(size 1 1)
					(thickness 0.15)
				)
			)
		)
		(property "License" "Apache-2.0"
			(at 294.960634 -92.212022 0)
			(layer "F.Fab")
			(hide yes)
			(effects
				(font
					(size 1 1)
					(thickness 0.15)
				)
			)
		)
		(property "MPN" "GRM155R61A475MEAAD"
			(at 294.960634 -92.212022 0)
			(layer "F.Fab")
			(hide yes)
			(effects
				(font
					(size 1 1)
					(thickness 0.15)
				)
			)
		)
		(property "Manufacturer" "Murata"
			(at 294.960634 -92.212022 0)
			(layer "F.Fab")
			(hide yes)
			(effects
				(font
					(size 1 1)
					(thickness 0.15)
				)
			)
		)
		(property "Val" "4u7"
			(at 294.960634 -92.212022 0)
			(layer "F.Fab")
			(hide yes)
			(effects
				(font
					(size 1 1)
					(thickness 0.15)
				)
			)
		)
		(property "Voltage" ""
			(at 294.960634 -92.212022 0)
			(layer "F.Fab")
			(hide yes)
			(effects
				(font
					(size 1 1)
					(thickness 0.15)
				)
			)
		)
		(sheetname "Ethernet")
		(sheetfile "ethernet.kicad_sch")
		(attr smd)
		(fp_rect
			(start -0.94 -0.47)
			(end 0.94 0.47)
			(stroke
				(width 0.05)
				(type solid)
			)
			(fill no)
			(layer "F.CrtYd")
		)
		(fp_rect
			(start -0.499 -0.249)
			(end 0.499 0.249)
			(stroke
				(width 0.15)
				(type solid)
			)
			(fill no)
			(layer "F.Fab")
		)
		(pad "1" smd roundrect
			(at -0.484 0 90)
			(size 0.59 0.64)
			(layers "F.Cu" "F.Mask" "F.Paste")
			(roundrect_rratio 0.25)
			(net 530 "/Ethernet/AVDDL_PLL")
			(pintype "passive")
		)
		(pad "2" smd roundrect
			(at 0.484 0 90)
			(size 0.59 0.64)
			(layers "F.Cu" "F.Mask" "F.Paste")
			(roundrect_rratio 0.25)
			(net 5 "GND")
			(pintype "passive")
		)
	)
	(footprint "antmicro-footprints:C_0402_1005Metric"
		(layer "F.Cu")
		(at 192.486328 101.374306 90)
		(descr "Capacitor SMD 0402")
		(tags "capacitor SMD 0402")
		(property "Reference" "C106"
			(at 2.974306 0.413672 90)
			(layer "F.SilkS")
			(effects
				(font
					(size 0.7 0.7)
					(thickness 0.15)
				)
				(justify left bottom)
			)
		)
		(property "Value" "C_100n_16V_0402"
			(at 0 1.4 90)
			(layer "F.Fab")
			(effects
				(font
					(size 0.7 0.7)
					(thickness 0.15)
				)
				(justify left bottom)
			)
		)
		(property "Description" " "
			(at 0 0 90)
			(layer "F.Fab")
			(hide yes)
			(effects
				(font
					(size 1.27 1.27)
					(thickness 0.15)
				)
			)
		)
		(property "Author" "Antmicro"
			(at 293.860634 -91.112022 0)
			(layer "F.Fab")
			(hide yes)
			(effects
				(font
					(size 1 1)
					(thickness 0.15)
				)
			)
		)
		(property "Dielectric" ""
			(at 293.860634 -91.112022 0)
			(layer "F.Fab")
			(hide yes)
			(effects
				(font
					(size 1 1)
					(thickness 0.15)
				)
			)
		)
		(property "License" "Apache-2.0"
			(at 293.860634 -91.112022 0)
			(layer "F.Fab")
			(hide yes)
			(effects
				(font
					(size 1 1)
					(thickness 0.15)
				)
			)
		)
		(property "MPN" "MC0402B104K160CT"
			(at 293.860634 -91.112022 0)
			(layer "F.Fab")
			(hide yes)
			(effects
				(font
					(size 1 1)
					(thickness 0.15)
				)
			)
		)
		(property "Manufacturer" "Multicomp"
			(at 293.860634 -91.112022 0)
			(layer "F.Fab")
			(hide yes)
			(effects
				(font
					(size 1 1)
					(thickness 0.15)
				)
			)
		)
		(property "Val" "100n"
			(at 293.860634 -91.112022 0)
			(layer "F.Fab")
			(hide yes)
			(effects
				(font
					(size 1 1)
					(thickness 0.15)
				)
			)
		)
		(property "Voltage" ""
			(at 293.860634 -91.112022 0)
			(layer "F.Fab")
			(hide yes)
			(effects
				(font
					(size 1 1)
					(thickness 0.15)
				)
			)
		)
		(sheetname "Ethernet")
		(sheetfile "ethernet.kicad_sch")
		(attr smd)
		(fp_rect
			(start -0.94 -0.47)
			(end 0.94 0.47)
			(stroke
				(width 0.05)
				(type solid)
			)
			(fill no)
			(layer "F.CrtYd")
		)
		(fp_rect
			(start -0.499 -0.249)
			(end 0.499 0.249)
			(stroke
				(width 0.15)
				(type solid)
			)
			(fill no)
			(layer "F.Fab")
		)
		(pad "1" smd roundrect
			(at -0.484 0 90)
			(size 0.59 0.64)
			(layers "F.Cu" "F.Mask" "F.Paste")
			(roundrect_rratio 0.25)
			(net 530 "/Ethernet/AVDDL_PLL")
			(pintype "passive")
		)
		(pad "2" smd roundrect
			(at 0.484 0 90)
			(size 0.59 0.64)
			(layers "F.Cu" "F.Mask" "F.Paste")
			(roundrect_rratio 0.25)
			(net 5 "GND")
			(pintype "passive")
		)
	)
	(footprint "antmicro-footprints:C_0402_1005Metric"
		(layer "F.Cu")
		(at 205.486328 106.174306 -90)
		(descr "Capacitor SMD 0402")
		(tags "capacitor SMD 0402")
		(property "Reference" "C108"
			(at 1.825694 -2.413672 270)
			(layer "F.SilkS")
			(effects
				(font
					(size 0.7 0.7)
					(thickness 0.15)
				)
				(justify left bottom)
			)
		)
		(property "Value" "C_470n_0402"
			(at 0 1.4 270)
			(layer "F.Fab")
			(effects
				(font
					(size 0.7 0.7)
					(thickness 0.15)
				)
				(justify left bottom)
			)
		)
		(property "Description" " "
			(at 0 0 270)
			(layer "F.Fab")
			(hide yes)
			(effects
				(font
					(size 1.27 1.27)
					(thickness 0.15)
				)
			)
		)
		(property "Author" "Antmicro"
			(at 99.312022 311.660634 0)
			(layer "F.Fab")
			(hide yes)
			(effects
				(font
					(size 1 1)
					(thickness 0.15)
				)
			)
		)
		(property "Dielectric" ""
			(at 99.312022 311.660634 0)
			(layer "F.Fab")
			(hide yes)
			(effects
				(font
					(size 1 1)
					(thickness 0.15)
				)
			)
		)
		(property "License" "Apache-2.0"
			(at 99.312022 311.660634 0)
			(layer "F.Fab")
			(hide yes)
			(effects
				(font
					(size 1 1)
					(thickness 0.15)
				)
			)
		)
		(property "MPN" "C1005X5R1E474M050BB"
			(at 99.312022 311.660634 0)
			(layer "F.Fab")
			(hide yes)
			(effects
				(font
					(size 1 1)
					(thickness 0.15)
				)
			)
		)
		(property "Manufacturer" "TDK"
			(at 99.312022 311.660634 0)
			(layer "F.Fab")
			(hide yes)
			(effects
				(font
					(size 1 1)
					(thickness 0.15)
				)
			)
		)
		(property "Val" "470n"
			(at 99.312022 311.660634 0)
			(layer "F.Fab")
			(hide yes)
			(effects
				(font
					(size 1 1)
					(thickness 0.15)
				)
			)
		)
		(property "Voltage" ""
			(at 99.312022 311.660634 0)
			(layer "F.Fab")
			(hide yes)
			(effects
				(font
					(size 1 1)
					(thickness 0.15)
				)
			)
		)
		(sheetname "Ethernet")
		(sheetfile "ethernet.kicad_sch")
		(attr smd)
		(fp_rect
			(start -0.94 -0.47)
			(end 0.94 0.47)
			(stroke
				(width 0.05)
				(type solid)
			)
			(fill no)
			(layer "F.CrtYd")
		)
		(fp_rect
			(start -0.499 -0.249)
			(end 0.499 0.249)
			(stroke
				(width 0.15)
				(type solid)
			)
			(fill no)
			(layer "F.Fab")
		)
		(pad "1" smd roundrect
			(at -0.484 0 270)
			(size 0.59 0.64)
			(layers "F.Cu" "F.Mask" "F.Paste")
			(roundrect_rratio 0.25)
			(net 602 "1V2_SYS")
			(pintype "passive")
		)
		(pad "2" smd roundrect
			(at 0.484 0 270)
			(size 0.59 0.64)
			(layers "F.Cu" "F.Mask" "F.Paste")
			(roundrect_rratio 0.25)
			(net 5 "GND")
			(pintype "passive")
		)
	)
	(footprint "antmicro-footprints:C_0402_1005Metric"
		(layer "F.Cu")
		(at 206.586328 100.374306 90)
		(descr "Capacitor SMD 0402")
		(tags "capacitor SMD 0402")
		(property "Reference" "C113"
			(at -1.425694 1.313672 90)
			(layer "F.SilkS")
			(effects
				(font
					(size 0.7 0.7)
					(thickness 0.15)
				)
				(justify left bottom)
			)
		)
		(property "Value" "C_10n_0402"
			(at 0 1.4 90)
			(layer "F.Fab")
			(effects
				(font
					(size 0.7 0.7)
					(thickness 0.15)
				)
				(justify left bottom)
			)
		)
		(property "Description" " "
			(at 0 0 90)
			(layer "F.Fab")
			(hide yes)
			(effects
				(font
					(size 1.27 1.27)
					(thickness 0.15)
				)
			)
		)
		(property "Author" "Antmicro"
			(at 306.960634 -106.212022 0)
			(layer "F.Fab")
			(hide yes)
			(effects
				(font
					(size 1 1)
					(thickness 0.15)
				)
			)
		)
		(property "Dielectric" "X7R"
			(at 306.960634 -106.212022 0)
			(layer "F.Fab")
			(hide yes)
			(effects
				(font
					(size 1 1)
					(thickness 0.15)
				)
			)
		)
		(property "License" "Apache-2.0"
			(at 306.960634 -106.212022 0)
			(layer "F.Fab")
			(hide yes)
			(effects
				(font
					(size 1 1)
					(thickness 0.15)
				)
			)
		)
		(property "MPN" "GRM155R71H103KA88D"
			(at 306.960634 -106.212022 0)
			(layer "F.Fab")
			(hide yes)
			(effects
				(font
					(size 1 1)
					(thickness 0.15)
				)
			)
		)
		(property "Manufacturer" "Murata"
			(at 306.960634 -106.212022 0)
			(layer "F.Fab")
			(hide yes)
			(effects
				(font
					(size 1 1)
					(thickness 0.15)
				)
			)
		)
		(property "Val" "10n"
			(at 306.960634 -106.212022 0)
			(layer "F.Fab")
			(hide yes)
			(effects
				(font
					(size 1 1)
					(thickness 0.15)
				)
			)
		)
		(property "Voltage" "50V"
			(at 306.960634 -106.212022 0)
			(layer "F.Fab")
			(hide yes)
			(effects
				(font
					(size 1 1)
					(thickness 0.15)
				)
			)
		)
		(sheetname "Ethernet")
		(sheetfile "ethernet.kicad_sch")
		(attr smd)
		(fp_rect
			(start -0.94 -0.47)
			(end 0.94 0.47)
			(stroke
				(width 0.05)
				(type solid)
			)
			(fill no)
			(layer "F.CrtYd")
		)
		(fp_rect
			(start -0.499 -0.249)
			(end 0.499 0.249)
			(stroke
				(width 0.15)
				(type solid)
			)
			(fill no)
			(layer "F.Fab")
		)
		(pad "1" smd roundrect
			(at -0.484 0 90)
			(size 0.59 0.64)
			(layers "F.Cu" "F.Mask" "F.Paste")
			(roundrect_rratio 0.25)
			(net 602 "1V2_SYS")
			(pintype "passive")
		)
		(pad "2" smd roundrect
			(at 0.484 0 90)
			(size 0.59 0.64)
			(layers "F.Cu" "F.Mask" "F.Paste")
			(roundrect_rratio 0.25)
			(net 5 "GND")
			(pintype "passive")
		)
	)
	(footprint "antmicro-footprints:C_0402_1005Metric"
		(layer "F.Cu")
		(at 206.586328 106.174306 -90)
		(descr "Capacitor SMD 0402")
		(tags "capacitor SMD 0402")
		(property "Reference" "C120"
			(at 1.825694 -2.413672 270)
			(layer "F.SilkS")
			(effects
				(font
					(size 0.7 0.7)
					(thickness 0.15)
				)
				(justify left bottom)
			)
		)
		(property "Value" "C_10n_0402"
			(at 0 1.4 270)
			(layer "F.Fab")
			(effects
				(font
					(size 0.7 0.7)
					(thickness 0.15)
				)
				(justify left bottom)
			)
		)
		(property "Description" " "
			(at 0 0 270)
			(layer "F.Fab")
			(hide yes)
			(effects
				(font
					(size 1.27 1.27)
					(thickness 0.15)
				)
			)
		)
		(property "Author" "Antmicro"
			(at 100.412022 312.760634 0)
			(layer "F.Fab")
			(hide yes)
			(effects
				(font
					(size 1 1)
					(thickness 0.15)
				)
			)
		)
		(property "Dielectric" "X7R"
			(at 100.412022 312.760634 0)
			(layer "F.Fab")
			(hide yes)
			(effects
				(font
					(size 1 1)
					(thickness 0.15)
				)
			)
		)
		(property "License" "Apache-2.0"
			(at 100.412022 312.760634 0)
			(layer "F.Fab")
			(hide yes)
			(effects
				(font
					(size 1 1)
					(thickness 0.15)
				)
			)
		)
		(property "MPN" "GRM155R71H103KA88D"
			(at 100.412022 312.760634 0)
			(layer "F.Fab")
			(hide yes)
			(effects
				(font
					(size 1 1)
					(thickness 0.15)
				)
			)
		)
		(property "Manufacturer" "Murata"
			(at 100.412022 312.760634 0)
			(layer "F.Fab")
			(hide yes)
			(effects
				(font
					(size 1 1)
					(thickness 0.15)
				)
			)
		)
		(property "Val" "10n"
			(at 100.412022 312.760634 0)
			(layer "F.Fab")
			(hide yes)
			(effects
				(font
					(size 1 1)
					(thickness 0.15)
				)
			)
		)
		(property "Voltage" "50V"
			(at 100.412022 312.760634 0)
			(layer "F.Fab")
			(hide yes)
			(effects
				(font
					(size 1 1)
					(thickness 0.15)
				)
			)
		)
		(sheetname "Ethernet")
		(sheetfile "ethernet.kicad_sch")
		(attr smd)
		(fp_rect
			(start -0.94 -0.47)
			(end 0.94 0.47)
			(stroke
				(width 0.05)
				(type solid)
			)
			(fill no)
			(layer "F.CrtYd")
		)
		(fp_rect
			(start -0.499 -0.249)
			(end 0.499 0.249)
			(stroke
				(width 0.15)
				(type solid)
			)
			(fill no)
			(layer "F.Fab")
		)
		(pad "1" smd roundrect
			(at -0.484 0 270)
			(size 0.59 0.64)
			(layers "F.Cu" "F.Mask" "F.Paste")
			(roundrect_rratio 0.25)
			(net 602 "1V2_SYS")
			(pintype "passive")
		)
		(pad "2" smd roundrect
			(at 0.484 0 270)
			(size 0.59 0.64)
			(layers "F.Cu" "F.Mask" "F.Paste")
			(roundrect_rratio 0.25)
			(net 5 "GND")
			(pintype "passive")
		)
	)
	(footprint "antmicro-footprints:C_0402_1005Metric"
		(layer "F.Cu")
		(at 191.186328 102.874306 180)
		(descr "Capacitor SMD 0402")
		(tags "capacitor SMD 0402")
		(property "Reference" "C121"
			(at 3.486328 -0.525694 180)
			(layer "F.SilkS")
			(effects
				(font
					(size 0.7 0.7)
					(thickness 0.15)
				)
				(justify left bottom)
			)
		)
		(property "Value" "C_22p_0402"
			(at 0 1.4 180)
			(layer "F.Fab")
			(effects
				(font
					(size 0.7 0.7)
					(thickness 0.15)
				)
				(justify left bottom)
			)
		)
		(property "Description" " "
			(at 0 0 180)
			(layer "F.Fab")
			(hide yes)
			(effects
				(font
					(size 1.27 1.27)
					(thickness 0.15)
				)
			)
		)
		(property "Author" "Antmicro"
			(at 382.372656 205.748612 0)
			(layer "F.Fab")
			(hide yes)
			(effects
				(font
					(size 1 1)
					(thickness 0.15)
				)
			)
		)
		(property "Dielectric" ""
			(at 382.372656 205.748612 0)
			(layer "F.Fab")
			(hide yes)
			(effects
				(font
					(size 1 1)
					(thickness 0.15)
				)
			)
		)
		(property "License" "Apache-2.0"
			(at 382.372656 205.748612 0)
			(layer "F.Fab")
			(hide yes)
			(effects
				(font
					(size 1 1)
					(thickness 0.15)
				)
			)
		)
		(property "MPN" "CC0402JRNPO9BN220"
			(at 382.372656 205.748612 0)
			(layer "F.Fab")
			(hide yes)
			(effects
				(font
					(size 1 1)
					(thickness 0.15)
				)
			)
		)
		(property "Manufacturer" "Yaego"
			(at 382.372656 205.748612 0)
			(layer "F.Fab")
			(hide yes)
			(effects
				(font
					(size 1 1)
					(thickness 0.15)
				)
			)
		)
		(property "Val" "22p"
			(at 382.372656 205.748612 0)
			(layer "F.Fab")
			(hide yes)
			(effects
				(font
					(size 1 1)
					(thickness 0.15)
				)
			)
		)
		(property "Voltage" ""
			(at 382.372656 205.748612 0)
			(layer "F.Fab")
			(hide yes)
			(effects
				(font
					(size 1 1)
					(thickness 0.15)
				)
			)
		)
		(sheetname "Ethernet")
		(sheetfile "ethernet.kicad_sch")
		(attr smd)
		(fp_rect
			(start -0.94 -0.47)
			(end 0.94 0.47)
			(stroke
				(width 0.05)
				(type solid)
			)
			(fill no)
			(layer "F.CrtYd")
		)
		(fp_rect
			(start -0.499 -0.249)
			(end 0.499 0.249)
			(stroke
				(width 0.15)
				(type solid)
			)
			(fill no)
			(layer "F.Fab")
		)
		(pad "1" smd roundrect
			(at -0.484 0 180)
			(size 0.59 0.64)
			(layers "F.Cu" "F.Mask" "F.Paste")
			(roundrect_rratio 0.25)
			(net 656 "ETH_XO")
			(pintype "passive")
		)
		(pad "2" smd roundrect
			(at 0.484 0 180)
			(size 0.59 0.64)
			(layers "F.Cu" "F.Mask" "F.Paste")
			(roundrect_rratio 0.25)
			(net 5 "GND")
			(pintype "passive")
		)
	)
	(footprint "antmicro-footprints:C_0402_1005Metric"
		(layer "F.Cu")
		(at 189.986328 107.674306)
		(descr "Capacitor SMD 0402")
		(tags "capacitor SMD 0402")
		(property "Reference" "C122"
			(at -3.586328 0.325694 0)
			(layer "F.SilkS")
			(effects
				(font
					(size 0.7 0.7)
					(thickness 0.15)
				)
				(justify left bottom)
			)
		)
		(property "Value" "C_22p_0402"
			(at 0 1.4 0)
			(layer "F.Fab")
			(effects
				(font
					(size 0.7 0.7)
					(thickness 0.15)
				)
				(justify left bottom)
			)
		)
		(property "Description" " "
			(at 0 0 0)
			(layer "F.Fab")
			(hide yes)
			(effects
				(font
					(size 1.27 1.27)
					(thickness 0.15)
				)
			)
		)
		(property "Author" "Antmicro"
			(at 0 0 0)
			(layer "F.Fab")
			(hide yes)
			(effects
				(font
					(size 1 1)
					(thickness 0.15)
				)
			)
		)
		(property "Dielectric" ""
			(at 0 0 0)
			(layer "F.Fab")
			(hide yes)
			(effects
				(font
					(size 1 1)
					(thickness 0.15)
				)
			)
		)
		(property "License" "Apache-2.0"
			(at 0 0 0)
			(layer "F.Fab")
			(hide yes)
			(effects
				(font
					(size 1 1)
					(thickness 0.15)
				)
			)
		)
		(property "MPN" "CC0402JRNPO9BN220"
			(at 0 0 0)
			(layer "F.Fab")
			(hide yes)
			(effects
				(font
					(size 1 1)
					(thickness 0.15)
				)
			)
		)
		(property "Manufacturer" "Yaego"
			(at 0 0 0)
			(layer "F.Fab")
			(hide yes)
			(effects
				(font
					(size 1 1)
					(thickness 0.15)
				)
			)
		)
		(property "Val" "22p"
			(at 0 0 0)
			(layer "F.Fab")
			(hide yes)
			(effects
				(font
					(size 1 1)
					(thickness 0.15)
				)
			)
		)
		(property "Voltage" ""
			(at 0 0 0)
			(layer "F.Fab")
			(hide yes)
			(effects
				(font
					(size 1 1)
					(thickness 0.15)
				)
			)
		)
		(sheetname "Ethernet")
		(sheetfile "ethernet.kicad_sch")
		(attr smd)
		(fp_rect
			(start -0.94 -0.47)
			(end 0.94 0.47)
			(stroke
				(width 0.05)
				(type solid)
			)
			(fill no)
			(layer "F.CrtYd")
		)
		(fp_rect
			(start -0.499 -0.249)
			(end 0.499 0.249)
			(stroke
				(width 0.15)
				(type solid)
			)
			(fill no)
			(layer "F.Fab")
		)
		(pad "1" smd roundrect
			(at -0.484 0)
			(size 0.59 0.64)
			(layers "F.Cu" "F.Mask" "F.Paste")
			(roundrect_rratio 0.25)
			(net 657 "ETH_XI")
			(pintype "passive")
		)
		(pad "2" smd roundrect
			(at 0.484 0)
			(size 0.59 0.64)
			(layers "F.Cu" "F.Mask" "F.Paste")
			(roundrect_rratio 0.25)
			(net 5 "GND")
			(pintype "passive")
		)
	)
	(footprint "antmicro-footprints:FB_0603_1608Metric"
		(layer "F.Cu")
		(at 189.286328 101.174306 -90)
		(property "Reference" "FB5"
			(at 1.025694 0.786328 270)
			(layer "F.SilkS")
			(effects
				(font
					(size 0.7 0.7)
					(thickness 0.15)
				)
				(justify left bottom)
			)
		)
		(property "Value" "FB_120Z_2A_0603"
			(at 0 1.5 270)
			(layer "F.Fab")
			(effects
				(font
					(size 0.7 0.7)
					(thickness 0.15)
				)
				(justify left bottom)
			)
		)
		(property "Description" "Ferrite Beads WE-TMSB Suppression 240Ohm 200mA "
			(at 0 0 270)
			(layer "F.Fab")
			(hide yes)
			(effects
				(font
					(size 1.27 1.27)
					(thickness 0.15)
				)
			)
		)
		(property "Author" "Antmicro"
			(at 88.112022 290.460634 0)
			(layer "F.Fab")
			(hide yes)
			(effects
				(font
					(size 1 1)
					(thickness 0.15)
				)
			)
		)
		(property "License" "Apache-2.0"
			(at 88.112022 290.460634 0)
			(layer "F.Fab")
			(hide yes)
			(effects
				(font
					(size 1 1)
					(thickness 0.15)
				)
			)
		)
		(property "MPN" "BLM18PG121SN1D"
			(at 88.112022 290.460634 0)
			(layer "F.Fab")
			(hide yes)
			(effects
				(font
					(size 1 1)
					(thickness 0.15)
				)
			)
		)
		(property "Manufacturer" "Murata"
			(at 88.112022 290.460634 0)
			(layer "F.Fab")
			(hide yes)
			(effects
				(font
					(size 1 1)
					(thickness 0.15)
				)
			)
		)
		(sheetname "Ethernet")
		(sheetfile "ethernet.kicad_sch")
		(attr smd)
		(fp_line
			(start -0.196 0.406)
			(end 0.193 0.406)
			(stroke
				(width 0.15)
				(type solid)
			)
			(layer "F.SilkS")
		)
		(fp_line
			(start -0.196 -0.408)
			(end 0.193 -0.408)
			(stroke
				(width 0.15)
				(type solid)
			)
			(layer "F.SilkS")
		)
		(fp_rect
			(start -1.3 -0.6)
			(end 1.3 0.6)
			(stroke
				(width 0.05)
				(type solid)
			)
			(fill no)
			(layer "F.CrtYd")
		)
		(fp_line
			(start -0.803 0.406)
			(end -0.803 -0.408)
			(stroke
				(width 0.15)
				(type solid)
			)
			(layer "F.Fab")
		)
		(fp_line
			(start 0.8 0.406)
			(end -0.803 0.406)
			(stroke
				(width 0.15)
				(type solid)
			)
			(layer "F.Fab")
		)
		(fp_line
			(start 0.8 -0.408)
			(end 0.8 0.406)
			(stroke
				(width 0.15)
				(type solid)
			)
			(layer "F.Fab")
		)
		(fp_line
			(start 0.8 -0.408)
			(end -0.803 -0.408)
			(stroke
				(width 0.15)
				(type solid)
			)
			(layer "F.Fab")
		)
		(pad "1" smd roundrect
			(at -0.891 0 270)
			(size 0.762 1.09)
			(layers "F.Cu" "F.Mask" "F.Paste")
			(roundrect_rratio 0.15)
			(net 602 "1V2_SYS")
			(pintype "passive")
		)
		(pad "2" smd roundrect
			(at 0.888 0 270)
			(size 0.762 1.09)
			(layers "F.Cu" "F.Mask" "F.Paste")
			(roundrect_rratio 0.15)
			(net 530 "/Ethernet/AVDDL_PLL")
			(pintype "passive")
		)
	)
	(footprint "antmicro-footprints:R_0402_1005Metric"
		(layer "F.Cu")
		(at 193.586328 106.474306 90)
		(descr "Resistor SMD 0402")
		(tags "resistor SMD 0402")
		(property "Reference" "R72"
			(at -1.225694 1.313672 90)
			(layer "F.SilkS")
			(effects
				(font
					(size 0.7 0.7)
					(thickness 0.15)
				)
				(justify left bottom)
			)
		)
		(property "Value" "R_12k1_0402"
			(at 0 1.4 90)
			(layer "F.Fab")
			(effects
				(font
					(size 0.7 0.7)
					(thickness 0.15)
				)
				(justify left bottom)
			)
		)
		(property "Description" "12k1 resistor in 0402 package with 1% tolerance"
			(at 0 0 90)
			(layer "F.Fab")
			(hide yes)
			(effects
				(font
					(size 1.27 1.27)
					(thickness 0.15)
				)
			)
		)
		(property "Author" "Antmicro"
			(at 300.060634 -87.112022 0)
			(layer "F.Fab")
			(hide yes)
			(effects
				(font
					(size 1 1)
					(thickness 0.15)
				)
			)
		)
		(property "License" "Apache-2.0"
			(at 300.060634 -87.112022 0)
			(layer "F.Fab")
			(hide yes)
			(effects
				(font
					(size 1 1)
					(thickness 0.15)
				)
			)
		)
		(property "MPN" "CR0402-FX-1212GLF"
			(at 300.060634 -87.112022 0)
			(layer "F.Fab")
			(hide yes)
			(effects
				(font
					(size 1 1)
					(thickness 0.15)
				)
			)
		)
		(property "Manufacturer" "Bourns"
			(at 300.060634 -87.112022 0)
			(layer "F.Fab")
			(hide yes)
			(effects
				(font
					(size 1 1)
					(thickness 0.15)
				)
			)
		)
		(property "Tolerance" "1%"
			(at 300.060634 -87.112022 0)
			(layer "F.Fab")
			(hide yes)
			(effects
				(font
					(size 1 1)
					(thickness 0.15)
				)
			)
		)
		(property "Val" "12k1"
			(at 300.060634 -87.112022 0)
			(layer "F.Fab")
			(hide yes)
			(effects
				(font
					(size 1 1)
					(thickness 0.15)
				)
			)
		)
		(sheetname "Ethernet")
		(sheetfile "ethernet.kicad_sch")
		(attr smd)
		(fp_rect
			(start -0.93 -0.47)
			(end 0.93 0.47)
			(stroke
				(width 0.05)
				(type solid)
			)
			(fill no)
			(layer "F.CrtYd")
		)
		(fp_rect
			(start -0.5 -0.25)
			(end 0.5 0.25)
			(stroke
				(width 0.15)
				(type solid)
			)
			(fill no)
			(layer "F.Fab")
		)
		(pad "1" smd roundrect
			(at -0.485 0 90)
			(size 0.59 0.64)
			(layers "F.Cu" "F.Mask" "F.Paste")
			(roundrect_rratio 0.25)
			(net 5 "GND")
			(pintype "passive")
		)
		(pad "2" smd roundrect
			(at 0.485 0 90)
			(size 0.59 0.64)
			(layers "F.Cu" "F.Mask" "F.Paste")
			(roundrect_rratio 0.25)
			(net 261 "Net-(U6-ISET)")
			(pintype "passive")
		)
	)
	(footprint "antmicro-footprints:R_0402_1005Metric"
		(layer "F.Cu")
		(at 193.586328 104.474306 -90)
		(descr "Resistor SMD 0402")
		(tags "resistor SMD 0402")
		(property "Reference" "R73"
			(at 1.025694 -1.313672 270)
			(layer "F.SilkS")
			(effects
				(font
					(size 0.7 0.7)
					(thickness 0.15)
				)
				(justify left bottom)
			)
		)
		(property "Value" "R_1M8_0402"
			(at 0 1.4 270)
			(layer "F.Fab")
			(effects
				(font
					(size 0.7 0.7)
					(thickness 0.15)
				)
				(justify left bottom)
			)
		)
		(property "Description" "1M8 resistor in 0402 package with 1% tolerance"
			(at 0 0 270)
			(layer "F.Fab")
			(hide yes)
			(effects
				(font
					(size 1.27 1.27)
					(thickness 0.15)
				)
			)
		)
		(property "Author" "Antmicro"
			(at 89.112022 298.060634 0)
			(layer "F.Fab")
			(hide yes)
			(effects
				(font
					(size 1 1)
					(thickness 0.15)
				)
			)
		)
		(property "License" "Apache-2.0"
			(at 89.112022 298.060634 0)
			(layer "F.Fab")
			(hide yes)
			(effects
				(font
					(size 1 1)
					(thickness 0.15)
				)
			)
		)
		(property "MPN" "CR0402-FX-1804GLF"
			(at 89.112022 298.060634 0)
			(layer "F.Fab")
			(hide yes)
			(effects
				(font
					(size 1 1)
					(thickness 0.15)
				)
			)
		)
		(property "Manufacturer" "Bourns"
			(at 89.112022 298.060634 0)
			(layer "F.Fab")
			(hide yes)
			(effects
				(font
					(size 1 1)
					(thickness 0.15)
				)
			)
		)
		(property "Tolerance" "1%"
			(at 89.112022 298.060634 0)
			(layer "F.Fab")
			(hide yes)
			(effects
				(font
					(size 1 1)
					(thickness 0.15)
				)
			)
		)
		(property "Val" "1M8"
			(at 89.112022 298.060634 0)
			(layer "F.Fab")
			(hide yes)
			(effects
				(font
					(size 1 1)
					(thickness 0.15)
				)
			)
		)
		(sheetname "Ethernet")
		(sheetfile "ethernet.kicad_sch")
		(attr smd)
		(fp_rect
			(start -0.93 -0.47)
			(end 0.93 0.47)
			(stroke
				(width 0.05)
				(type solid)
			)
			(fill no)
			(layer "F.CrtYd")
		)
		(fp_rect
			(start -0.5 -0.25)
			(end 0.5 0.25)
			(stroke
				(width 0.15)
				(type solid)
			)
			(fill no)
			(layer "F.Fab")
		)
		(pad "1" smd roundrect
			(at -0.485 0 270)
			(size 0.59 0.64)
			(layers "F.Cu" "F.Mask" "F.Paste")
			(roundrect_rratio 0.25)
			(net 656 "ETH_XO")
			(pintype "passive")
		)
		(pad "2" smd roundrect
			(at 0.485 0 270)
			(size 0.59 0.64)
			(layers "F.Cu" "F.Mask" "F.Paste")
			(roundrect_rratio 0.25)
			(net 657 "ETH_XI")
			(pintype "passive")
		)
	)
	(footprint "antmicro-footprints:Spacer_Drill3.7mm_H5mm_9774050151R"
		(layer "F.Cu")
		(at 154.136328 49.747157)
		(descr "Spacer steel M2.5 h=5mm fi=5.1mm")
		(property "Reference" "SP1"
			(at 3.597672 0.290843 0)
			(layer "F.SilkS")
			(effects
				(font
					(size 0.7 0.7)
					(thickness 0.15)
				)
				(justify left bottom)
			)
		)
		(property "Value" "Spacer_H5.0mm_9774050151"
			(at 0 4 0)
			(layer "F.Fab")
			(effects
				(font
					(size 0.7 0.7)
					(thickness 0.15)
				)
				(justify left bottom)
			)
		)
		(property "Description" "Spacer, SMT, Non Stop, Steel, Swage Round, 5.1 mm x 5 mm, M2.5 Thread, WA-SMSI Series"
			(at 0 0 0)
			(layer "F.Fab")
			(hide yes)
			(effects
				(font
					(size 1.27 1.27)
					(thickness 0.15)
				)
			)
		)
		(property "Author" "Antmicro"
			(at 0 0 0)
			(layer "F.Fab")
			(hide yes)
			(effects
				(font
					(size 1 1)
					(thickness 0.15)
				)
			)
		)
		(property "License" "Apache-2.0"
			(at 0 0 0)
			(layer "F.Fab")
			(hide yes)
			(effects
				(font
					(size 1 1)
					(thickness 0.15)
				)
			)
		)
		(property "MPN" "9774050151R"
			(at 0 0 0)
			(layer "F.Fab")
			(hide yes)
			(effects
				(font
					(size 1 1)
					(thickness 0.15)
				)
			)
		)
		(property "Manufacturer" "Würth Elektronik"
			(at 0 0 0)
			(layer "F.Fab")
			(hide yes)
			(effects
				(font
					(size 1 1)
					(thickness 0.15)
				)
			)
		)
		(sheetname "SO-DIMM")
		(sheetfile "sodimm.kicad_sch")
		(attr smd)
		(fp_circle
			(center 0 0)
			(end 0.05 -3.05)
			(stroke
				(width 0.05)
				(type solid)
			)
			(fill no)
			(layer "F.CrtYd")
		)
		(pad "1" thru_hole circle
			(at 0 0)
			(size 6 6)
			(drill 3.7)
			(layers "*.Cu" "*.Mask" "F.Paste")
			(remove_unused_layers no)
			(net 203 "unconnected-(SP1-Pad1)")
			(pintype "passive+no_connect")
			(solder_paste_margin_ratio -0.05)
		)
	)
	(footprint "antmicro-footprints:SW_Slide_E-Switch_EG1218"
		(layer "F.Cu")
		(at 184.236828 125.647157 -90)
		(property "Reference" "S1"
			(at -3.747157 2.336828 0)
			(layer "F.SilkS")
			(effects
				(font
					(size 0.7 0.7)
					(thickness 0.15)
				)
				(justify left bottom)
			)
		)
		(property "Value" "SW_EG1218"
			(at 0 3.5 270)
			(layer "F.Fab")
			(effects
				(font
					(size 0.7 0.7)
					(thickness 0.15)
				)
				(justify left bottom)
			)
		)
		(property "Description" "E-Switch Slide Switches PC MNT 3 PIN SLIDE"
			(at 0 0 270)
			(layer "F.Fab")
			(hide yes)
			(effects
				(font
					(size 1.27 1.27)
					(thickness 0.15)
				)
			)
		)
		(property "Author" "Antmicro"
			(at 58.589671 309.883985 0)
			(layer "F.Fab")
			(hide yes)
			(effects
				(font
					(size 1 1)
					(thickness 0.15)
				)
			)
		)
		(property "License" "Apache-2.0"
			(at 58.589671 309.883985 0)
			(layer "F.Fab")
			(hide yes)
			(effects
				(font
					(size 1 1)
					(thickness 0.15)
				)
			)
		)
		(property "MPN" "EG1218"
			(at 58.589671 309.883985 0)
			(layer "F.Fab")
			(hide yes)
			(effects
				(font
					(size 1 1)
					(thickness 0.15)
				)
			)
		)
		(property "Manufacturer" "E-Switch"
			(at 58.589671 309.883985 0)
			(layer "F.Fab")
			(hide yes)
			(effects
				(font
					(size 1 1)
					(thickness 0.15)
				)
			)
		)
		(sheetname "Supply")
		(sheetfile "supply.kicad_sch")
		(attr through_hole)
		(fp_line
			(start -3.5 2.2)
			(end -3 2.2)
			(stroke
				(width 0.15)
				(type solid)
			)
			(layer "F.SilkS")
		)
		(fp_line
			(start -3.5 2.2)
			(end -3.5 1.7)
			(stroke
				(width 0.15)
				(type solid)
			)
			(layer "F.SilkS")
		)
		(fp_line
			(start 8.5 2.2)
			(end 7.999 2.2)
			(stroke
				(width 0.15)
				(type solid)
			)
			(layer "F.SilkS")
		)
		(fp_line
			(start 8.5 2.2)
			(end 8.5 1.7)
			(stroke
				(width 0.15)
				(type solid)
			)
			(layer "F.SilkS")
		)
		(fp_line
			(start -3.5 -2.2)
			(end -3.5 -1.7)
			(stroke
				(width 0.15)
				(type solid)
			)
			(layer "F.SilkS")
		)
		(fp_line
			(start -3.5 -2.2)
			(end -3 -2.2)
			(stroke
				(width 0.15)
				(type solid)
			)
			(layer "F.SilkS")
		)
		(fp_line
			(start 8.5 -2.2)
			(end 8.5 -1.7)
			(stroke
				(width 0.15)
				(type solid)
			)
			(layer "F.SilkS")
		)
		(fp_line
			(start 8.5 -2.2)
			(end 7.999 -2.2)
			(stroke
				(width 0.15)
				(type solid)
			)
			(layer "F.SilkS")
		)
		(fp_rect
			(start -3.6 -2.299)
			(end 8.6 2.3)
			(stroke
				(width 0.05)
				(type solid)
			)
			(fill no)
			(layer "F.CrtYd")
		)
		(fp_rect
			(start 8.3 -2)
			(end -3.3 2)
			(stroke
				(width 0.15)
				(type solid)
			)
			(fill no)
			(layer "F.Fab")
		)
		(pad "1" thru_hole rect
			(at 0 0 270)
			(size 1.9 1.9)
			(drill 0.9)
			(layers "*.Cu" "*.Mask")
			(remove_unused_layers no)
			(net 202 "unconnected-(S1-Pad1)")
			(pintype "passive+no_connect")
		)
		(pad "2" thru_hole circle
			(at 2.499 0 270)
			(size 1.9 1.9)
			(drill 0.9)
			(layers "*.Cu" "*.Mask")
			(remove_unused_layers no)
			(net 514 "/Supply/SYS_EN")
			(pintype "passive")
		)
		(pad "3" thru_hole circle
			(at 4.998 0 270)
			(size 1.9 1.9)
			(drill 0.9)
			(layers "*.Cu" "*.Mask")
			(remove_unused_layers no)
			(net 5 "GND")
			(pintype "passive")
		)
	)
	(footprint "antmicro-footprints:oshw-logo"
		(layer "F.Cu")
		(at 191.386328 58.320008)
		(descr "OSHW Logo")
		(tags "OSHW Logo")
		(property "Reference" "N2"
			(at 0 -4.4 0)
			(layer "F.SilkS")
			(hide yes)
			(effects
				(font
					(size 0.7 0.7)
					(thickness 0.15)
				)
				(justify left bottom)
			)
		)
		(property "Value" "oshw_logo"
			(at 0 -3.4 0)
			(layer "F.Fab")
			(hide yes)
			(effects
				(font
					(size 0.7 0.7)
					(thickness 0.15)
				)
				(justify left bottom)
			)
		)
		(property "Author" "Antmicro"
			(at 0 0 0)
			(layer "F.Fab")
			(hide yes)
			(effects
				(font
					(size 1 1)
					(thickness 0.15)
				)
			)
		)
		(property "License" "Apache-2.0"
			(at 0 0 0)
			(layer "F.Fab")
			(hide yes)
			(effects
				(font
					(size 1 1)
					(thickness 0.15)
				)
			)
		)
		(property "MPN" ""
			(at 0 0 0)
			(layer "F.Fab")
			(hide yes)
			(effects
				(font
					(size 1 1)
					(thickness 0.15)
				)
			)
		)
		(property "Manufacturer" ""
			(at 0 0 0)
			(layer "F.Fab")
			(hide yes)
			(effects
				(font
					(size 1 1)
					(thickness 0.15)
				)
			)
		)
		(sheetfile "lpddr4-test-board.kicad_sch")
		(attr exclude_from_pos_files)
		(fp_poly
			(pts
				(xy -0.843 2.558) (xy -0.815 2.564) (xy -0.794 2.572) (xy -0.773 2.581) (xy -0.759 2.589) (xy -0.738 2.603)
				(xy -0.783 2.658) (xy -0.8 2.677) (xy -0.814 2.694) (xy -0.825 2.706) (xy -0.831 2.712) (xy -0.832 2.712)
				(xy -0.837 2.71) (xy -0.847 2.703) (xy -0.849 2.702) (xy -0.874 2.69) (xy -0.904 2.684) (xy -0.935 2.685)
				(xy -0.942 2.686) (xy -0.975 2.698) (xy -1.001 2.717) (xy -1.02 2.741) (xy -1.034 2.766) (xy -1.039 3.197)
				(xy -1.164 3.2) (xy -1.164 2.565) (xy -1.037 2.565) (xy -1.037 2.626) (xy -1.009 2.604) (xy -0.972 2.579)
				(xy -0.931 2.563) (xy -0.887 2.556) (xy -0.843 2.558)
			)
			(stroke
				(width 0.01)
				(type solid)
			)
			(fill yes)
			(layer "F.Cu")
		)
		(fp_poly
			(pts
				(xy 1.889 1.554) (xy 1.907 1.559) (xy 1.927 1.566) (xy 1.948 1.574) (xy 1.966 1.583) (xy 1.979 1.592)
				(xy 1.984 1.597) (xy 1.982 1.604) (xy 1.974 1.616) (xy 1.962 1.633) (xy 1.946 1.652) (xy 1.945 1.654)
				(xy 1.929 1.673) (xy 1.915 1.689) (xy 1.906 1.7) (xy 1.901 1.706) (xy 1.896 1.705) (xy 1.885 1.7)
				(xy 1.873 1.695) (xy 1.84 1.683) (xy 1.808 1.68) (xy 1.776 1.685) (xy 1.747 1.698) (xy 1.723 1.717)
				(xy 1.704 1.742) (xy 1.696 1.763) (xy 1.695 1.772) (xy 1.694 1.79) (xy 1.693 1.817) (xy 1.692 1.85)
				(xy 1.692 1.89) (xy 1.691 1.934) (xy 1.691 1.983) (xy 1.691 2.194) (xy 1.559 2.194) (xy 1.559 1.559)
				(xy 1.691 1.559) (xy 1.691 1.626) (xy 1.71 1.607) (xy 1.739 1.585) (xy 1.775 1.568) (xy 1.814 1.556)
				(xy 1.855 1.552) (xy 1.889 1.554)
			)
			(stroke
				(width 0.01)
				(type solid)
			)
			(fill yes)
			(layer "F.Cu")
		)
		(fp_poly
			(pts
				(xy -0.837 1.56) (xy -0.797 1.576) (xy -0.761 1.6) (xy -0.73 1.63) (xy -0.706 1.667) (xy -0.69 1.709)
				(xy -0.687 1.721) (xy -0.685 1.734) (xy -0.684 1.757) (xy -0.683 1.79) (xy -0.682 1.833) (xy -0.681 1.884)
				(xy -0.681 1.945) (xy -0.681 1.971) (xy -0.681 2.194) (xy -0.808 2.194) (xy -0.809 1.984) (xy -0.811 1.774)
				(xy -0.826 1.744) (xy -0.845 1.716) (xy -0.868 1.697) (xy -0.897 1.686) (xy -0.925 1.682) (xy -0.947 1.682)
				(xy -0.967 1.684) (xy -0.979 1.686) (xy -1.001 1.698) (xy -1.023 1.716) (xy -1.041 1.738) (xy -1.049 1.752)
				(xy -1.052 1.758) (xy -1.054 1.765) (xy -1.056 1.773) (xy -1.057 1.783) (xy -1.058 1.797) (xy -1.059 1.815)
				(xy -1.06 1.839) (xy -1.06 1.869) (xy -1.061 1.907) (xy -1.061 1.953) (xy -1.061 1.985) (xy -1.063 2.194)
				(xy -1.189 2.194) (xy -1.189 1.559) (xy -1.062 1.559) (xy -1.062 1.625) (xy -1.033 1.602) (xy -1.001 1.579)
				(xy -0.969 1.564) (xy -0.934 1.555) (xy -0.927 1.554) (xy -0.881 1.553) (xy -0.837 1.56)
			)
			(stroke
				(width 0.01)
				(type solid)
			)
			(fill yes)
			(layer "F.Cu")
		)
		(fp_poly
			(pts
				(xy 1.042 1.769) (xy 1.043 1.979) (xy 1.059 2.009) (xy 1.077 2.036) (xy 1.1 2.056) (xy 1.129 2.067)
				(xy 1.159 2.071) (xy 1.193 2.07) (xy 1.221 2.063) (xy 1.245 2.047) (xy 1.258 2.034) (xy 1.266 2.025)
				(xy 1.273 2.016) (xy 1.278 2.008) (xy 1.282 1.997) (xy 1.286 1.985) (xy 1.288 1.969) (xy 1.29 1.948)
				(xy 1.291 1.922) (xy 1.292 1.89) (xy 1.293 1.85) (xy 1.293 1.801) (xy 1.294 1.766) (xy 1.295 1.559)
				(xy 1.422 1.559) (xy 1.422 2.194) (xy 1.295 2.194) (xy 1.295 2.161) (xy 1.295 2.144) (xy 1.293 2.132)
				(xy 1.292 2.128) (xy 1.287 2.131) (xy 1.278 2.14) (xy 1.271 2.147) (xy 1.256 2.159) (xy 1.236 2.171)
				(xy 1.219 2.181) (xy 1.202 2.188) (xy 1.186 2.193) (xy 1.17 2.196) (xy 1.148 2.197) (xy 1.135 2.198)
				(xy 1.107 2.198) (xy 1.087 2.197) (xy 1.07 2.194) (xy 1.059 2.19) (xy 1.036 2.181) (xy 1.019 2.172)
				(xy 1.003 2.161) (xy 0.985 2.146) (xy 0.981 2.141) (xy 0.952 2.107) (xy 0.931 2.068) (xy 0.92 2.033)
				(xy 0.918 2.019) (xy 0.917 1.996) (xy 0.916 1.963) (xy 0.915 1.92) (xy 0.914 1.869) (xy 0.914 1.808)
				(xy 0.914 1.782) (xy 0.914 1.559) (xy 1.04 1.559) (xy 1.042 1.769)
			)
			(stroke
				(width 0.01)
				(type solid)
			)
			(fill yes)
			(layer "F.Cu")
		)
		(fp_poly
			(pts
				(xy 1.753 2.563) (xy 1.768 2.568) (xy 1.787 2.577) (xy 1.804 2.586) (xy 1.818 2.595) (xy 1.826 2.602)
				(xy 1.827 2.606) (xy 1.824 2.611) (xy 1.815 2.621) (xy 1.803 2.636) (xy 1.789 2.654) (xy 1.775 2.671)
				(xy 1.761 2.688) (xy 1.749 2.701) (xy 1.742 2.71) (xy 1.739 2.712) (xy 1.735 2.71) (xy 1.724 2.704)
				(xy 1.713 2.698) (xy 1.697 2.69) (xy 1.682 2.686) (xy 1.664 2.685) (xy 1.653 2.685) (xy 1.618 2.688)
				(xy 1.59 2.699) (xy 1.566 2.718) (xy 1.561 2.723) (xy 1.554 2.732) (xy 1.548 2.74) (xy 1.544 2.748)
				(xy 1.54 2.758) (xy 1.537 2.769) (xy 1.534 2.785) (xy 1.533 2.804) (xy 1.532 2.829) (xy 1.531 2.861)
				(xy 1.53 2.899) (xy 1.53 2.947) (xy 1.53 2.988) (xy 1.528 3.2) (xy 1.468 3.2) (xy 1.444 3.2) (xy 1.425 3.199)
				(xy 1.411 3.198) (xy 1.405 3.197) (xy 1.404 3.191) (xy 1.404 3.176) (xy 1.403 3.153) (xy 1.403 3.122)
				(xy 1.402 3.085) (xy 1.402 3.042) (xy 1.402 2.993) (xy 1.402 2.941) (xy 1.402 2.886) (xy 1.402 2.565)
				(xy 1.529 2.565) (xy 1.529 2.595) (xy 1.529 2.611) (xy 1.53 2.623) (xy 1.532 2.626) (xy 1.537 2.623)
				(xy 1.547 2.615) (xy 1.554 2.608) (xy 1.588 2.584) (xy 1.627 2.567) (xy 1.669 2.558) (xy 1.712 2.556)
				(xy 1.753 2.563)
			)
			(stroke
				(width 0.01)
				(type solid)
			)
			(fill yes)
			(layer "F.Cu")
		)
		(fp_poly
			(pts
				(xy 2.316 1.557) (xy 2.365 1.57) (xy 2.41 1.593) (xy 2.453 1.625) (xy 2.46 1.631) (xy 2.491 1.661)
				(xy 2.466 1.684) (xy 2.448 1.699) (xy 2.43 1.715) (xy 2.419 1.725) (xy 2.397 1.743) (xy 2.376 1.724)
				(xy 2.345 1.701) (xy 2.312 1.687) (xy 2.274 1.681) (xy 2.265 1.681) (xy 2.226 1.684) (xy 2.195 1.693)
				(xy 2.167 1.708) (xy 2.159 1.715) (xy 2.136 1.741) (xy 2.118 1.776) (xy 2.107 1.817) (xy 2.103 1.866)
				(xy 2.103 1.876) (xy 2.106 1.926) (xy 2.116 1.97) (xy 2.132 2.006) (xy 2.155 2.034) (xy 2.184 2.055)
				(xy 2.219 2.067) (xy 2.259 2.072) (xy 2.274 2.071) (xy 2.309 2.066) (xy 2.339 2.056) (xy 2.366 2.038)
				(xy 2.377 2.028) (xy 2.386 2.02) (xy 2.393 2.016) (xy 2.4 2.015) (xy 2.409 2.018) (xy 2.42 2.027)
				(xy 2.436 2.041) (xy 2.456 2.059) (xy 2.491 2.092) (xy 2.476 2.108) (xy 2.449 2.132) (xy 2.416 2.155)
				(xy 2.38 2.174) (xy 2.35 2.186) (xy 2.327 2.193) (xy 2.306 2.197) (xy 2.283 2.199) (xy 2.259 2.199)
				(xy 2.233 2.198) (xy 2.209 2.196) (xy 2.189 2.193) (xy 2.182 2.191) (xy 2.133 2.173) (xy 2.089 2.146)
				(xy 2.053 2.112) (xy 2.023 2.071) (xy 2.012 2.051) (xy 2 2.023) (xy 1.991 1.999) (xy 1.984 1.975)
				(xy 1.981 1.948) (xy 1.979 1.917) (xy 1.978 1.879) (xy 1.978 1.877) (xy 1.979 1.838) (xy 1.98 1.806)
				(xy 1.984 1.78) (xy 1.99 1.756) (xy 1.999 1.731) (xy 2.011 1.704) (xy 2.012 1.701) (xy 2.039 1.657)
				(xy 2.072 1.62) (xy 2.111 1.591) (xy 2.156 1.57) (xy 2.207 1.557) (xy 2.263 1.552) (xy 2.316 1.557)
			)
			(stroke
				(width 0.01)
				(type solid)
			)
			(fill yes)
			(layer "F.Cu")
		)
		(fp_poly
			(pts
				(xy -1.494 1.56) (xy -1.447 1.576) (xy -1.405 1.6) (xy -1.368 1.633) (xy -1.341 1.668) (xy -1.326 1.692)
				(xy -1.316 1.716) (xy -1.308 1.743) (xy -1.302 1.774) (xy -1.299 1.811) (xy -1.297 1.845) (xy -1.294 1.925)
				(xy -1.692 1.925) (xy -1.692 1.942) (xy -1.687 1.977) (xy -1.673 2.011) (xy -1.65 2.039) (xy -1.626 2.059)
				(xy -1.601 2.071) (xy -1.572 2.078) (xy -1.537 2.079) (xy -1.497 2.074) (xy -1.458 2.06) (xy -1.422 2.036)
				(xy -1.421 2.036) (xy -1.402 2.021) (xy -1.359 2.057) (xy -1.342 2.072) (xy -1.327 2.085) (xy -1.317 2.094)
				(xy -1.314 2.098) (xy -1.316 2.103) (xy -1.324 2.113) (xy -1.338 2.126) (xy -1.354 2.139) (xy -1.372 2.152)
				(xy -1.389 2.163) (xy -1.399 2.168) (xy -1.421 2.178) (xy -1.445 2.187) (xy -1.461 2.191) (xy -1.488 2.196)
				(xy -1.522 2.199) (xy -1.557 2.199) (xy -1.591 2.196) (xy -1.62 2.192) (xy -1.629 2.19) (xy -1.677 2.171)
				(xy -1.718 2.146) (xy -1.752 2.114) (xy -1.779 2.074) (xy -1.8 2.026) (xy -1.802 2.02) (xy -1.81 1.989)
				(xy -1.815 1.951) (xy -1.818 1.908) (xy -1.819 1.865) (xy -1.818 1.823) (xy -1.816 1.804) (xy -1.692 1.804)
				(xy -1.692 1.818) (xy -1.428 1.818) (xy -1.428 1.801) (xy -1.432 1.775) (xy -1.442 1.748) (xy -1.457 1.722)
				(xy -1.469 1.707) (xy -1.495 1.688) (xy -1.526 1.676) (xy -1.56 1.672) (xy -1.593 1.676) (xy -1.619 1.685)
				(xy -1.646 1.704) (xy -1.668 1.73) (xy -1.683 1.76) (xy -1.691 1.792) (xy -1.692 1.804) (xy -1.816 1.804)
				(xy -1.814 1.786) (xy -1.812 1.777) (xy -1.797 1.724) (xy -1.775 1.676) (xy -1.747 1.636) (xy -1.713 1.603)
				(xy -1.673 1.578) (xy -1.629 1.561) (xy -1.597 1.554) (xy -1.544 1.552) (xy -1.494 1.56)
			)
			(stroke
				(width 0.01)
				(type solid)
			)
			(fill yes)
			(layer "F.Cu")
		)
		(fp_poly
			(pts
				(xy 2.835 1.557) (xy 2.883 1.57) (xy 2.926 1.592) (xy 2.964 1.621) (xy 2.996 1.657) (xy 3.021 1.699)
				(xy 3.038 1.747) (xy 3.04 1.757) (xy 3.043 1.776) (xy 3.045 1.802) (xy 3.047 1.832) (xy 3.047 1.858)
				(xy 3.047 1.925) (xy 2.65 1.925) (xy 2.653 1.951) (xy 2.663 1.991) (xy 2.68 2.024) (xy 2.703 2.049)
				(xy 2.733 2.067) (xy 2.77 2.077) (xy 2.801 2.079) (xy 2.845 2.075) (xy 2.883 2.063) (xy 2.916 2.042)
				(xy 2.92 2.039) (xy 2.929 2.031) (xy 2.935 2.026) (xy 2.941 2.025) (xy 2.949 2.027) (xy 2.959 2.034)
				(xy 2.974 2.047) (xy 2.994 2.064) (xy 3.01 2.078) (xy 3.023 2.088) (xy 3.03 2.095) (xy 3.032 2.096)
				(xy 3.03 2.1) (xy 3.022 2.11) (xy 3.01 2.122) (xy 3.009 2.123) (xy 2.98 2.147) (xy 2.945 2.169)
				(xy 2.906 2.185) (xy 2.887 2.191) (xy 2.861 2.196) (xy 2.828 2.198) (xy 2.793 2.198) (xy 2.759 2.197)
				(xy 2.729 2.193) (xy 2.721 2.191) (xy 2.675 2.175) (xy 2.634 2.15) (xy 2.599 2.118) (xy 2.569 2.077)
				(xy 2.547 2.029) (xy 2.536 1.996) (xy 2.532 1.973) (xy 2.529 1.942) (xy 2.527 1.906) (xy 2.527 1.869)
				(xy 2.528 1.832) (xy 2.529 1.818) (xy 2.65 1.818) (xy 2.922 1.818) (xy 2.918 1.799) (xy 2.908 1.758)
				(xy 2.891 1.725) (xy 2.869 1.7) (xy 2.84 1.683) (xy 2.826 1.678) (xy 2.788 1.672) (xy 2.753 1.675)
				(xy 2.722 1.687) (xy 2.695 1.706) (xy 2.674 1.734) (xy 2.659 1.768) (xy 2.654 1.794) (xy 2.65 1.818)
				(xy 2.529 1.818) (xy 2.53 1.798) (xy 2.534 1.769) (xy 2.536 1.76) (xy 2.554 1.707) (xy 2.578 1.662)
				(xy 2.609 1.624) (xy 2.645 1.593) (xy 2.687 1.571) (xy 2.734 1.557) (xy 2.783 1.553) (xy 2.835 1.557)
			)
			(stroke
				(width 0.01)
				(type solid)
			)
			(fill yes)
			(layer "F.Cu")
		)
		(fp_poly
			(pts
				(xy -2.733 1.557) (xy -2.685 1.57) (xy -2.642 1.592) (xy -2.604 1.622) (xy -2.581 1.649) (xy -2.562 1.676)
				(xy -2.548 1.706) (xy -2.537 1.739) (xy -2.53 1.777) (xy -2.527 1.821) (xy -2.526 1.873) (xy -2.527 1.907)
				(xy -2.529 1.956) (xy -2.534 1.997) (xy -2.542 2.031) (xy -2.553 2.06) (xy -2.567 2.086) (xy -2.587 2.111)
				(xy -2.603 2.129) (xy -2.637 2.158) (xy -2.673 2.178) (xy -2.714 2.192) (xy -2.76 2.198) (xy -2.789 2.199)
				(xy -2.813 2.198) (xy -2.835 2.196) (xy -2.852 2.194) (xy -2.857 2.194) (xy -2.898 2.179) (xy -2.937 2.155)
				(xy -2.97 2.126) (xy -2.993 2.101) (xy -3.011 2.077) (xy -3.024 2.051) (xy -3.034 2.022) (xy -3.041 1.988)
				(xy -3.045 1.947) (xy -3.047 1.91) (xy -3.047 1.882) (xy -2.919 1.882) (xy -2.919 1.968) (xy -2.903 2.001)
				(xy -2.885 2.031) (xy -2.863 2.051) (xy -2.837 2.064) (xy -2.804 2.07) (xy -2.779 2.07) (xy -2.755 2.069)
				(xy -2.737 2.065) (xy -2.722 2.058) (xy -2.717 2.055) (xy -2.697 2.041) (xy -2.681 2.025) (xy -2.67 2.004)
				(xy -2.662 1.978) (xy -2.657 1.945) (xy -2.654 1.903) (xy -2.654 1.899) (xy -2.653 1.848) (xy -2.656 1.806)
				(xy -2.662 1.772) (xy -2.673 1.744) (xy -2.687 1.722) (xy -2.707 1.705) (xy -2.723 1.695) (xy -2.755 1.684)
				(xy -2.788 1.68) (xy -2.821 1.684) (xy -2.851 1.695) (xy -2.877 1.713) (xy -2.892 1.729) (xy -2.901 1.745)
				(xy -2.908 1.76) (xy -2.913 1.778) (xy -2.916 1.8) (xy -2.918 1.828) (xy -2.919 1.864) (xy -2.919 1.882)
				(xy -3.047 1.882) (xy -3.048 1.844) (xy -3.043 1.786) (xy -3.034 1.736) (xy -3.021 1.695) (xy -3.004 1.664)
				(xy -2.972 1.624) (xy -2.935 1.594) (xy -2.893 1.571) (xy -2.846 1.558) (xy -2.794 1.553) (xy -2.787 1.553)
				(xy -2.733 1.557)
			)
			(stroke
				(width 0.01)
				(type solid)
			)
			(fill yes)
			(layer "F.Cu")
		)
		(fp_poly
			(pts
				(xy 2.148 2.561) (xy 2.193 2.574) (xy 2.235 2.595) (xy 2.273 2.623) (xy 2.304 2.657) (xy 2.326 2.691)
				(xy 2.338 2.718) (xy 2.346 2.745) (xy 2.352 2.774) (xy 2.355 2.808) (xy 2.357 2.85) (xy 2.357 2.858)
				(xy 2.357 2.931) (xy 1.96 2.931) (xy 1.963 2.955) (xy 1.973 2.993) (xy 1.991 3.026) (xy 2.015 3.053)
				(xy 2.039 3.069) (xy 2.057 3.076) (xy 2.08 3.08) (xy 2.103 3.082) (xy 2.144 3.081) (xy 2.18 3.071)
				(xy 2.214 3.054) (xy 2.227 3.045) (xy 2.24 3.035) (xy 2.25 3.029) (xy 2.253 3.027) (xy 2.258 3.03)
				(xy 2.269 3.039) (xy 2.284 3.05) (xy 2.3 3.064) (xy 2.315 3.078) (xy 2.329 3.09) (xy 2.338 3.099)
				(xy 2.341 3.103) (xy 2.337 3.11) (xy 2.327 3.121) (xy 2.312 3.134) (xy 2.294 3.148) (xy 2.276 3.161)
				(xy 2.259 3.171) (xy 2.252 3.175) (xy 2.204 3.192) (xy 2.152 3.202) (xy 2.098 3.204) (xy 2.046 3.198)
				(xy 2.032 3.195) (xy 1.984 3.178) (xy 1.943 3.154) (xy 1.909 3.123) (xy 1.881 3.084) (xy 1.859 3.037)
				(xy 1.847 3.003) (xy 1.841 2.972) (xy 1.838 2.934) (xy 1.836 2.893) (xy 1.837 2.851) (xy 1.839 2.824)
				(xy 1.96 2.824) (xy 2.23 2.824) (xy 2.23 2.813) (xy 2.225 2.783) (xy 2.214 2.753) (xy 2.196 2.725)
				(xy 2.175 2.702) (xy 2.151 2.686) (xy 2.128 2.68) (xy 2.101 2.677) (xy 2.072 2.678) (xy 2.051 2.683)
				(xy 2.023 2.696) (xy 2 2.717) (xy 1.981 2.746) (xy 1.968 2.779) (xy 1.963 2.8) (xy 1.96 2.824) (xy 1.839 2.824)
				(xy 1.839 2.811) (xy 1.844 2.776) (xy 1.848 2.76) (xy 1.866 2.708) (xy 1.889 2.663) (xy 1.919 2.627)
				(xy 1.954 2.598) (xy 1.996 2.575) (xy 2.007 2.571) (xy 2.054 2.559) (xy 2.101 2.556) (xy 2.148 2.561)
			)
			(stroke
				(width 0.01)
				(type solid)
			)
			(fill yes)
			(layer "F.Cu")
		)
		(fp_poly
			(pts
				(xy -0.229 3.2) (xy -0.354 3.197) (xy -0.355 3.165) (xy -0.357 3.133) (xy -0.374 3.148) (xy -0.411 3.175)
				(xy -0.453 3.193) (xy -0.497 3.203) (xy -0.542 3.204) (xy -0.585 3.195) (xy -0.586 3.195) (xy -0.621 3.181)
				(xy -0.651 3.16) (xy -0.673 3.141) (xy -0.689 3.123) (xy -0.702 3.106) (xy -0.712 3.086) (xy -0.72 3.064)
				(xy -0.726 3.038) (xy -0.73 3.007) (xy -0.732 2.968) (xy -0.733 2.922) (xy -0.733 2.88) (xy -0.602 2.88)
				(xy -0.602 2.915) (xy -0.602 2.942) (xy -0.601 2.962) (xy -0.6 2.977) (xy -0.598 2.988) (xy -0.596 2.998)
				(xy -0.592 3.007) (xy -0.591 3.01) (xy -0.574 3.039) (xy -0.552 3.059) (xy -0.525 3.071) (xy -0.492 3.076)
				(xy -0.472 3.076) (xy -0.442 3.072) (xy -0.418 3.063) (xy -0.398 3.048) (xy -0.382 3.029) (xy -0.371 3.004)
				(xy -0.363 2.972) (xy -0.358 2.933) (xy -0.356 2.885) (xy -0.356 2.88) (xy -0.358 2.828) (xy -0.363 2.785)
				(xy -0.373 2.75) (xy -0.387 2.724) (xy -0.406 2.704) (xy -0.43 2.692) (xy -0.46 2.686) (xy -0.483 2.685)
				(xy -0.517 2.687) (xy -0.544 2.696) (xy -0.565 2.711) (xy -0.583 2.734) (xy -0.591 2.751) (xy -0.595 2.76)
				(xy -0.598 2.769) (xy -0.6 2.779) (xy -0.601 2.793) (xy -0.602 2.811) (xy -0.602 2.836) (xy -0.602 2.869)
				(xy -0.602 2.88) (xy -0.733 2.88) (xy -0.733 2.827) (xy -0.732 2.783) (xy -0.729 2.746) (xy -0.725 2.716)
				(xy -0.719 2.691) (xy -0.71 2.67) (xy -0.699 2.651) (xy -0.685 2.633) (xy -0.668 2.616) (xy -0.668 2.615)
				(xy -0.632 2.587) (xy -0.592 2.567) (xy -0.55 2.557) (xy -0.506 2.556) (xy -0.463 2.564) (xy -0.421 2.582)
				(xy -0.411 2.587) (xy -0.394 2.598) (xy -0.377 2.61) (xy -0.373 2.614) (xy -0.356 2.627) (xy -0.356 2.306)
				(xy -0.229 2.306) (xy -0.229 3.2)
			)
			(stroke
				(width 0.01)
				(type solid)
			)
			(fill yes)
			(layer "F.Cu")
		)
		(fp_poly
			(pts
				(xy 0.605 1.558) (xy 0.651 1.574) (xy 0.694 1.598) (xy 0.728 1.627) (xy 0.75 1.652) (xy 0.768 1.678)
				(xy 0.781 1.707) (xy 0.791 1.739) (xy 0.797 1.777) (xy 0.801 1.822) (xy 0.802 1.876) (xy 0.802 1.877)
				(xy 0.801 1.929) (xy 0.798 1.973) (xy 0.792 2.009) (xy 0.784 2.04) (xy 0.774 2.062) (xy 0.748 2.103)
				(xy 0.715 2.139) (xy 0.675 2.167) (xy 0.632 2.187) (xy 0.626 2.189) (xy 0.599 2.195) (xy 0.567 2.198)
				(xy 0.532 2.199) (xy 0.499 2.197) (xy 0.471 2.193) (xy 0.466 2.192) (xy 0.428 2.177) (xy 0.391 2.155)
				(xy 0.359 2.129) (xy 0.354 2.123) (xy 0.332 2.098) (xy 0.316 2.073) (xy 0.303 2.047) (xy 0.294 2.017)
				(xy 0.287 1.983) (xy 0.284 1.943) (xy 0.282 1.894) (xy 0.282 1.877) (xy 0.409 1.877) (xy 0.41 1.918)
				(xy 0.412 1.95) (xy 0.416 1.976) (xy 0.423 1.997) (xy 0.432 2.015) (xy 0.445 2.03) (xy 0.451 2.037)
				(xy 0.471 2.054) (xy 0.491 2.064) (xy 0.514 2.07) (xy 0.543 2.072) (xy 0.569 2.07) (xy 0.59 2.065)
				(xy 0.601 2.06) (xy 0.625 2.047) (xy 0.642 2.031) (xy 0.656 2.009) (xy 0.661 1.998) (xy 0.665 1.989)
				(xy 0.668 1.98) (xy 0.67 1.969) (xy 0.671 1.954) (xy 0.672 1.935) (xy 0.673 1.909) (xy 0.673 1.877)
				(xy 0.673 1.842) (xy 0.672 1.817) (xy 0.671 1.798) (xy 0.67 1.784) (xy 0.668 1.773) (xy 0.665 1.764)
				(xy 0.661 1.755) (xy 0.647 1.73) (xy 0.632 1.712) (xy 0.612 1.698) (xy 0.601 1.693) (xy 0.569 1.683)
				(xy 0.535 1.681) (xy 0.501 1.686) (xy 0.471 1.7) (xy 0.447 1.719) (xy 0.434 1.736) (xy 0.424 1.753)
				(xy 0.417 1.774) (xy 0.412 1.8) (xy 0.41 1.833) (xy 0.409 1.873) (xy 0.409 1.877) (xy 0.282 1.877)
				(xy 0.283 1.824) (xy 0.286 1.78) (xy 0.292 1.742) (xy 0.301 1.711) (xy 0.313 1.683) (xy 0.33 1.657)
				(xy 0.35 1.633) (xy 0.351 1.632) (xy 0.385 1.601) (xy 0.42 1.578) (xy 0.46 1.563) (xy 0.505 1.554)
				(xy 0.555 1.551) (xy 0.605 1.558)
			)
			(stroke
				(width 0.01)
				(type solid)
			)
			(fill yes)
			(layer "F.Cu")
		)
		(fp_poly
			(pts
				(xy 0.004 1.556) (xy 0.054 1.566) (xy 0.102 1.582) (xy 0.146 1.605) (xy 0.154 1.61) (xy 0.193 1.636)
				(xy 0.178 1.655) (xy 0.166 1.668) (xy 0.152 1.686) (xy 0.138 1.7) (xy 0.114 1.727) (xy 0.07 1.705)
				(xy 0.032 1.688) (xy -0.007 1.677) (xy -0.044 1.672) (xy -0.079 1.672) (xy -0.11 1.678) (xy -0.136 1.69)
				(xy -0.154 1.707) (xy -0.162 1.724) (xy -0.164 1.745) (xy -0.164 1.761) (xy -0.159 1.772) (xy -0.15 1.782)
				(xy -0.149 1.783) (xy -0.139 1.791) (xy -0.128 1.797) (xy -0.114 1.802) (xy -0.095 1.805) (xy -0.07 1.808)
				(xy -0.037 1.811) (xy -0.02 1.813) (xy 0.027 1.817) (xy 0.065 1.823) (xy 0.096 1.832) (xy 0.122 1.842)
				(xy 0.14 1.854) (xy 0.166 1.879) (xy 0.186 1.91) (xy 0.2 1.947) (xy 0.206 1.987) (xy 0.206 2.018)
				(xy 0.198 2.06) (xy 0.181 2.097) (xy 0.155 2.129) (xy 0.122 2.156) (xy 0.08 2.177) (xy 0.042 2.189)
				(xy 0.005 2.196) (xy -0.038 2.199) (xy -0.083 2.198) (xy -0.125 2.194) (xy -0.153 2.189) (xy -0.177 2.181)
				(xy -0.204 2.171) (xy -0.229 2.16) (xy -0.232 2.159) (xy -0.251 2.148) (xy -0.272 2.136) (xy -0.292 2.122)
				(xy -0.309 2.109) (xy -0.323 2.098) (xy -0.33 2.09) (xy -0.331 2.088) (xy -0.327 2.084) (xy -0.318 2.073)
				(xy -0.304 2.059) (xy -0.288 2.043) (xy -0.246 2) (xy -0.221 2.021) (xy -0.184 2.047) (xy -0.145 2.065)
				(xy -0.102 2.075) (xy -0.053 2.079) (xy -0.049 2.079) (xy -0.023 2.079) (xy -0.004 2.078) (xy 0.011 2.074)
				(xy 0.025 2.069) (xy 0.029 2.068) (xy 0.054 2.052) (xy 0.071 2.033) (xy 0.079 2.01) (xy 0.078 1.986)
				(xy 0.074 1.975) (xy 0.068 1.964) (xy 0.06 1.956) (xy 0.048 1.949) (xy 0.031 1.944) (xy 0.007 1.939)
				(xy -0.024 1.935) (xy -0.052 1.932) (xy -0.089 1.929) (xy -0.119 1.925) (xy -0.142 1.921) (xy -0.16 1.917)
				(xy -0.176 1.912) (xy -0.192 1.906) (xy -0.201 1.901) (xy -0.235 1.879) (xy -0.262 1.85) (xy -0.28 1.816)
				(xy -0.29 1.776) (xy -0.292 1.75) (xy -0.291 1.727) (xy -0.289 1.705) (xy -0.286 1.689) (xy -0.286 1.688)
				(xy -0.273 1.659) (xy -0.253 1.63) (xy -0.229 1.604) (xy -0.221 1.599) (xy -0.185 1.577) (xy -0.143 1.562)
				(xy -0.096 1.554) (xy -0.047 1.552) (xy 0.004 1.556)
			)
			(stroke
				(width 0.01)
				(type solid)
			)
			(fill yes)
			(layer "F.Cu")
		)
		(fp_poly
			(pts
				(xy 1.038 2.556) (xy 1.091 2.563) (xy 1.137 2.576) (xy 1.177 2.595) (xy 1.209 2.62) (xy 1.234 2.65)
				(xy 1.242 2.665) (xy 1.247 2.677) (xy 1.251 2.691) (xy 1.255 2.708) (xy 1.258 2.727) (xy 1.26 2.751)
				(xy 1.262 2.78) (xy 1.263 2.815) (xy 1.263 2.858) (xy 1.264 2.908) (xy 1.263 2.967) (xy 1.263 2.989)
				(xy 1.262 3.197) (xy 1.135 3.197) (xy 1.133 3.171) (xy 1.132 3.144) (xy 1.119 3.159) (xy 1.096 3.179)
				(xy 1.065 3.193) (xy 1.026 3.202) (xy 0.98 3.204) (xy 0.976 3.204) (xy 0.955 3.204) (xy 0.937 3.203)
				(xy 0.925 3.202) (xy 0.924 3.201) (xy 0.879 3.189) (xy 0.839 3.17) (xy 0.806 3.144) (xy 0.781 3.113)
				(xy 0.763 3.077) (xy 0.753 3.037) (xy 0.753 3.005) (xy 0.873 3.005) (xy 0.874 3.023) (xy 0.878 3.035)
				(xy 0.887 3.047) (xy 0.89 3.05) (xy 0.903 3.063) (xy 0.917 3.072) (xy 0.935 3.078) (xy 0.957 3.081)
				(xy 0.986 3.082) (xy 1.013 3.082) (xy 1.043 3.081) (xy 1.065 3.079) (xy 1.08 3.077) (xy 1.091 3.073)
				(xy 1.096 3.071) (xy 1.112 3.058) (xy 1.123 3.039) (xy 1.13 3.012) (xy 1.132 2.977) (xy 1.132 2.975)
				(xy 1.132 2.931) (xy 1.035 2.931) (xy 0.999 2.931) (xy 0.973 2.931) (xy 0.953 2.932) (xy 0.939 2.934)
				(xy 0.928 2.936) (xy 0.919 2.939) (xy 0.916 2.94) (xy 0.893 2.954) (xy 0.88 2.971) (xy 0.874 2.994)
				(xy 0.873 3.005) (xy 0.753 3.005) (xy 0.753 2.994) (xy 0.761 2.951) (xy 0.768 2.931) (xy 0.776 2.915)
				(xy 0.786 2.901) (xy 0.802 2.884) (xy 0.804 2.882) (xy 0.82 2.867) (xy 0.835 2.854) (xy 0.85 2.845)
				(xy 0.867 2.838) (xy 0.887 2.833) (xy 0.912 2.829) (xy 0.943 2.827) (xy 0.982 2.826) (xy 1.015 2.825)
				(xy 1.133 2.823) (xy 1.132 2.771) (xy 1.131 2.746) (xy 1.129 2.73) (xy 1.127 2.719) (xy 1.123 2.711)
				(xy 1.117 2.705) (xy 1.098 2.691) (xy 1.07 2.682) (xy 1.032 2.677) (xy 1.006 2.677) (xy 0.972 2.678)
				(xy 0.945 2.682) (xy 0.924 2.688) (xy 0.907 2.699) (xy 0.9 2.706) (xy 0.882 2.723) (xy 0.834 2.686)
				(xy 0.816 2.672) (xy 0.801 2.66) (xy 0.79 2.652) (xy 0.787 2.648) (xy 0.791 2.639) (xy 0.801 2.626)
				(xy 0.816 2.612) (xy 0.832 2.6) (xy 0.864 2.581) (xy 0.902 2.568) (xy 0.946 2.559) (xy 0.98 2.556)
				(xy 1.038 2.556)
			)
			(stroke
				(width 0.01)
				(type solid)
			)
			(fill yes)
			(layer "F.Cu")
		)
		(fp_poly
			(pts
				(xy -1.521 2.559) (xy -1.485 2.562) (xy -1.454 2.568) (xy -1.427 2.577) (xy -1.401 2.589) (xy -1.371 2.61)
				(xy -1.345 2.639) (xy -1.325 2.67) (xy -1.321 2.679) (xy -1.309 2.71) (xy -1.309 3.197) (xy -1.433 3.2)
				(xy -1.433 3.172) (xy -1.434 3.157) (xy -1.435 3.147) (xy -1.436 3.144) (xy -1.44 3.147) (xy -1.449 3.156)
				(xy -1.453 3.161) (xy -1.472 3.178) (xy -1.496 3.19) (xy -1.526 3.198) (xy -1.563 3.202) (xy -1.578 3.203)
				(xy -1.603 3.203) (xy -1.627 3.203) (xy -1.647 3.201) (xy -1.656 3.2) (xy -1.686 3.191) (xy -1.717 3.176)
				(xy -1.746 3.159) (xy -1.765 3.143) (xy -1.79 3.111) (xy -1.807 3.075) (xy -1.816 3.037) (xy -1.817 2.998)
				(xy -1.817 2.997) (xy -1.697 2.997) (xy -1.696 3.02) (xy -1.687 3.042) (xy -1.67 3.06) (xy -1.668 3.062)
				(xy -1.654 3.07) (xy -1.64 3.076) (xy -1.624 3.08) (xy -1.602 3.081) (xy -1.574 3.082) (xy -1.558 3.082)
				(xy -1.529 3.081) (xy -1.508 3.08) (xy -1.494 3.078) (xy -1.483 3.075) (xy -1.474 3.07) (xy -1.458 3.058)
				(xy -1.447 3.041) (xy -1.44 3.017) (xy -1.435 2.985) (xy -1.435 2.977) (xy -1.432 2.931) (xy -1.533 2.931)
				(xy -1.568 2.931) (xy -1.595 2.931) (xy -1.615 2.932) (xy -1.63 2.934) (xy -1.641 2.936) (xy -1.65 2.938)
				(xy -1.655 2.941) (xy -1.676 2.955) (xy -1.69 2.974) (xy -1.697 2.997) (xy -1.817 2.997) (xy -1.811 2.96)
				(xy -1.797 2.924) (xy -1.775 2.892) (xy -1.747 2.864) (xy -1.715 2.845) (xy -1.7 2.838) (xy -1.685 2.833)
				(xy -1.668 2.83) (xy -1.648 2.827) (xy -1.623 2.825) (xy -1.591 2.824) (xy -1.551 2.824) (xy -1.54 2.824)
				(xy -1.432 2.824) (xy -1.434 2.776) (xy -1.436 2.747) (xy -1.441 2.726) (xy -1.448 2.711) (xy -1.46 2.699)
				(xy -1.474 2.689) (xy -1.483 2.685) (xy -1.492 2.682) (xy -1.505 2.68) (xy -1.524 2.68) (xy -1.55 2.679)
				(xy -1.56 2.679) (xy -1.594 2.68) (xy -1.62 2.682) (xy -1.639 2.686) (xy -1.654 2.692) (xy -1.666 2.701)
				(xy -1.675 2.711) (xy -1.686 2.724) (xy -1.735 2.686) (xy -1.754 2.672) (xy -1.769 2.659) (xy -1.78 2.65)
				(xy -1.784 2.646) (xy -1.78 2.64) (xy -1.77 2.629) (xy -1.756 2.616) (xy -1.74 2.604) (xy -1.724 2.592)
				(xy -1.711 2.584) (xy -1.71 2.583) (xy -1.688 2.574) (xy -1.668 2.566) (xy -1.647 2.562) (xy -1.623 2.559)
				(xy -1.593 2.558) (xy -1.565 2.558) (xy -1.521 2.559)
			)
			(stroke
				(width 0.01)
				(type solid)
			)
			(fill yes)
			(layer "F.Cu")
		)
		(fp_poly
			(pts
				(xy 0.035 2.777) (xy 0.047 2.822) (xy 0.059 2.864) (xy 0.069 2.903) (xy 0.078 2.936) (xy 0.086 2.963)
				(xy 0.092 2.984) (xy 0.095 2.996) (xy 0.096 2.999) (xy 0.098 2.999) (xy 0.103 2.991) (xy 0.109 2.975)
				(xy 0.118 2.95) (xy 0.129 2.917) (xy 0.143 2.874) (xy 0.152 2.849) (xy 0.165 2.807) (xy 0.179 2.766)
				(xy 0.192 2.726) (xy 0.204 2.689) (xy 0.214 2.658) (xy 0.221 2.634) (xy 0.224 2.627) (xy 0.244 2.565)
				(xy 0.338 2.565) (xy 0.406 2.774) (xy 0.42 2.819) (xy 0.434 2.861) (xy 0.446 2.899) (xy 0.457 2.932)
				(xy 0.466 2.96) (xy 0.473 2.981) (xy 0.477 2.993) (xy 0.478 2.997) (xy 0.48 2.998) (xy 0.482 2.996)
				(xy 0.485 2.99) (xy 0.49 2.978) (xy 0.495 2.96) (xy 0.502 2.936) (xy 0.511 2.905) (xy 0.523 2.865)
				(xy 0.536 2.817) (xy 0.543 2.789) (xy 0.556 2.744) (xy 0.568 2.701) (xy 0.578 2.663) (xy 0.587 2.629)
				(xy 0.595 2.602) (xy 0.601 2.582) (xy 0.605 2.57) (xy 0.606 2.567) (xy 0.611 2.566) (xy 0.625 2.566)
				(xy 0.645 2.566) (xy 0.669 2.566) (xy 0.673 2.566) (xy 0.739 2.567) (xy 0.656 2.827) (xy 0.64 2.878)
				(xy 0.624 2.928) (xy 0.609 2.976) (xy 0.595 3.02) (xy 0.582 3.06) (xy 0.571 3.094) (xy 0.563 3.121)
				(xy 0.557 3.139) (xy 0.556 3.143) (xy 0.538 3.2) (xy 0.425 3.197) (xy 0.358 2.975) (xy 0.341 2.917)
				(xy 0.327 2.87) (xy 0.315 2.831) (xy 0.305 2.801) (xy 0.297 2.78) (xy 0.292 2.766) (xy 0.289 2.761)
				(xy 0.288 2.761) (xy 0.286 2.768) (xy 0.281 2.783) (xy 0.274 2.806) (xy 0.265 2.836) (xy 0.254 2.871)
				(xy 0.242 2.911) (xy 0.23 2.953) (xy 0.223 2.976) (xy 0.21 3.02) (xy 0.197 3.062) (xy 0.186 3.099)
				(xy 0.177 3.132) (xy 0.169 3.158) (xy 0.163 3.177) (xy 0.16 3.189) (xy 0.159 3.191) (xy 0.157 3.195)
				(xy 0.151 3.198) (xy 0.141 3.199) (xy 0.124 3.2) (xy 0.101 3.2) (xy 0.073 3.199) (xy 0.055 3.198)
				(xy 0.045 3.196) (xy 0.043 3.194) (xy 0.041 3.188) (xy 0.036 3.173) (xy 0.029 3.15) (xy 0.019 3.121)
				(xy 0.008 3.084) (xy -0.006 3.043) (xy -0.02 2.996) (xy -0.036 2.946) (xy -0.053 2.893) (xy -0.057 2.883)
				(xy -0.074 2.83) (xy -0.09 2.779) (xy -0.105 2.732) (xy -0.119 2.689) (xy -0.131 2.652) (xy -0.141 2.621)
				(xy -0.148 2.596) (xy -0.154 2.58) (xy -0.156 2.572) (xy -0.156 2.569) (xy -0.151 2.567) (xy -0.14 2.566)
				(xy -0.123 2.565) (xy -0.096 2.565) (xy -0.091 2.565) (xy -0.023 2.565) (xy 0.035 2.777)
			)
			(stroke
				(width 0.01)
				(type solid)
			)
			(fill yes)
			(layer "F.Cu")
		)
		(fp_poly
			(pts
				(xy -2.065 1.559) (xy -2.024 1.576) (xy -1.986 1.601) (xy -1.973 1.612) (xy -1.957 1.63) (xy -1.943 1.649)
				(xy -1.932 1.668) (xy -1.924 1.69) (xy -1.918 1.716) (xy -1.914 1.747) (xy -1.911 1.785) (xy -1.91 1.831)
				(xy -1.91 1.877) (xy -1.91 1.93) (xy -1.912 1.974) (xy -1.914 2.011) (xy -1.919 2.041) (xy -1.925 2.067)
				(xy -1.934 2.088) (xy -1.945 2.107) (xy -1.959 2.125) (xy -1.972 2.139) (xy -1.993 2.157) (xy -2.018 2.173)
				(xy -2.031 2.18) (xy -2.047 2.188) (xy -2.06 2.192) (xy -2.074 2.195) (xy -2.091 2.196) (xy -2.114 2.197)
				(xy -2.122 2.197) (xy -2.147 2.196) (xy -2.165 2.195) (xy -2.179 2.193) (xy -2.191 2.189) (xy -2.205 2.183)
				(xy -2.21 2.18) (xy -2.231 2.169) (xy -2.251 2.156) (xy -2.265 2.146) (xy -2.286 2.127) (xy -2.286 2.627)
				(xy -2.266 2.608) (xy -2.248 2.595) (xy -2.227 2.582) (xy -2.217 2.577) (xy -2.173 2.562) (xy -2.129 2.556)
				(xy -2.086 2.559) (xy -2.045 2.57) (xy -2.007 2.589) (xy -1.974 2.616) (xy -1.946 2.648) (xy -1.926 2.687)
				(xy -1.919 2.707) (xy -1.917 2.715) (xy -1.915 2.724) (xy -1.914 2.737) (xy -1.913 2.753) (xy -1.912 2.774)
				(xy -1.911 2.8) (xy -1.911 2.833) (xy -1.911 2.874) (xy -1.911 2.923) (xy -1.911 2.967) (xy -1.911 3.2)
				(xy -2.035 3.197) (xy -2.038 2.984) (xy -2.038 2.932) (xy -2.039 2.889) (xy -2.039 2.854) (xy -2.04 2.826)
				(xy -2.041 2.805) (xy -2.042 2.788) (xy -2.043 2.776) (xy -2.045 2.767) (xy -2.046 2.76) (xy -2.049 2.755)
				(xy -2.051 2.75) (xy -2.072 2.721) (xy -2.098 2.701) (xy -2.128 2.688) (xy -2.161 2.683) (xy -2.195 2.687)
				(xy -2.22 2.697) (xy -2.24 2.71) (xy -2.259 2.729) (xy -2.274 2.75) (xy -2.278 2.757) (xy -2.28 2.765)
				(xy -2.281 2.781) (xy -2.283 2.806) (xy -2.284 2.839) (xy -2.285 2.881) (xy -2.286 2.933) (xy -2.286 2.984)
				(xy -2.289 3.197) (xy -2.413 3.2) (xy -2.413 1.877) (xy -2.286 1.877) (xy -2.285 1.926) (xy -2.281 1.966)
				(xy -2.274 1.998) (xy -2.262 2.024) (xy -2.247 2.043) (xy -2.228 2.058) (xy -2.215 2.064) (xy -2.194 2.07)
				(xy -2.168 2.072) (xy -2.141 2.071) (xy -2.117 2.066) (xy -2.106 2.063) (xy -2.079 2.044) (xy -2.058 2.019)
				(xy -2.05 2.001) (xy -2.045 1.984) (xy -2.042 1.959) (xy -2.04 1.929) (xy -2.038 1.895) (xy -2.038 1.861)
				(xy -2.039 1.829) (xy -2.041 1.8) (xy -2.044 1.777) (xy -2.045 1.772) (xy -2.057 1.738) (xy -2.073 1.712)
				(xy -2.094 1.695) (xy -2.122 1.684) (xy -2.156 1.681) (xy -2.159 1.681) (xy -2.192 1.683) (xy -2.22 1.691)
				(xy -2.243 1.705) (xy -2.26 1.725) (xy -2.273 1.753) (xy -2.281 1.788) (xy -2.285 1.832) (xy -2.286 1.877)
				(xy -2.413 1.877) (xy -2.413 1.559) (xy -2.286 1.559) (xy -2.286 1.62) (xy -2.26 1.6) (xy -2.225 1.577)
				(xy -2.19 1.563) (xy -2.154 1.554) (xy -2.109 1.552) (xy -2.065 1.559)
			)
			(stroke
				(width 0.01)
				(type solid)
			)
			(fill yes)
			(layer "F.Cu")
		)
		(fp_poly
			(pts
				(xy 0.063 -3.201) (xy 0.118 -3.201) (xy 0.164 -3.201) (xy 0.202 -3.2) (xy 0.233 -3.2) (xy 0.258 -3.2)
				(xy 0.277 -3.199) (xy 0.292 -3.198) (xy 0.302 -3.197) (xy 0.309 -3.196) (xy 0.314 -3.195) (xy 0.317 -3.193)
				(xy 0.319 -3.192) (xy 0.321 -3.189) (xy 0.324 -3.183) (xy 0.327 -3.174) (xy 0.33 -3.161) (xy 0.334 -3.144)
				(xy 0.339 -3.12) (xy 0.345 -3.091) (xy 0.352 -3.054) (xy 0.361 -3.01) (xy 0.371 -2.958) (xy 0.382 -2.897)
				(xy 0.385 -2.878) (xy 0.395 -2.824) (xy 0.405 -2.772) (xy 0.414 -2.724) (xy 0.423 -2.68) (xy 0.43 -2.642)
				(xy 0.437 -2.61) (xy 0.442 -2.586) (xy 0.446 -2.569) (xy 0.448 -2.562) (xy 0.456 -2.55) (xy 0.464 -2.544)
				(xy 0.476 -2.539) (xy 0.495 -2.53) (xy 0.521 -2.519) (xy 0.552 -2.506) (xy 0.587 -2.492) (xy 0.624 -2.477)
				(xy 0.664 -2.461) (xy 0.704 -2.445) (xy 0.743 -2.43) (xy 0.78 -2.415) (xy 0.814 -2.402) (xy 0.843 -2.391)
				(xy 0.868 -2.382) (xy 0.885 -2.376) (xy 0.895 -2.373) (xy 0.896 -2.373) (xy 0.911 -2.376) (xy 0.931 -2.386)
				(xy 0.948 -2.397) (xy 0.962 -2.406) (xy 0.983 -2.421) (xy 1.011 -2.44) (xy 1.043 -2.462) (xy 1.079 -2.487)
				(xy 1.118 -2.513) (xy 1.158 -2.541) (xy 1.198 -2.568) (xy 1.238 -2.595) (xy 1.275 -2.621) (xy 1.309 -2.644)
				(xy 1.338 -2.665) (xy 1.362 -2.681) (xy 1.377 -2.691) (xy 1.398 -2.705) (xy 1.418 -2.717) (xy 1.433 -2.725)
				(xy 1.442 -2.728) (xy 1.443 -2.728) (xy 1.448 -2.726) (xy 1.456 -2.72) (xy 1.468 -2.71) (xy 1.486 -2.694)
				(xy 1.508 -2.673) (xy 1.535 -2.647) (xy 1.568 -2.614) (xy 1.608 -2.575) (xy 1.654 -2.53) (xy 1.675 -2.509)
				(xy 1.721 -2.462) (xy 1.761 -2.422) (xy 1.794 -2.388) (xy 1.822 -2.36) (xy 1.844 -2.337) (xy 1.862 -2.318)
				(xy 1.875 -2.304) (xy 1.884 -2.293) (xy 1.89 -2.284) (xy 1.893 -2.279) (xy 1.894 -2.275) (xy 1.892 -2.269)
				(xy 1.886 -2.257) (xy 1.875 -2.239) (xy 1.86 -2.215) (xy 1.839 -2.183) (xy 1.814 -2.145) (xy 1.783 -2.1)
				(xy 1.747 -2.046) (xy 1.721 -2.009) (xy 1.69 -1.964) (xy 1.661 -1.921) (xy 1.634 -1.88) (xy 1.609 -1.844)
				(xy 1.588 -1.811) (xy 1.57 -1.785) (xy 1.557 -1.764) (xy 1.549 -1.75) (xy 1.546 -1.743) (xy 1.547 -1.735)
				(xy 1.552 -1.719) (xy 1.56 -1.696) (xy 1.571 -1.667) (xy 1.585 -1.634) (xy 1.6 -1.597) (xy 1.616 -1.557)
				(xy 1.633 -1.516) (xy 1.651 -1.476) (xy 1.668 -1.436) (xy 1.685 -1.398) (xy 1.701 -1.363) (xy 1.715 -1.333)
				(xy 1.727 -1.309) (xy 1.736 -1.291) (xy 1.742 -1.281) (xy 1.744 -1.279) (xy 1.751 -1.277) (xy 1.767 -1.273)
				(xy 1.791 -1.268) (xy 1.822 -1.261) (xy 1.86 -1.254) (xy 1.903 -1.245) (xy 1.951 -1.236) (xy 2.002 -1.226)
				(xy 2.049 -1.217) (xy 2.103 -1.207) (xy 2.154 -1.198) (xy 2.201 -1.188) (xy 2.244 -1.18) (xy 2.281 -1.173)
				(xy 2.311 -1.166) (xy 2.335 -1.161) (xy 2.35 -1.157) (xy 2.355 -1.156) (xy 2.367 -1.148) (xy 2.367 -0.834)
				(xy 2.367 -0.768) (xy 2.367 -0.712) (xy 2.367 -0.664) (xy 2.366 -0.625) (xy 2.366 -0.592) (xy 2.365 -0.566)
				(xy 2.364 -0.546) (xy 2.363 -0.531) (xy 2.361 -0.52) (xy 2.358 -0.512) (xy 2.355 -0.507) (xy 2.352 -0.504)
				(xy 2.348 -0.503) (xy 2.343 -0.501) (xy 2.34 -0.501) (xy 2.333 -0.499) (xy 2.317 -0.496) (xy 2.293 -0.492)
				(xy 2.261 -0.486) (xy 2.224 -0.479) (xy 2.181 -0.471) (xy 2.134 -0.462) (xy 2.084 -0.453) (xy 2.054 -0.448)
				(xy 2.002 -0.438) (xy 1.953 -0.429) (xy 1.907 -0.42) (xy 1.866 -0.412) (xy 1.831 -0.404) (xy 1.802 -0.398)
				(xy 1.78 -0.394) (xy 1.767 -0.391) (xy 1.764 -0.39) (xy 1.76 -0.387) (xy 1.757 -0.384) (xy 1.753 -0.379)
				(xy 1.748 -0.371) (xy 1.742 -0.36) (xy 1.735 -0.344) (xy 1.726 -0.324) (xy 1.715 -0.297) (xy 1.701 -0.264)
				(xy 1.685 -0.223) (xy 1.665 -0.174) (xy 1.653 -0.145) (xy 1.63 -0.086) (xy 1.61 -0.037) (xy 1.594 0.005)
				(xy 1.582 0.038) (xy 1.572 0.064) (xy 1.566 0.084) (xy 1.562 0.097) (xy 1.561 0.104) (xy 1.562 0.105)
				(xy 1.565 0.111) (xy 1.574 0.125) (xy 1.587 0.146) (xy 1.604 0.173) (xy 1.626 0.205) (xy 1.65 0.241)
				(xy 1.677 0.281) (xy 1.706 0.324) (xy 1.729 0.358) (xy 1.768 0.413) (xy 1.8 0.461) (xy 1.827 0.502)
				(xy 1.85 0.535) (xy 1.867 0.562) (xy 1.88 0.583) (xy 1.889 0.598) (xy 1.893 0.608) (xy 1.894 0.612)
				(xy 1.893 0.616) (xy 1.89 0.622) (xy 1.885 0.63) (xy 1.876 0.64) (xy 1.863 0.655) (xy 1.846 0.673)
				(xy 1.825 0.695) (xy 1.798 0.723) (xy 1.765 0.756) (xy 1.727 0.795) (xy 1.682 0.839) (xy 1.635 0.886)
				(xy 1.595 0.926) (xy 1.561 0.96) (xy 1.532 0.989) (xy 1.508 1.012) (xy 1.488 1.03) (xy 1.473 1.044)
				(xy 1.461 1.054) (xy 1.452 1.061) (xy 1.445 1.065) (xy 1.44 1.066) (xy 1.438 1.066) (xy 1.433 1.064)
				(xy 1.421 1.055) (xy 1.401 1.043) (xy 1.376 1.026) (xy 1.345 1.005) (xy 1.31 0.981) (xy 1.27 0.954)
				(xy 1.228 0.925) (xy 1.193 0.901) (xy 1.138 0.864) (xy 1.089 0.83) (xy 1.046 0.802) (xy 1.01 0.778)
				(xy 0.981 0.759) (xy 0.96 0.746) (xy 0.946 0.738) (xy 0.94 0.736) (xy 0.932 0.738) (xy 0.917 0.745)
				(xy 0.895 0.755) (xy 0.869 0.768) (xy 0.84 0.783) (xy 0.816 0.795) (xy 0.781 0.814) (xy 0.753 0.828)
				(xy 0.732 0.838) (xy 0.717 0.845) (xy 0.707 0.849) (xy 0.699 0.85) (xy 0.694 0.849) (xy 0.691 0.847)
				(xy 0.687 0.84) (xy 0.682 0.829) (xy 0.674 0.814) (xy 0.665 0.793) (xy 0.653 0.767) (xy 0.639 0.735)
				(xy 0.623 0.696) (xy 0.604 0.651) (xy 0.582 0.598) (xy 0.556 0.538) (xy 0.528 0.469) (xy 0.496 0.391)
				(xy 0.47 0.329) (xy 0.436 0.247) (xy 0.406 0.173) (xy 0.379 0.108) (xy 0.355 0.05) (xy 0.335 0)
				(xy 0.317 -0.043) (xy 0.303 -0.079) (xy 0.291 -0.11) (xy 0.281 -0.135) (xy 0.273 -0.155) (xy 0.268 -0.171)
				(xy 0.264 -0.183) (xy 0.262 -0.191) (xy 0.262 -0.196) (xy 0.262 -0.198) (xy 0.269 -0.207) (xy 0.283 -0.219)
				(xy 0.302 -0.233) (xy 0.303 -0.234) (xy 0.354 -0.268) (xy 0.398 -0.3) (xy 0.435 -0.331) (xy 0.469 -0.363)
				(xy 0.5 -0.397) (xy 0.507 -0.405) (xy 0.556 -0.472) (xy 0.596 -0.543) (xy 0.627 -0.619) (xy 0.643 -0.672)
				(xy 0.651 -0.718) (xy 0.657 -0.77) (xy 0.66 -0.824) (xy 0.659 -0.878) (xy 0.654 -0.927) (xy 0.652 -0.936)
				(xy 0.634 -1.015) (xy 0.607 -1.09) (xy 0.571 -1.161) (xy 0.528 -1.227) (xy 0.477 -1.287) (xy 0.419 -1.341)
				(xy 0.355 -1.387) (xy 0.285 -1.426) (xy 0.21 -1.456) (xy 0.205 -1.458) (xy 0.131 -1.477) (xy 0.054 -1.487)
				(xy -0.025 -1.489) (xy -0.103 -1.482) (xy -0.178 -1.466) (xy -0.206 -1.458) (xy -0.281 -1.428) (xy -0.351 -1.39)
				(xy -0.416 -1.344) (xy -0.474 -1.29) (xy -0.526 -1.23) (xy -0.571 -1.164) (xy -0.607 -1.093) (xy -0.63 -1.034)
				(xy -0.649 -0.96) (xy -0.659 -0.883) (xy -0.661 -0.804) (xy -0.654 -0.726) (xy -0.638 -0.651) (xy -0.63 -0.623)
				(xy -0.618 -0.591) (xy -0.602 -0.554) (xy -0.584 -0.518) (xy -0.566 -0.485) (xy -0.553 -0.463) (xy -0.509 -0.407)
				(xy -0.457 -0.352) (xy -0.397 -0.299) (xy -0.33 -0.25) (xy -0.289 -0.224) (xy -0.273 -0.212) (xy -0.263 -0.2)
				(xy -0.262 -0.197) (xy -0.263 -0.19) (xy -0.268 -0.175) (xy -0.277 -0.151) (xy -0.288 -0.121) (xy -0.302 -0.084)
				(xy -0.319 -0.042) (xy -0.338 0.005) (xy -0.358 0.056) (xy -0.381 0.111) (xy -0.404 0.168) (xy -0.428 0.228)
				(xy -0.453 0.288) (xy -0.478 0.349) (xy -0.504 0.41) (xy -0.529 0.47) (xy -0.553 0.527) (xy -0.576 0.583)
				(xy -0.598 0.635) (xy -0.619 0.683) (xy -0.638 0.727) (xy -0.655 0.765) (xy -0.669 0.797) (xy -0.68 0.822)
				(xy -0.689 0.839) (xy -0.694 0.848) (xy -0.695 0.849) (xy -0.699 0.85) (xy -0.706 0.849) (xy -0.717 0.845)
				(xy -0.732 0.839) (xy -0.752 0.829) (xy -0.779 0.815) (xy -0.814 0.797) (xy -0.817 0.795) (xy -0.848 0.779)
				(xy -0.877 0.764) (xy -0.902 0.752) (xy -0.922 0.743) (xy -0.936 0.737) (xy -0.941 0.736) (xy -0.949 0.739)
				(xy -0.964 0.748) (xy -0.987 0.761) (xy -1.015 0.78) (xy -1.05 0.803) (xy -1.072 0.818) (xy -1.138 0.863)
				(xy -1.195 0.903) (xy -1.245 0.937) (xy -1.289 0.966) (xy -1.325 0.991) (xy -1.356 1.012) (xy -1.381 1.029)
				(xy -1.401 1.042) (xy -1.416 1.052) (xy -1.427 1.059) (xy -1.435 1.064) (xy -1.439 1.066) (xy -1.44 1.066)
				(xy -1.449 1.064) (xy -1.453 1.061) (xy -1.458 1.057) (xy -1.47 1.046) (xy -1.487 1.029) (xy -1.509 1.007)
				(xy -1.537 0.98) (xy -1.568 0.95) (xy -1.602 0.915) (xy -1.639 0.879) (xy -1.678 0.84) (xy -1.678 0.839)
				(xy -1.726 0.792) (xy -1.767 0.751) (xy -1.801 0.716) (xy -1.829 0.687) (xy -1.852 0.663) (xy -1.869 0.644)
				(xy -1.882 0.63) (xy -1.89 0.62) (xy -1.894 0.613) (xy -1.895 0.61) (xy -1.892 0.603) (xy -1.884 0.588)
				(xy -1.87 0.565) (xy -1.85 0.536) (xy -1.826 0.499) (xy -1.797 0.455) (xy -1.763 0.405) (xy -1.73 0.358)
				(xy -1.7 0.313) (xy -1.671 0.271) (xy -1.645 0.232) (xy -1.621 0.197) (xy -1.601 0.166) (xy -1.584 0.141)
				(xy -1.572 0.121) (xy -1.565 0.109) (xy -1.563 0.105) (xy -1.563 0.099) (xy -1.566 0.087) (xy -1.572 0.07)
				(xy -1.58 0.045) (xy -1.592 0.013) (xy -1.607 -0.026) (xy -1.626 -0.074) (xy -1.648 -0.13) (xy -1.654 -0.145)
				(xy -1.676 -0.199) (xy -1.695 -0.245) (xy -1.71 -0.282) (xy -1.723 -0.313) (xy -1.733 -0.337) (xy -1.741 -0.356)
				(xy -1.748 -0.369) (xy -1.753 -0.379) (xy -1.758 -0.385) (xy -1.761 -0.388) (xy -1.763 -0.389) (xy -1.767 -0.39)
				(xy -1.774 -0.392) (xy -1.784 -0.395) (xy -1.799 -0.398) (xy -1.818 -0.402) (xy -1.843 -0.407) (xy -1.873 -0.413)
				(xy -1.91 -0.42) (xy -1.954 -0.429) (xy -2.005 -0.438) (xy -2.065 -0.449) (xy -2.133 -0.462) (xy -2.211 -0.477)
				(xy -2.22 -0.478) (xy -2.26 -0.486) (xy -2.29 -0.491) (xy -2.313 -0.496) (xy -2.33 -0.499) (xy -2.341 -0.502)
				(xy -2.349 -0.504) (xy -2.353 -0.506) (xy -2.356 -0.508) (xy -2.359 -0.51) (xy -2.36 -0.511) (xy -2.361 -0.514)
				(xy -2.363 -0.518) (xy -2.364 -0.526) (xy -2.365 -0.536) (xy -2.366 -0.551) (xy -2.366 -0.571) (xy -2.367 -0.597)
				(xy -2.367 -0.629) (xy -2.368 -0.668) (xy -2.368 -0.715) (xy -2.368 -0.771) (xy -2.368 -0.834) (xy -2.368 -1.148)
				(xy -2.356 -1.155) (xy -2.349 -1.158) (xy -2.333 -1.162) (xy -2.309 -1.167) (xy -2.278 -1.173) (xy -2.24 -1.181)
				(xy -2.197 -1.189) (xy -2.149 -1.198) (xy -2.098 -1.208) (xy -2.051 -1.217) (xy -1.996 -1.227) (xy -1.945 -1.237)
				(xy -1.897 -1.246) (xy -1.854 -1.254) (xy -1.817 -1.262) (xy -1.787 -1.268) (xy -1.764 -1.273) (xy -1.75 -1.277)
				(xy -1.745 -1.279) (xy -1.741 -1.285) (xy -1.733 -1.3) (xy -1.722 -1.322) (xy -1.709 -1.35) (xy -1.694 -1.382)
				(xy -1.677 -1.419) (xy -1.66 -1.458) (xy -1.642 -1.498) (xy -1.625 -1.539) (xy -1.608 -1.58) (xy -1.592 -1.618)
				(xy -1.578 -1.653) (xy -1.565 -1.684) (xy -1.556 -1.709) (xy -1.549 -1.729) (xy -1.546 -1.74) (xy -1.546 -1.742)
				(xy -1.549 -1.749) (xy -1.558 -1.763) (xy -1.571 -1.784) (xy -1.588 -1.811) (xy -1.61 -1.843) (xy -1.634 -1.88)
				(xy -1.661 -1.92) (xy -1.691 -1.963) (xy -1.722 -2.008) (xy -1.762 -2.067) (xy -1.796 -2.117) (xy -1.825 -2.16)
				(xy -1.848 -2.196) (xy -1.867 -2.225) (xy -1.881 -2.247) (xy -1.89 -2.262) (xy -1.895 -2.272) (xy -1.895 -2.275)
				(xy -1.894 -2.279) (xy -1.891 -2.285) (xy -1.884 -2.293) (xy -1.875 -2.305) (xy -1.861 -2.32) (xy -1.843 -2.339)
				(xy -1.82 -2.363) (xy -1.792 -2.392) (xy -1.758 -2.426) (xy -1.718 -2.466) (xy -1.676 -2.509) (xy -1.627 -2.557)
				(xy -1.585 -2.599) (xy -1.549 -2.634) (xy -1.52 -2.663) (xy -1.495 -2.686) (xy -1.476 -2.704) (xy -1.462 -2.716)
				(xy -1.452 -2.724) (xy -1.446 -2.728) (xy -1.444 -2.728) (xy -1.437 -2.726) (xy -1.423 -2.717) (xy -1.401 -2.703)
				(xy -1.372 -2.685) (xy -1.337 -2.661) (xy -1.295 -2.634) (xy -1.248 -2.602) (xy -1.196 -2.566) (xy -1.173 -2.551)
				(xy -1.118 -2.513) (xy -1.071 -2.481) (xy -1.031 -2.454) (xy -0.998 -2.432) (xy -0.97 -2.413) (xy -0.948 -2.399)
				(xy -0.931 -2.389) (xy -0.917 -2.381) (xy -0.907 -2.376) (xy -0.901 -2.373) (xy -0.897 -2.373) (xy -0.888 -2.375)
				(xy -0.87 -2.38) (xy -0.845 -2.39) (xy -0.813 -2.402) (xy -0.774 -2.417) (xy -0.73 -2.434) (xy -0.681 -2.454)
				(xy -0.629 -2.475) (xy -0.586 -2.493) (xy -0.55 -2.508) (xy -0.522 -2.52) (xy -0.499 -2.529) (xy -0.482 -2.537)
				(xy -0.47 -2.543) (xy -0.461 -2.548) (xy -0.455 -2.551) (xy -0.452 -2.554) (xy -0.449 -2.557) (xy -0.448 -2.56)
				(xy -0.447 -2.566) (xy -0.443 -2.582) (xy -0.438 -2.605) (xy -0.432 -2.637) (xy -0.425 -2.674) (xy -0.417 -2.717)
				(xy -0.407 -2.765) (xy -0.398 -2.817) (xy -0.388 -2.871) (xy -0.387 -2.876) (xy -0.375 -2.94) (xy -0.364 -2.995)
				(xy -0.356 -3.042) (xy -0.348 -3.081) (xy -0.342 -3.112) (xy -0.337 -3.137) (xy -0.332 -3.157) (xy -0.328 -3.171)
				(xy -0.325 -3.181) (xy -0.323 -3.188) (xy -0.32 -3.191) (xy -0.32 -3.192) (xy -0.317 -3.194) (xy -0.313 -3.195)
				(xy -0.307 -3.197) (xy -0.298 -3.198) (xy -0.286 -3.199) (xy -0.269 -3.199) (xy -0.247 -3.2) (xy -0.219 -3.2)
				(xy -0.184 -3.201) (xy -0.142 -3.201) (xy -0.092 -3.201) (xy -0.033 -3.201) (xy -0.001 -3.201) (xy 0.063 -3.201)
			)
			(stroke
				(width 0.01)
				(type solid)
			)
			(fill yes)
			(layer "F.Cu")
		)
		(fp_poly
			(pts
				(xy -0.843 2.558) (xy -0.815 2.564) (xy -0.794 2.572) (xy -0.773 2.581) (xy -0.759 2.589) (xy -0.738 2.603)
				(xy -0.783 2.658) (xy -0.8 2.677) (xy -0.814 2.694) (xy -0.825 2.706) (xy -0.831 2.712) (xy -0.832 2.712)
				(xy -0.837 2.71) (xy -0.847 2.703) (xy -0.849 2.702) (xy -0.874 2.69) (xy -0.904 2.684) (xy -0.935 2.685)
				(xy -0.942 2.686) (xy -0.975 2.698) (xy -1.001 2.717) (xy -1.02 2.741) (xy -1.034 2.766) (xy -1.039 3.197)
				(xy -1.164 3.2) (xy -1.164 2.565) (xy -1.037 2.565) (xy -1.037 2.626) (xy -1.009 2.604) (xy -0.972 2.579)
				(xy -0.931 2.563) (xy -0.887 2.556) (xy -0.843 2.558)
			)
			(stroke
				(width 0.01)
				(type solid)
			)
			(fill yes)
			(layer "F.Mask")
		)
		(fp_poly
			(pts
				(xy 1.889 1.554) (xy 1.907 1.559) (xy 1.927 1.566) (xy 1.948 1.574) (xy 1.966 1.583) (xy 1.979 1.592)
				(xy 1.984 1.597) (xy 1.982 1.604) (xy 1.974 1.616) (xy 1.962 1.633) (xy 1.946 1.652) (xy 1.945 1.654)
				(xy 1.929 1.673) (xy 1.915 1.689) (xy 1.906 1.7) (xy 1.901 1.706) (xy 1.896 1.705) (xy 1.885 1.7)
				(xy 1.873 1.695) (xy 1.84 1.683) (xy 1.808 1.68) (xy 1.776 1.685) (xy 1.747 1.698) (xy 1.723 1.717)
				(xy 1.704 1.742) (xy 1.696 1.763) (xy 1.695 1.772) (xy 1.694 1.79) (xy 1.693 1.817) (xy 1.692 1.85)
				(xy 1.692 1.89) (xy 1.691 1.934) (xy 1.691 1.983) (xy 1.691 2.194) (xy 1.559 2.194) (xy 1.559 1.559)
				(xy 1.691 1.559) (xy 1.691 1.626) (xy 1.71 1.607) (xy 1.739 1.585) (xy 1.775 1.568) (xy 1.814 1.556)
				(xy 1.855 1.552) (xy 1.889 1.554)
			)
			(stroke
				(width 0.01)
				(type solid)
			)
			(fill yes)
			(layer "F.Mask")
		)
		(fp_poly
			(pts
				(xy -0.837 1.56) (xy -0.797 1.576) (xy -0.761 1.6) (xy -0.73 1.63) (xy -0.706 1.667) (xy -0.69 1.709)
				(xy -0.687 1.721) (xy -0.685 1.734) (xy -0.684 1.757) (xy -0.683 1.79) (xy -0.682 1.833) (xy -0.681 1.884)
				(xy -0.681 1.945) (xy -0.681 1.971) (xy -0.681 2.194) (xy -0.808 2.194) (xy -0.809 1.984) (xy -0.811 1.774)
				(xy -0.826 1.744) (xy -0.845 1.716) (xy -0.868 1.697) (xy -0.897 1.686) (xy -0.925 1.682) (xy -0.947 1.682)
				(xy -0.967 1.684) (xy -0.979 1.686) (xy -1.001 1.698) (xy -1.023 1.716) (xy -1.041 1.738) (xy -1.049 1.752)
				(xy -1.052 1.758) (xy -1.054 1.765) (xy -1.056 1.773) (xy -1.057 1.783) (xy -1.058 1.797) (xy -1.059 1.815)
				(xy -1.06 1.839) (xy -1.06 1.869) (xy -1.061 1.907) (xy -1.061 1.953) (xy -1.061 1.985) (xy -1.063 2.194)
				(xy -1.189 2.194) (xy -1.189 1.559) (xy -1.062 1.559) (xy -1.062 1.625) (xy -1.033 1.602) (xy -1.001 1.579)
				(xy -0.969 1.564) (xy -0.934 1.555) (xy -0.927 1.554) (xy -0.881 1.553) (xy -0.837 1.56)
			)
			(stroke
				(width 0.01)
				(type solid)
			)
			(fill yes)
			(layer "F.Mask")
		)
		(fp_poly
			(pts
				(xy 1.042 1.769) (xy 1.043 1.979) (xy 1.059 2.009) (xy 1.077 2.036) (xy 1.1 2.056) (xy 1.129 2.067)
				(xy 1.159 2.071) (xy 1.193 2.07) (xy 1.221 2.063) (xy 1.245 2.047) (xy 1.258 2.034) (xy 1.266 2.025)
				(xy 1.273 2.016) (xy 1.278 2.008) (xy 1.282 1.997) (xy 1.286 1.985) (xy 1.288 1.969) (xy 1.29 1.948)
				(xy 1.291 1.922) (xy 1.292 1.89) (xy 1.293 1.85) (xy 1.293 1.801) (xy 1.294 1.766) (xy 1.295 1.559)
				(xy 1.422 1.559) (xy 1.422 2.194) (xy 1.295 2.194) (xy 1.295 2.161) (xy 1.295 2.144) (xy 1.293 2.132)
				(xy 1.292 2.128) (xy 1.287 2.131) (xy 1.278 2.14) (xy 1.271 2.147) (xy 1.256 2.159) (xy 1.236 2.171)
				(xy 1.219 2.181) (xy 1.202 2.188) (xy 1.186 2.193) (xy 1.17 2.196) (xy 1.148 2.197) (xy 1.135 2.198)
				(xy 1.107 2.198) (xy 1.087 2.197) (xy 1.07 2.194) (xy 1.059 2.19) (xy 1.036 2.181) (xy 1.019 2.172)
				(xy 1.003 2.161) (xy 0.985 2.146) (xy 0.981 2.141) (xy 0.952 2.107) (xy 0.931 2.068) (xy 0.92 2.033)
				(xy 0.918 2.019) (xy 0.917 1.996) (xy 0.916 1.963) (xy 0.915 1.92) (xy 0.914 1.869) (xy 0.914 1.808)
				(xy 0.914 1.782) (xy 0.914 1.559) (xy 1.04 1.559) (xy 1.042 1.769)
			)
			(stroke
				(width 0.01)
				(type solid)
			)
			(fill yes)
			(layer "F.Mask")
		)
		(fp_poly
			(pts
				(xy 1.753 2.563) (xy 1.768 2.568) (xy 1.787 2.577) (xy 1.804 2.586) (xy 1.818 2.595) (xy 1.826 2.602)
				(xy 1.827 2.606) (xy 1.824 2.611) (xy 1.815 2.621) (xy 1.803 2.636) (xy 1.789 2.654) (xy 1.775 2.671)
				(xy 1.761 2.688) (xy 1.749 2.701) (xy 1.742 2.71) (xy 1.739 2.712) (xy 1.735 2.71) (xy 1.724 2.704)
				(xy 1.713 2.698) (xy 1.697 2.69) (xy 1.682 2.686) (xy 1.664 2.685) (xy 1.653 2.685) (xy 1.618 2.688)
				(xy 1.59 2.699) (xy 1.566 2.718) (xy 1.561 2.723) (xy 1.554 2.732) (xy 1.548 2.74) (xy 1.544 2.748)
				(xy 1.54 2.758) (xy 1.537 2.769) (xy 1.534 2.785) (xy 1.533 2.804) (xy 1.532 2.829) (xy 1.531 2.861)
				(xy 1.53 2.899) (xy 1.53 2.947) (xy 1.53 2.988) (xy 1.528 3.2) (xy 1.468 3.2) (xy 1.444 3.2) (xy 1.425 3.199)
				(xy 1.411 3.198) (xy 1.405 3.197) (xy 1.404 3.191) (xy 1.404 3.176) (xy 1.403 3.153) (xy 1.403 3.122)
				(xy 1.402 3.085) (xy 1.402 3.042) (xy 1.402 2.993) (xy 1.402 2.941) (xy 1.402 2.886) (xy 1.402 2.565)
				(xy 1.529 2.565) (xy 1.529 2.595) (xy 1.529 2.611) (xy 1.53 2.623) (xy 1.532 2.626) (xy 1.537 2.623)
				(xy 1.547 2.615) (xy 1.554 2.608) (xy 1.588 2.584) (xy 1.627 2.567) (xy 1.669 2.558) (xy 1.712 2.556)
				(xy 1.753 2.563)
			)
			(stroke
				(width 0.01)
				(type solid)
			)
			(fill yes)
			(layer "F.Mask")
		)
		(fp_poly
			(pts
				(xy 2.316 1.557) (xy 2.365 1.57) (xy 2.41 1.593) (xy 2.453 1.625) (xy 2.46 1.631) (xy 2.491 1.661)
				(xy 2.466 1.684) (xy 2.448 1.699) (xy 2.43 1.715) (xy 2.419 1.725) (xy 2.397 1.743) (xy 2.376 1.724)
				(xy 2.345 1.701) (xy 2.312 1.687) (xy 2.274 1.681) (xy 2.265 1.681) (xy 2.226 1.684) (xy 2.195 1.693)
				(xy 2.167 1.708) (xy 2.159 1.715) (xy 2.136 1.741) (xy 2.118 1.776) (xy 2.107 1.817) (xy 2.103 1.866)
				(xy 2.103 1.876) (xy 2.106 1.926) (xy 2.116 1.97) (xy 2.132 2.006) (xy 2.155 2.034) (xy 2.184 2.055)
				(xy 2.219 2.067) (xy 2.259 2.072) (xy 2.274 2.071) (xy 2.309 2.066) (xy 2.339 2.056) (xy 2.366 2.038)
				(xy 2.377 2.028) (xy 2.386 2.02) (xy 2.393 2.016) (xy 2.4 2.015) (xy 2.409 2.018) (xy 2.42 2.027)
				(xy 2.436 2.041) (xy 2.456 2.059) (xy 2.491 2.092) (xy 2.476 2.108) (xy 2.449 2.132) (xy 2.416 2.155)
				(xy 2.38 2.174) (xy 2.35 2.186) (xy 2.327 2.193) (xy 2.306 2.197) (xy 2.283 2.199) (xy 2.259 2.199)
				(xy 2.233 2.198) (xy 2.209 2.196) (xy 2.189 2.193) (xy 2.182 2.191) (xy 2.133 2.173) (xy 2.089 2.146)
				(xy 2.053 2.112) (xy 2.023 2.071) (xy 2.012 2.051) (xy 2 2.023) (xy 1.991 1.999) (xy 1.984 1.975)
				(xy 1.981 1.948) (xy 1.979 1.917) (xy 1.978 1.879) (xy 1.978 1.877) (xy 1.979 1.838) (xy 1.98 1.806)
				(xy 1.984 1.78) (xy 1.99 1.756) (xy 1.999 1.731) (xy 2.011 1.704) (xy 2.012 1.701) (xy 2.039 1.657)
				(xy 2.072 1.62) (xy 2.111 1.591) (xy 2.156 1.57) (xy 2.207 1.557) (xy 2.263 1.552) (xy 2.316 1.557)
			)
			(stroke
				(width 0.01)
				(type solid)
			)
			(fill yes)
			(layer "F.Mask")
		)
		(fp_poly
			(pts
				(xy -1.494 1.56) (xy -1.447 1.576) (xy -1.405 1.6) (xy -1.368 1.633) (xy -1.341 1.668) (xy -1.326 1.692)
				(xy -1.316 1.716) (xy -1.308 1.743) (xy -1.302 1.774) (xy -1.299 1.811) (xy -1.297 1.845) (xy -1.294 1.925)
				(xy -1.692 1.925) (xy -1.692 1.942) (xy -1.687 1.977) (xy -1.673 2.011) (xy -1.65 2.039) (xy -1.626 2.059)
				(xy -1.601 2.071) (xy -1.572 2.078) (xy -1.537 2.079) (xy -1.497 2.074) (xy -1.458 2.06) (xy -1.422 2.036)
				(xy -1.421 2.036) (xy -1.402 2.021) (xy -1.359 2.057) (xy -1.342 2.072) (xy -1.327 2.085) (xy -1.317 2.094)
				(xy -1.314 2.098) (xy -1.316 2.103) (xy -1.324 2.113) (xy -1.338 2.126) (xy -1.354 2.139) (xy -1.372 2.152)
				(xy -1.389 2.163) (xy -1.399 2.168) (xy -1.421 2.178) (xy -1.445 2.187) (xy -1.461 2.191) (xy -1.488 2.196)
				(xy -1.522 2.199) (xy -1.557 2.199) (xy -1.591 2.196) (xy -1.62 2.192) (xy -1.629 2.19) (xy -1.677 2.171)
				(xy -1.718 2.146) (xy -1.752 2.114) (xy -1.779 2.074) (xy -1.8 2.026) (xy -1.802 2.02) (xy -1.81 1.989)
				(xy -1.815 1.951) (xy -1.818 1.908) (xy -1.819 1.865) (xy -1.818 1.823) (xy -1.816 1.804) (xy -1.692 1.804)
				(xy -1.692 1.818) (xy -1.428 1.818) (xy -1.428 1.801) (xy -1.432 1.775) (xy -1.442 1.748) (xy -1.457 1.722)
				(xy -1.469 1.707) (xy -1.495 1.688) (xy -1.526 1.676) (xy -1.56 1.672) (xy -1.593 1.676) (xy -1.619 1.685)
				(xy -1.646 1.704) (xy -1.668 1.73) (xy -1.683 1.76) (xy -1.691 1.792) (xy -1.692 1.804) (xy -1.816 1.804)
				(xy -1.814 1.786) (xy -1.812 1.777) (xy -1.797 1.724) (xy -1.775 1.676) (xy -1.747 1.636) (xy -1.713 1.603)
				(xy -1.673 1.578) (xy -1.629 1.561) (xy -1.597 1.554) (xy -1.544 1.552) (xy -1.494 1.56)
			)
			(stroke
				(width 0.01)
				(type solid)
			)
			(fill yes)
			(layer "F.Mask")
		)
		(fp_poly
			(pts
				(xy 2.835 1.557) (xy 2.883 1.57) (xy 2.926 1.592) (xy 2.964 1.621) (xy 2.996 1.657) (xy 3.021 1.699)
				(xy 3.038 1.747) (xy 3.04 1.757) (xy 3.043 1.776) (xy 3.045 1.802) (xy 3.047 1.832) (xy 3.047 1.858)
				(xy 3.047 1.925) (xy 2.65 1.925) (xy 2.653 1.951) (xy 2.663 1.991) (xy 2.68 2.024) (xy 2.703 2.049)
				(xy 2.733 2.067) (xy 2.77 2.077) (xy 2.801 2.079) (xy 2.845 2.075) (xy 2.883 2.063) (xy 2.916 2.042)
				(xy 2.92 2.039) (xy 2.929 2.031) (xy 2.935 2.026) (xy 2.941 2.025) (xy 2.949 2.027) (xy 2.959 2.034)
				(xy 2.974 2.047) (xy 2.994 2.064) (xy 3.01 2.078) (xy 3.023 2.088) (xy 3.03 2.095) (xy 3.032 2.096)
				(xy 3.03 2.1) (xy 3.022 2.11) (xy 3.01 2.122) (xy 3.009 2.123) (xy 2.98 2.147) (xy 2.945 2.169)
				(xy 2.906 2.185) (xy 2.887 2.191) (xy 2.861 2.196) (xy 2.828 2.198) (xy 2.793 2.198) (xy 2.759 2.197)
				(xy 2.729 2.193) (xy 2.721 2.191) (xy 2.675 2.175) (xy 2.634 2.15) (xy 2.599 2.118) (xy 2.569 2.077)
				(xy 2.547 2.029) (xy 2.536 1.996) (xy 2.532 1.973) (xy 2.529 1.942) (xy 2.527 1.906) (xy 2.527 1.869)
				(xy 2.528 1.832) (xy 2.529 1.818) (xy 2.65 1.818) (xy 2.922 1.818) (xy 2.918 1.799) (xy 2.908 1.758)
				(xy 2.891 1.725) (xy 2.869 1.7) (xy 2.84 1.683) (xy 2.826 1.678) (xy 2.788 1.672) (xy 2.753 1.675)
				(xy 2.722 1.687) (xy 2.695 1.706) (xy 2.674 1.734) (xy 2.659 1.768) (xy 2.654 1.794) (xy 2.65 1.818)
				(xy 2.529 1.818) (xy 2.53 1.798) (xy 2.534 1.769) (xy 2.536 1.76) (xy 2.554 1.707) (xy 2.578 1.662)
				(xy 2.609 1.624) (xy 2.645 1.593) (xy 2.687 1.571) (xy 2.734 1.557) (xy 2.783 1.553) (xy 2.835 1.557)
			)
			(stroke
				(width 0.01)
				(type solid)
			)
			(fill yes)
			(layer "F.Mask")
		)
		(fp_poly
			(pts
				(xy -2.733 1.557) (xy -2.685 1.57) (xy -2.642 1.592) (xy -2.604 1.622) (xy -2.581 1.649) (xy -2.562 1.676)
				(xy -2.548 1.706) (xy -2.537 1.739) (xy -2.53 1.777) (xy -2.527 1.821) (xy -2.526 1.873) (xy -2.527 1.907)
				(xy -2.529 1.956) (xy -2.534 1.997) (xy -2.542 2.031) (xy -2.553 2.06) (xy -2.567 2.086) (xy -2.587 2.111)
				(xy -2.603 2.129) (xy -2.637 2.158) (xy -2.673 2.178) (xy -2.714 2.192) (xy -2.76 2.198) (xy -2.789 2.199)
				(xy -2.813 2.198) (xy -2.835 2.196) (xy -2.852 2.194) (xy -2.857 2.194) (xy -2.898 2.179) (xy -2.937 2.155)
				(xy -2.97 2.126) (xy -2.993 2.101) (xy -3.011 2.077) (xy -3.024 2.051) (xy -3.034 2.022) (xy -3.041 1.988)
				(xy -3.045 1.947) (xy -3.047 1.91) (xy -3.047 1.882) (xy -2.919 1.882) (xy -2.919 1.968) (xy -2.903 2.001)
				(xy -2.885 2.031) (xy -2.863 2.051) (xy -2.837 2.064) (xy -2.804 2.07) (xy -2.779 2.07) (xy -2.755 2.069)
				(xy -2.737 2.065) (xy -2.722 2.058) (xy -2.717 2.055) (xy -2.697 2.041) (xy -2.681 2.025) (xy -2.67 2.004)
				(xy -2.662 1.978) (xy -2.657 1.945) (xy -2.654 1.903) (xy -2.654 1.899) (xy -2.653 1.848) (xy -2.656 1.806)
				(xy -2.662 1.772) (xy -2.673 1.744) (xy -2.687 1.722) (xy -2.707 1.705) (xy -2.723 1.695) (xy -2.755 1.684)
				(xy -2.788 1.68) (xy -2.821 1.684) (xy -2.851 1.695) (xy -2.877 1.713) (xy -2.892 1.729) (xy -2.901 1.745)
				(xy -2.908 1.76) (xy -2.913 1.778) (xy -2.916 1.8) (xy -2.918 1.828) (xy -2.919 1.864) (xy -2.919 1.882)
				(xy -3.047 1.882) (xy -3.048 1.844) (xy -3.043 1.786) (xy -3.034 1.736) (xy -3.021 1.695) (xy -3.004 1.664)
				(xy -2.972 1.624) (xy -2.935 1.594) (xy -2.893 1.571) (xy -2.846 1.558) (xy -2.794 1.553) (xy -2.787 1.553)
				(xy -2.733 1.557)
			)
			(stroke
				(width 0.01)
				(type solid)
			)
			(fill yes)
			(layer "F.Mask")
		)
		(fp_poly
			(pts
				(xy 2.148 2.561) (xy 2.193 2.574) (xy 2.235 2.595) (xy 2.273 2.623) (xy 2.304 2.657) (xy 2.326 2.691)
				(xy 2.338 2.718) (xy 2.346 2.745) (xy 2.352 2.774) (xy 2.355 2.808) (xy 2.357 2.85) (xy 2.357 2.858)
				(xy 2.357 2.931) (xy 1.96 2.931) (xy 1.963 2.955) (xy 1.973 2.993) (xy 1.991 3.026) (xy 2.015 3.053)
				(xy 2.039 3.069) (xy 2.057 3.076) (xy 2.08 3.08) (xy 2.103 3.082) (xy 2.144 3.081) (xy 2.18 3.071)
				(xy 2.214 3.054) (xy 2.227 3.045) (xy 2.24 3.035) (xy 2.25 3.029) (xy 2.253 3.027) (xy 2.258 3.03)
				(xy 2.269 3.039) (xy 2.284 3.05) (xy 2.3 3.064) (xy 2.315 3.078) (xy 2.329 3.09) (xy 2.338 3.099)
				(xy 2.341 3.103) (xy 2.337 3.11) (xy 2.327 3.121) (xy 2.312 3.134) (xy 2.294 3.148) (xy 2.276 3.161)
				(xy 2.259 3.171) (xy 2.252 3.175) (xy 2.204 3.192) (xy 2.152 3.202) (xy 2.098 3.204) (xy 2.046 3.198)
				(xy 2.032 3.195) (xy 1.984 3.178) (xy 1.943 3.154) (xy 1.909 3.123) (xy 1.881 3.084) (xy 1.859 3.037)
				(xy 1.847 3.003) (xy 1.841 2.972) (xy 1.838 2.934) (xy 1.836 2.893) (xy 1.837 2.851) (xy 1.839 2.824)
				(xy 1.96 2.824) (xy 2.23 2.824) (xy 2.23 2.813) (xy 2.225 2.783) (xy 2.214 2.753) (xy 2.196 2.725)
				(xy 2.175 2.702) (xy 2.151 2.686) (xy 2.128 2.68) (xy 2.101 2.677) (xy 2.072 2.678) (xy 2.051 2.683)
				(xy 2.023 2.696) (xy 2 2.717) (xy 1.981 2.746) (xy 1.968 2.779) (xy 1.963 2.8) (xy 1.96 2.824) (xy 1.839 2.824)
				(xy 1.839 2.811) (xy 1.844 2.776) (xy 1.848 2.76) (xy 1.866 2.708) (xy 1.889 2.663) (xy 1.919 2.627)
				(xy 1.954 2.598) (xy 1.996 2.575) (xy 2.007 2.571) (xy 2.054 2.559) (xy 2.101 2.556) (xy 2.148 2.561)
			)
			(stroke
				(width 0.01)
				(type solid)
			)
			(fill yes)
			(layer "F.Mask")
		)
		(fp_poly
			(pts
				(xy -0.229 3.2) (xy -0.354 3.197) (xy -0.355 3.165) (xy -0.357 3.133) (xy -0.374 3.148) (xy -0.411 3.175)
				(xy -0.453 3.193) (xy -0.497 3.203) (xy -0.542 3.204) (xy -0.585 3.195) (xy -0.586 3.195) (xy -0.621 3.181)
				(xy -0.651 3.16) (xy -0.673 3.141) (xy -0.689 3.123) (xy -0.702 3.106) (xy -0.712 3.086) (xy -0.72 3.064)
				(xy -0.726 3.038) (xy -0.73 3.007) (xy -0.732 2.968) (xy -0.733 2.922) (xy -0.733 2.88) (xy -0.602 2.88)
				(xy -0.602 2.915) (xy -0.602 2.942) (xy -0.601 2.962) (xy -0.6 2.977) (xy -0.598 2.988) (xy -0.596 2.998)
				(xy -0.592 3.007) (xy -0.591 3.01) (xy -0.574 3.039) (xy -0.552 3.059) (xy -0.525 3.071) (xy -0.492 3.076)
				(xy -0.472 3.076) (xy -0.442 3.072) (xy -0.418 3.063) (xy -0.398 3.048) (xy -0.382 3.029) (xy -0.371 3.004)
				(xy -0.363 2.972) (xy -0.358 2.933) (xy -0.356 2.885) (xy -0.356 2.88) (xy -0.358 2.828) (xy -0.363 2.785)
				(xy -0.373 2.75) (xy -0.387 2.724) (xy -0.406 2.704) (xy -0.43 2.692) (xy -0.46 2.686) (xy -0.483 2.685)
				(xy -0.517 2.687) (xy -0.544 2.696) (xy -0.565 2.711) (xy -0.583 2.734) (xy -0.591 2.751) (xy -0.595 2.76)
				(xy -0.598 2.769) (xy -0.6 2.779) (xy -0.601 2.793) (xy -0.602 2.811) (xy -0.602 2.836) (xy -0.602 2.869)
				(xy -0.602 2.88) (xy -0.733 2.88) (xy -0.733 2.827) (xy -0.732 2.783) (xy -0.729 2.746) (xy -0.725 2.716)
				(xy -0.719 2.691) (xy -0.71 2.67) (xy -0.699 2.651) (xy -0.685 2.633) (xy -0.668 2.616) (xy -0.668 2.615)
				(xy -0.632 2.587) (xy -0.592 2.567) (xy -0.55 2.557) (xy -0.506 2.556) (xy -0.463 2.564) (xy -0.421 2.582)
				(xy -0.411 2.587) (xy -0.394 2.598) (xy -0.377 2.61) (xy -0.373 2.614) (xy -0.356 2.627) (xy -0.356 2.306)
				(xy -0.229 2.306) (xy -0.229 3.2)
			)
			(stroke
				(width 0.01)
				(type solid)
			)
			(fill yes)
			(layer "F.Mask")
		)
		(fp_poly
			(pts
				(xy 0.605 1.558) (xy 0.651 1.574) (xy 0.694 1.598) (xy 0.728 1.627) (xy 0.75 1.652) (xy 0.768 1.678)
				(xy 0.781 1.707) (xy 0.791 1.739) (xy 0.797 1.777) (xy 0.801 1.822) (xy 0.802 1.876) (xy 0.802 1.877)
				(xy 0.801 1.929) (xy 0.798 1.973) (xy 0.792 2.009) (xy 0.784 2.04) (xy 0.774 2.062) (xy 0.748 2.103)
				(xy 0.715 2.139) (xy 0.675 2.167) (xy 0.632 2.187) (xy 0.626 2.189) (xy 0.599 2.195) (xy 0.567 2.198)
				(xy 0.532 2.199) (xy 0.499 2.197) (xy 0.471 2.193) (xy 0.466 2.192) (xy 0.428 2.177) (xy 0.391 2.155)
				(xy 0.359 2.129) (xy 0.354 2.123) (xy 0.332 2.098) (xy 0.316 2.073) (xy 0.303 2.047) (xy 0.294 2.017)
				(xy 0.287 1.983) (xy 0.284 1.943) (xy 0.282 1.894) (xy 0.282 1.877) (xy 0.409 1.877) (xy 0.41 1.918)
				(xy 0.412 1.95) (xy 0.416 1.976) (xy 0.423 1.997) (xy 0.432 2.015) (xy 0.445 2.03) (xy 0.451 2.037)
				(xy 0.471 2.054) (xy 0.491 2.064) (xy 0.514 2.07) (xy 0.543 2.072) (xy 0.569 2.07) (xy 0.59 2.065)
				(xy 0.601 2.06) (xy 0.625 2.047) (xy 0.642 2.031) (xy 0.656 2.009) (xy 0.661 1.998) (xy 0.665 1.989)
				(xy 0.668 1.98) (xy 0.67 1.969) (xy 0.671 1.954) (xy 0.672 1.935) (xy 0.673 1.909) (xy 0.673 1.877)
				(xy 0.673 1.842) (xy 0.672 1.817) (xy 0.671 1.798) (xy 0.67 1.784) (xy 0.668 1.773) (xy 0.665 1.764)
				(xy 0.661 1.755) (xy 0.647 1.73) (xy 0.632 1.712) (xy 0.612 1.698) (xy 0.601 1.693) (xy 0.569 1.683)
				(xy 0.535 1.681) (xy 0.501 1.686) (xy 0.471 1.7) (xy 0.447 1.719) (xy 0.434 1.736) (xy 0.424 1.753)
				(xy 0.417 1.774) (xy 0.412 1.8) (xy 0.41 1.833) (xy 0.409 1.873) (xy 0.409 1.877) (xy 0.282 1.877)
				(xy 0.283 1.824) (xy 0.286 1.78) (xy 0.292 1.742) (xy 0.301 1.711) (xy 0.313 1.683) (xy 0.33 1.657)
				(xy 0.35 1.633) (xy 0.351 1.632) (xy 0.385 1.601) (xy 0.42 1.578) (xy 0.46 1.563) (xy 0.505 1.554)
				(xy 0.555 1.551) (xy 0.605 1.558)
			)
			(stroke
				(width 0.01)
				(type solid)
			)
			(fill yes)
			(layer "F.Mask")
		)
		(fp_poly
			(pts
				(xy 0.004 1.556) (xy 0.054 1.566) (xy 0.102 1.582) (xy 0.146 1.605) (xy 0.154 1.61) (xy 0.193 1.636)
				(xy 0.178 1.655) (xy 0.166 1.668) (xy 0.152 1.686) (xy 0.138 1.7) (xy 0.114 1.727) (xy 0.07 1.705)
				(xy 0.032 1.688) (xy -0.007 1.677) (xy -0.044 1.672) (xy -0.079 1.672) (xy -0.11 1.678) (xy -0.136 1.69)
				(xy -0.154 1.707) (xy -0.162 1.724) (xy -0.164 1.745) (xy -0.164 1.761) (xy -0.159 1.772) (xy -0.15 1.782)
				(xy -0.149 1.783) (xy -0.139 1.791) (xy -0.128 1.797) (xy -0.114 1.802) (xy -0.095 1.805) (xy -0.07 1.808)
				(xy -0.037 1.811) (xy -0.02 1.813) (xy 0.027 1.817) (xy 0.065 1.823) (xy 0.096 1.832) (xy 0.122 1.842)
				(xy 0.14 1.854) (xy 0.166 1.879) (xy 0.186 1.91) (xy 0.2 1.947) (xy 0.206 1.987) (xy 0.206 2.018)
				(xy 0.198 2.06) (xy 0.181 2.097) (xy 0.155 2.129) (xy 0.122 2.156) (xy 0.08 2.177) (xy 0.042 2.189)
				(xy 0.005 2.196) (xy -0.038 2.199) (xy -0.083 2.198) (xy -0.125 2.194) (xy -0.153 2.189) (xy -0.177 2.181)
				(xy -0.204 2.171) (xy -0.229 2.16) (xy -0.232 2.159) (xy -0.251 2.148) (xy -0.272 2.136) (xy -0.292 2.122)
				(xy -0.309 2.109) (xy -0.323 2.098) (xy -0.33 2.09) (xy -0.331 2.088) (xy -0.327 2.084) (xy -0.318 2.073)
				(xy -0.304 2.059) (xy -0.288 2.043) (xy -0.246 2) (xy -0.221 2.021) (xy -0.184 2.047) (xy -0.145 2.065)
				(xy -0.102 2.075) (xy -0.053 2.079) (xy -0.049 2.079) (xy -0.023 2.079) (xy -0.004 2.078) (xy 0.011 2.074)
				(xy 0.025 2.069) (xy 0.029 2.068) (xy 0.054 2.052) (xy 0.071 2.033) (xy 0.079 2.01) (xy 0.078 1.986)
				(xy 0.074 1.975) (xy 0.068 1.964) (xy 0.06 1.956) (xy 0.048 1.949) (xy 0.031 1.944) (xy 0.007 1.939)
				(xy -0.024 1.935) (xy -0.052 1.932) (xy -0.089 1.929) (xy -0.119 1.925) (xy -0.142 1.921) (xy -0.16 1.917)
				(xy -0.176 1.912) (xy -0.192 1.906) (xy -0.201 1.901) (xy -0.235 1.879) (xy -0.262 1.85) (xy -0.28 1.816)
				(xy -0.29 1.776) (xy -0.292 1.75) (xy -0.291 1.727) (xy -0.289 1.705) (xy -0.286 1.689) (xy -0.286 1.688)
				(xy -0.273 1.659) (xy -0.253 1.63) (xy -0.229 1.604) (xy -0.221 1.599) (xy -0.185 1.577) (xy -0.143 1.562)
				(xy -0.096 1.554) (xy -0.047 1.552) (xy 0.004 1.556)
			)
			(stroke
				(width 0.01)
				(type solid)
			)
			(fill yes)
			(layer "F.Mask")
		)
		(fp_poly
			(pts
				(xy 1.038 2.556) (xy 1.091 2.563) (xy 1.137 2.576) (xy 1.177 2.595) (xy 1.209 2.62) (xy 1.234 2.65)
				(xy 1.242 2.665) (xy 1.247 2.677) (xy 1.251 2.691) (xy 1.255 2.708) (xy 1.258 2.727) (xy 1.26 2.751)
				(xy 1.262 2.78) (xy 1.263 2.815) (xy 1.263 2.858) (xy 1.264 2.908) (xy 1.263 2.967) (xy 1.263 2.989)
				(xy 1.262 3.197) (xy 1.135 3.197) (xy 1.133 3.171) (xy 1.132 3.144) (xy 1.119 3.159) (xy 1.096 3.179)
				(xy 1.065 3.193) (xy 1.026 3.202) (xy 0.98 3.204) (xy 0.976 3.204) (xy 0.955 3.204) (xy 0.937 3.203)
				(xy 0.925 3.202) (xy 0.924 3.201) (xy 0.879 3.189) (xy 0.839 3.17) (xy 0.806 3.144) (xy 0.781 3.113)
				(xy 0.763 3.077) (xy 0.753 3.037) (xy 0.753 3.005) (xy 0.873 3.005) (xy 0.874 3.023) (xy 0.878 3.035)
				(xy 0.887 3.047) (xy 0.89 3.05) (xy 0.903 3.063) (xy 0.917 3.072) (xy 0.935 3.078) (xy 0.957 3.081)
				(xy 0.986 3.082) (xy 1.013 3.082) (xy 1.043 3.081) (xy 1.065 3.079) (xy 1.08 3.077) (xy 1.091 3.073)
				(xy 1.096 3.071) (xy 1.112 3.058) (xy 1.123 3.039) (xy 1.13 3.012) (xy 1.132 2.977) (xy 1.132 2.975)
				(xy 1.132 2.931) (xy 1.035 2.931) (xy 0.999 2.931) (xy 0.973 2.931) (xy 0.953 2.932) (xy 0.939 2.934)
				(xy 0.928 2.936) (xy 0.919 2.939) (xy 0.916 2.94) (xy 0.893 2.954) (xy 0.88 2.971) (xy 0.874 2.994)
				(xy 0.873 3.005) (xy 0.753 3.005) (xy 0.753 2.994) (xy 0.761 2.951) (xy 0.768 2.931) (xy 0.776 2.915)
				(xy 0.786 2.901) (xy 0.802 2.884) (xy 0.804 2.882) (xy 0.82 2.867) (xy 0.835 2.854) (xy 0.85 2.845)
				(xy 0.867 2.838) (xy 0.887 2.833) (xy 0.912 2.829) (xy 0.943 2.827) (xy 0.982 2.826) (xy 1.015 2.825)
				(xy 1.133 2.823) (xy 1.132 2.771) (xy 1.131 2.746) (xy 1.129 2.73) (xy 1.127 2.719) (xy 1.123 2.711)
				(xy 1.117 2.705) (xy 1.098 2.691) (xy 1.07 2.682) (xy 1.032 2.677) (xy 1.006 2.677) (xy 0.972 2.678)
				(xy 0.945 2.682) (xy 0.924 2.688) (xy 0.907 2.699) (xy 0.9 2.706) (xy 0.882 2.723) (xy 0.834 2.686)
				(xy 0.816 2.672) (xy 0.801 2.66) (xy 0.79 2.652) (xy 0.787 2.648) (xy 0.791 2.639) (xy 0.801 2.626)
				(xy 0.816 2.612) (xy 0.832 2.6) (xy 0.864 2.581) (xy 0.902 2.568) (xy 0.946 2.559) (xy 0.98 2.556)
				(xy 1.038 2.556)
			)
			(stroke
				(width 0.01)
				(type solid)
			)
			(fill yes)
			(layer "F.Mask")
		)
		(fp_poly
			(pts
				(xy -1.521 2.559) (xy -1.485 2.562) (xy -1.454 2.568) (xy -1.427 2.577) (xy -1.401 2.589) (xy -1.371 2.61)
				(xy -1.345 2.639) (xy -1.325 2.67) (xy -1.321 2.679) (xy -1.309 2.71) (xy -1.309 3.197) (xy -1.433 3.2)
				(xy -1.433 3.172) (xy -1.434 3.157) (xy -1.435 3.147) (xy -1.436 3.144) (xy -1.44 3.147) (xy -1.449 3.156)
				(xy -1.453 3.161) (xy -1.472 3.178) (xy -1.496 3.19) (xy -1.526 3.198) (xy -1.563 3.202) (xy -1.578 3.203)
				(xy -1.603 3.203) (xy -1.627 3.203) (xy -1.647 3.201) (xy -1.656 3.2) (xy -1.686 3.191) (xy -1.717 3.176)
				(xy -1.746 3.159) (xy -1.765 3.143) (xy -1.79 3.111) (xy -1.807 3.075) (xy -1.816 3.037) (xy -1.817 2.998)
				(xy -1.817 2.997) (xy -1.697 2.997) (xy -1.696 3.02) (xy -1.687 3.042) (xy -1.67 3.06) (xy -1.668 3.062)
				(xy -1.654 3.07) (xy -1.64 3.076) (xy -1.624 3.08) (xy -1.602 3.081) (xy -1.574 3.082) (xy -1.558 3.082)
				(xy -1.529 3.081) (xy -1.508 3.08) (xy -1.494 3.078) (xy -1.483 3.075) (xy -1.474 3.07) (xy -1.458 3.058)
				(xy -1.447 3.041) (xy -1.44 3.017) (xy -1.435 2.985) (xy -1.435 2.977) (xy -1.432 2.931) (xy -1.533 2.931)
				(xy -1.568 2.931) (xy -1.595 2.931) (xy -1.615 2.932) (xy -1.63 2.934) (xy -1.641 2.936) (xy -1.65 2.938)
				(xy -1.655 2.941) (xy -1.676 2.955) (xy -1.69 2.974) (xy -1.697 2.997) (xy -1.817 2.997) (xy -1.811 2.96)
				(xy -1.797 2.924) (xy -1.775 2.892) (xy -1.747 2.864) (xy -1.715 2.845) (xy -1.7 2.838) (xy -1.685 2.833)
				(xy -1.668 2.83) (xy -1.648 2.827) (xy -1.623 2.825) (xy -1.591 2.824) (xy -1.551 2.824) (xy -1.54 2.824)
				(xy -1.432 2.824) (xy -1.434 2.776) (xy -1.436 2.747) (xy -1.441 2.726) (xy -1.448 2.711) (xy -1.46 2.699)
				(xy -1.474 2.689) (xy -1.483 2.685) (xy -1.492 2.682) (xy -1.505 2.68) (xy -1.524 2.68) (xy -1.55 2.679)
				(xy -1.56 2.679) (xy -1.594 2.68) (xy -1.62 2.682) (xy -1.639 2.686) (xy -1.654 2.692) (xy -1.666 2.701)
				(xy -1.675 2.711) (xy -1.686 2.724) (xy -1.735 2.686) (xy -1.754 2.672) (xy -1.769 2.659) (xy -1.78 2.65)
				(xy -1.784 2.646) (xy -1.78 2.64) (xy -1.77 2.629) (xy -1.756 2.616) (xy -1.74 2.604) (xy -1.724 2.592)
				(xy -1.711 2.584) (xy -1.71 2.583) (xy -1.688 2.574) (xy -1.668 2.566) (xy -1.647 2.562) (xy -1.623 2.559)
				(xy -1.593 2.558) (xy -1.565 2.558) (xy -1.521 2.559)
			)
			(stroke
				(width 0.01)
				(type solid)
			)
			(fill yes)
			(layer "F.Mask")
		)
		(fp_poly
			(pts
				(xy 0.035 2.777) (xy 0.047 2.822) (xy 0.059 2.864) (xy 0.069 2.903) (xy 0.078 2.936) (xy 0.086 2.963)
				(xy 0.092 2.984) (xy 0.095 2.996) (xy 0.096 2.999) (xy 0.098 2.999) (xy 0.103 2.991) (xy 0.109 2.975)
				(xy 0.118 2.95) (xy 0.129 2.917) (xy 0.143 2.874) (xy 0.152 2.849) (xy 0.165 2.807) (xy 0.179 2.766)
				(xy 0.192 2.726) (xy 0.204 2.689) (xy 0.214 2.658) (xy 0.221 2.634) (xy 0.224 2.627) (xy 0.244 2.565)
				(xy 0.338 2.565) (xy 0.406 2.774) (xy 0.42 2.819) (xy 0.434 2.861) (xy 0.446 2.899) (xy 0.457 2.932)
				(xy 0.466 2.96) (xy 0.473 2.981) (xy 0.477 2.993) (xy 0.478 2.997) (xy 0.48 2.998) (xy 0.482 2.996)
				(xy 0.485 2.99) (xy 0.49 2.978) (xy 0.495 2.96) (xy 0.502 2.936) (xy 0.511 2.905) (xy 0.523 2.865)
				(xy 0.536 2.817) (xy 0.543 2.789) (xy 0.556 2.744) (xy 0.568 2.701) (xy 0.578 2.663) (xy 0.587 2.629)
				(xy 0.595 2.602) (xy 0.601 2.582) (xy 0.605 2.57) (xy 0.606 2.567) (xy 0.611 2.566) (xy 0.625 2.566)
				(xy 0.645 2.566) (xy 0.669 2.566) (xy 0.673 2.566) (xy 0.739 2.567) (xy 0.656 2.827) (xy 0.64 2.878)
				(xy 0.624 2.928) (xy 0.609 2.976) (xy 0.595 3.02) (xy 0.582 3.06) (xy 0.571 3.094) (xy 0.563 3.121)
				(xy 0.557 3.139) (xy 0.556 3.143) (xy 0.538 3.2) (xy 0.425 3.197) (xy 0.358 2.975) (xy 0.341 2.917)
				(xy 0.327 2.87) (xy 0.315 2.831) (xy 0.305 2.801) (xy 0.297 2.78) (xy 0.292 2.766) (xy 0.289 2.761)
				(xy 0.288 2.761) (xy 0.286 2.768) (xy 0.281 2.783) (xy 0.274 2.806) (xy 0.265 2.836) (xy 0.254 2.871)
				(xy 0.242 2.911) (xy 0.23 2.953) (xy 0.223 2.976) (xy 0.21 3.02) (xy 0.197 3.062) (xy 0.186 3.099)
				(xy 0.177 3.132) (xy 0.169 3.158) (xy 0.163 3.177) (xy 0.16 3.189) (xy 0.159 3.191) (xy 0.157 3.195)
				(xy 0.151 3.198) (xy 0.141 3.199) (xy 0.124 3.2) (xy 0.101 3.2) (xy 0.073 3.199) (xy 0.055 3.198)
				(xy 0.045 3.196) (xy 0.043 3.194) (xy 0.041 3.188) (xy 0.036 3.173) (xy 0.029 3.15) (xy 0.019 3.121)
				(xy 0.008 3.084) (xy -0.006 3.043) (xy -0.02 2.996) (xy -0.036 2.946) (xy -0.053 2.893) (xy -0.057 2.883)
				(xy -0.074 2.83) (xy -0.09 2.779) (xy -0.105 2.732) (xy -0.119 2.689) (xy -0.131 2.652) (xy -0.141 2.621)
				(xy -0.148 2.596) (xy -0.154 2.58) (xy -0.156 2.572) (xy -0.156 2.569) (xy -0.151 2.567) (xy -0.14 2.566)
				(xy -0.123 2.565) (xy -0.096 2.565) (xy -0.091 2.565) (xy -0.023 2.565) (xy 0.035 2.777)
			)
			(stroke
				(width 0.01)
				(type solid)
			)
			(fill yes)
			(layer "F.Mask")
		)
		(fp_poly
			(pts
				(xy -2.065 1.559) (xy -2.024 1.576) (xy -1.986 1.601) (xy -1.973 1.612) (xy -1.957 1.63) (xy -1.943 1.649)
				(xy -1.932 1.668) (xy -1.924 1.69) (xy -1.918 1.716) (xy -1.914 1.747) (xy -1.911 1.785) (xy -1.91 1.831)
				(xy -1.91 1.877) (xy -1.91 1.93) (xy -1.912 1.974) (xy -1.914 2.011) (xy -1.919 2.041) (xy -1.925 2.067)
				(xy -1.934 2.088) (xy -1.945 2.107) (xy -1.959 2.125) (xy -1.972 2.139) (xy -1.993 2.157) (xy -2.018 2.173)
				(xy -2.031 2.18) (xy -2.047 2.188) (xy -2.06 2.192) (xy -2.074 2.195) (xy -2.091 2.196) (xy -2.114 2.197)
				(xy -2.122 2.197) (xy -2.147 2.196) (xy -2.165 2.195) (xy -2.179 2.193) (xy -2.191 2.189) (xy -2.205 2.183)
				(xy -2.21 2.18) (xy -2.231 2.169) (xy -2.251 2.156) (xy -2.265 2.146) (xy -2.286 2.127) (xy -2.286 2.627)
				(xy -2.266 2.608) (xy -2.248 2.595) (xy -2.227 2.582) (xy -2.217 2.577) (xy -2.173 2.562) (xy -2.129 2.556)
				(xy -2.086 2.559) (xy -2.045 2.57) (xy -2.007 2.589) (xy -1.974 2.616) (xy -1.946 2.648) (xy -1.926 2.687)
				(xy -1.919 2.707) (xy -1.917 2.715) (xy -1.915 2.724) (xy -1.914 2.737) (xy -1.913 2.753) (xy -1.912 2.774)
				(xy -1.911 2.8) (xy -1.911 2.833) (xy -1.911 2.874) (xy -1.911 2.923) (xy -1.911 2.967) (xy -1.911 3.2)
				(xy -2.035 3.197) (xy -2.038 2.984) (xy -2.038 2.932) (xy -2.039 2.889) (xy -2.039 2.854) (xy -2.04 2.826)
				(xy -2.041 2.805) (xy -2.042 2.788) (xy -2.043 2.776) (xy -2.045 2.767) (xy -2.046 2.76) (xy -2.049 2.755)
				(xy -2.051 2.75) (xy -2.072 2.721) (xy -2.098 2.701) (xy -2.128 2.688) (xy -2.161 2.683) (xy -2.195 2.687)
				(xy -2.22 2.697) (xy -2.24 2.71) (xy -2.259 2.729) (xy -2.274 2.75) (xy -2.278 2.757) (xy -2.28 2.765)
				(xy -2.281 2.781) (xy -2.283 2.806) (xy -2.284 2.839) (xy -2.285 2.881) (xy -2.286 2.933) (xy -2.286 2.984)
				(xy -2.289 3.197) (xy -2.413 3.2) (xy -2.413 1.877) (xy -2.286 1.877) (xy -2.285 1.926) (xy -2.281 1.966)
				(xy -2.274 1.998) (xy -2.262 2.024) (xy -2.247 2.043) (xy -2.228 2.058) (xy -2.215 2.064) (xy -2.194 2.07)
				(xy -2.168 2.072) (xy -2.141 2.071) (xy -2.117 2.066) (xy -2.106 2.063) (xy -2.079 2.044) (xy -2.058 2.019)
				(xy -2.05 2.001) (xy -2.045 1.984) (xy -2.042 1.959) (xy -2.04 1.929) (xy -2.038 1.895) (xy -2.038 1.861)
				(xy -2.039 1.829) (xy -2.041 1.8) (xy -2.044 1.777) (xy -2.045 1.772) (xy -2.057 1.738) (xy -2.073 1.712)
				(xy -2.094 1.695) (xy -2.122 1.684) (xy -2.156 1.681) (xy -2.159 1.681) (xy -2.192 1.683) (xy -2.22 1.691)
				(xy -2.243 1.705) (xy -2.26 1.725) (xy -2.273 1.753) (xy -2.281 1.788) (xy -2.285 1.832) (xy -2.286 1.877)
				(xy -2.413 1.877) (xy -2.413 1.559) (xy -2.286 1.559) (xy -2.286 1.62) (xy -2.26 1.6) (xy -2.225 1.577)
				(xy -2.19 1.563) (xy -2.154 1.554) (xy -2.109 1.552) (xy -2.065 1.559)
			)
			(stroke
				(width 0.01)
				(type solid)
			)
			(fill yes)
			(layer "F.Mask")
		)
		(fp_poly
			(pts
				(xy 0.063 -3.201) (xy 0.118 -3.201) (xy 0.164 -3.201) (xy 0.202 -3.2) (xy 0.233 -3.2) (xy 0.258 -3.2)
				(xy 0.277 -3.199) (xy 0.292 -3.198) (xy 0.302 -3.197) (xy 0.309 -3.196) (xy 0.314 -3.195) (xy 0.317 -3.193)
				(xy 0.319 -3.192) (xy 0.321 -3.189) (xy 0.324 -3.183) (xy 0.327 -3.174) (xy 0.33 -3.161) (xy 0.334 -3.144)
				(xy 0.339 -3.12) (xy 0.345 -3.091) (xy 0.352 -3.054) (xy 0.361 -3.01) (xy 0.371 -2.958) (xy 0.382 -2.897)
				(xy 0.385 -2.878) (xy 0.395 -2.824) (xy 0.405 -2.772) (xy 0.414 -2.724) (xy 0.423 -2.68) (xy 0.43 -2.642)
				(xy 0.437 -2.61) (xy 0.442 -2.586) (xy 0.446 -2.569) (xy 0.448 -2.562) (xy 0.456 -2.55) (xy 0.464 -2.544)
				(xy 0.476 -2.539) (xy 0.495 -2.53) (xy 0.521 -2.519) (xy 0.552 -2.506) (xy 0.587 -2.492) (xy 0.624 -2.477)
				(xy 0.664 -2.461) (xy 0.704 -2.445) (xy 0.743 -2.43) (xy 0.78 -2.415) (xy 0.814 -2.402) (xy 0.843 -2.391)
				(xy 0.868 -2.382) (xy 0.885 -2.376) (xy 0.895 -2.373) (xy 0.896 -2.373) (xy 0.911 -2.376) (xy 0.931 -2.386)
				(xy 0.948 -2.397) (xy 0.962 -2.406) (xy 0.983 -2.421) (xy 1.011 -2.44) (xy 1.043 -2.462) (xy 1.079 -2.487)
				(xy 1.118 -2.513) (xy 1.158 -2.541) (xy 1.198 -2.568) (xy 1.238 -2.595) (xy 1.275 -2.621) (xy 1.309 -2.644)
				(xy 1.338 -2.665) (xy 1.362 -2.681) (xy 1.377 -2.691) (xy 1.398 -2.705) (xy 1.418 -2.717) (xy 1.433 -2.725)
				(xy 1.442 -2.728) (xy 1.443 -2.728) (xy 1.448 -2.726) (xy 1.456 -2.72) (xy 1.468 -2.71) (xy 1.486 -2.694)
				(xy 1.508 -2.673) (xy 1.535 -2.647) (xy 1.568 -2.614) (xy 1.608 -2.575) (xy 1.654 -2.53) (xy 1.675 -2.509)
				(xy 1.721 -2.462) (xy 1.761 -2.422) (xy 1.794 -2.388) (xy 1.822 -2.36) (xy 1.844 -2.337) (xy 1.862 -2.318)
				(xy 1.875 -2.304) (xy 1.884 -2.293) (xy 1.89 -2.284) (xy 1.893 -2.279) (xy 1.894 -2.275) (xy 1.892 -2.269)
				(xy 1.886 -2.257) (xy 1.875 -2.239) (xy 1.86 -2.215) (xy 1.839 -2.183) (xy 1.814 -2.145) (xy 1.783 -2.1)
				(xy 1.747 -2.046) (xy 1.721 -2.009) (xy 1.69 -1.964) (xy 1.661 -1.921) (xy 1.634 -1.88) (xy 1.609 -1.844)
				(xy 1.588 -1.811) (xy 1.57 -1.785) (xy 1.557 -1.764) (xy 1.549 -1.75) (xy 1.546 -1.743) (xy 1.547 -1.735)
				(xy 1.552 -1.719) (xy 1.56 -1.696) (xy 1.571 -1.667) (xy 1.585 -1.634) (xy 1.6 -1.597) (xy 1.616 -1.557)
				(xy 1.633 -1.516) (xy 1.651 -1.476) (xy 1.668 -1.436) (xy 1.685 -1.398) (xy 1.701 -1.363) (xy 1.715 -1.333)
				(xy 1.727 -1.309) (xy 1.736 -1.291) (xy 1.742 -1.281) (xy 1.744 -1.279) (xy 1.751 -1.277) (xy 1.767 -1.273)
				(xy 1.791 -1.268) (xy 1.822 -1.261) (xy 1.86 -1.254) (xy 1.903 -1.245) (xy 1.951 -1.236) (xy 2.002 -1.226)
				(xy 2.049 -1.217) (xy 2.103 -1.207) (xy 2.154 -1.198) (xy 2.201 -1.188) (xy 2.244 -1.18) (xy 2.281 -1.173)
				(xy 2.311 -1.166) (xy 2.335 -1.161) (xy 2.35 -1.157) (xy 2.355 -1.156) (xy 2.367 -1.148) (xy 2.367 -0.834)
				(xy 2.367 -0.768) (xy 2.367 -0.712) (xy 2.367 -0.664) (xy 2.366 -0.625) (xy 2.366 -0.592) (xy 2.365 -0.566)
				(xy 2.364 -0.546) (xy 2.363 -0.531) (xy 2.361 -0.52) (xy 2.358 -0.512) (xy 2.355 -0.507) (xy 2.352 -0.504)
				(xy 2.348 -0.503) (xy 2.343 -0.501) (xy 2.34 -0.501) (xy 2.333 -0.499) (xy 2.317 -0.496) (xy 2.293 -0.492)
				(xy 2.261 -0.486) (xy 2.224 -0.479) (xy 2.181 -0.471) (xy 2.134 -0.462) (xy 2.084 -0.453) (xy 2.054 -0.448)
				(xy 2.002 -0.438) (xy 1.953 -0.429) (xy 1.907 -0.42) (xy 1.866 -0.412) (xy 1.831 -0.404) (xy 1.802 -0.398)
				(xy 1.78 -0.394) (xy 1.767 -0.391) (xy 1.764 -0.39) (xy 1.76 -0.387) (xy 1.757 -0.384) (xy 1.753 -0.379)
				(xy 1.748 -0.371) (xy 1.742 -0.36) (xy 1.735 -0.344) (xy 1.726 -0.324) (xy 1.715 -0.297) (xy 1.701 -0.264)
				(xy 1.685 -0.223) (xy 1.665 -0.174) (xy 1.653 -0.145) (xy 1.63 -0.086) (xy 1.61 -0.037) (xy 1.594 0.005)
				(xy 1.582 0.038) (xy 1.572 0.064) (xy 1.566 0.084) (xy 1.562 0.097) (xy 1.561 0.104) (xy 1.562 0.105)
				(xy 1.565 0.111) (xy 1.574 0.125) (xy 1.587 0.146) (xy 1.604 0.173) (xy 1.626 0.205) (xy 1.65 0.241)
				(xy 1.677 0.281) (xy 1.706 0.324) (xy 1.729 0.358) (xy 1.768 0.413) (xy 1.8 0.461) (xy 1.827 0.502)
				(xy 1.85 0.535) (xy 1.867 0.562) (xy 1.88 0.583) (xy 1.889 0.598) (xy 1.893 0.608) (xy 1.894 0.612)
				(xy 1.893 0.616) (xy 1.89 0.622) (xy 1.885 0.63) (xy 1.876 0.64) (xy 1.863 0.655) (xy 1.846 0.673)
				(xy 1.825 0.695) (xy 1.798 0.723) (xy 1.765 0.756) (xy 1.727 0.795) (xy 1.682 0.839) (xy 1.635 0.886)
				(xy 1.595 0.926) (xy 1.561 0.96) (xy 1.532 0.989) (xy 1.508 1.012) (xy 1.488 1.03) (xy 1.473 1.044)
				(xy 1.461 1.054) (xy 1.452 1.061) (xy 1.445 1.065) (xy 1.44 1.066) (xy 1.438 1.066) (xy 1.433 1.064)
				(xy 1.421 1.055) (xy 1.401 1.043) (xy 1.376 1.026) (xy 1.345 1.005) (xy 1.31 0.981) (xy 1.27 0.954)
				(xy 1.228 0.925) (xy 1.193 0.901) (xy 1.138 0.864) (xy 1.089 0.83) (xy 1.046 0.802) (xy 1.01 0.778)
				(xy 0.981 0.759) (xy 0.96 0.746) (xy 0.946 0.738) (xy 0.94 0.736) (xy 0.932 0.738) (xy 0.917 0.745)
				(xy 0.895 0.755) (xy 0.869 0.768) (xy 0.84 0.783) (xy 0.816 0.795) (xy 0.781 0.814) (xy 0.753 0.828)
				(xy 0.732 0.838) (xy 0.717 0.845) (xy 0.707 0.849) (xy 0.699 0.85) (xy 0.694 0.849) (xy 0.691 0.847)
				(xy 0.687 0.84) (xy 0.682 0.829) (xy 0.674 0.814) (xy 0.665 0.793) (xy 0.653 0.767) (xy 0.639 0.735)
				(xy 0.623 0.696) (xy 0.604 0.651) (xy 0.582 0.598) (xy 0.556 0.538) (xy 0.528 0.469) (xy 0.496 0.391)
				(xy 0.47 0.329) (xy 0.436 0.247) (xy 0.406 0.173) (xy 0.379 0.108) (xy 0.355 0.05) (xy 0.335 0)
				(xy 0.317 -0.043) (xy 0.303 -0.079) (xy 0.291 -0.11) (xy 0.281 -0.135) (xy 0.273 -0.155) (xy 0.268 -0.171)
				(xy 0.264 -0.183) (xy 0.262 -0.191) (xy 0.262 -0.196) (xy 0.262 -0.198) (xy 0.269 -0.207) (xy 0.283 -0.219)
				(xy 0.302 -0.233) (xy 0.303 -0.234) (xy 0.354 -0.268) (xy 0.398 -0.3) (xy 0.435 -0.331) (xy 0.469 -0.363)
				(xy 0.5 -0.397) (xy 0.507 -0.405) (xy 0.556 -0.472) (xy 0.596 -0.543) (xy 0.627 -0.619) (xy 0.643 -0.672)
				(xy 0.651 -0.718) (xy 0.657 -0.77) (xy 0.66 -0.824) (xy 0.659 -0.878) (xy 0.654 -0.927) (xy 0.652 -0.936)
				(xy 0.634 -1.015) (xy 0.607 -1.09) (xy 0.571 -1.161) (xy 0.528 -1.227) (xy 0.477 -1.287) (xy 0.419 -1.341)
				(xy 0.355 -1.387) (xy 0.285 -1.426) (xy 0.21 -1.456) (xy 0.205 -1.458) (xy 0.131 -1.477) (xy 0.054 -1.487)
				(xy -0.025 -1.489) (xy -0.103 -1.482) (xy -0.178 -1.466) (xy -0.206 -1.458) (xy -0.281 -1.428) (xy -0.351 -1.39)
				(xy -0.416 -1.344) (xy -0.474 -1.29) (xy -0.526 -1.23) (xy -0.571 -1.164) (xy -0.607 -1.093) (xy -0.63 -1.034)
				(xy -0.649 -0.96) (xy -0.659 -0.883) (xy -0.661 -0.804) (xy -0.654 -0.726) (xy -0.638 -0.651) (xy -0.63 -0.623)
				(xy -0.618 -0.591) (xy -0.602 -0.554) (xy -0.584 -0.518) (xy -0.566 -0.485) (xy -0.553 -0.463) (xy -0.509 -0.407)
				(xy -0.457 -0.352) (xy -0.397 -0.299) (xy -0.33 -0.25) (xy -0.289 -0.224) (xy -0.273 -0.212) (xy -0.263 -0.2)
				(xy -0.262 -0.197) (xy -0.263 -0.19) (xy -0.268 -0.175) (xy -0.277 -0.151) (xy -0.288 -0.121) (xy -0.302 -0.084)
				(xy -0.319 -0.042) (xy -0.338 0.005) (xy -0.358 0.056) (xy -0.381 0.111) (xy -0.404 0.168) (xy -0.428 0.228)
				(xy -0.453 0.288) (xy -0.478 0.349) (xy -0.504 0.41) (xy -0.529 0.47) (xy -0.553 0.527) (xy -0.576 0.583)
				(xy -0.598 0.635) (xy -0.619 0.683) (xy -0.638 0.727) (xy -0.655 0.765) (xy -0.669 0.797) (xy -0.68 0.822)
				(xy -0.689 0.839) (xy -0.694 0.848) (xy -0.695 0.849) (xy -0.699 0.85) (xy -0.706 0.849) (xy -0.717 0.845)
				(xy -0.732 0.839) (xy -0.752 0.829) (xy -0.779 0.815) (xy -0.814 0.797) (xy -0.817 0.795) (xy -0.848 0.779)
				(xy -0.877 0.764) (xy -0.902 0.752) (xy -0.922 0.743) (xy -0.936 0.737) (xy -0.941 0.736) (xy -0.949 0.739)
				(xy -0.964 0.748) (xy -0.987 0.761) (xy -1.015 0.78) (xy -1.05 0.803) (xy -1.072 0.818) (xy -1.138 0.863)
				(xy -1.195 0.903) (xy -1.245 0.937) (xy -1.289 0.966) (xy -1.325 0.991) (xy -1.356 1.012) (xy -1.381 1.029)
				(xy -1.401 1.042) (xy -1.416 1.052) (xy -1.427 1.059) (xy -1.435 1.064) (xy -1.439 1.066) (xy -1.44 1.066)
				(xy -1.449 1.064) (xy -1.453 1.061) (xy -1.458 1.057) (xy -1.47 1.046) (xy -1.487 1.029) (xy -1.509 1.007)
				(xy -1.537 0.98) (xy -1.568 0.95) (xy -1.602 0.915) (xy -1.639 0.879) (xy -1.678 0.84) (xy -1.678 0.839)
				(xy -1.726 0.792) (xy -1.767 0.751) (xy -1.801 0.716) (xy -1.829 0.687) (xy -1.852 0.663) (xy -1.869 0.644)
				(xy -1.882 0.63) (xy -1.89 0.62) (xy -1.894 0.613) (xy -1.895 0.61) (xy -1.892 0.603) (xy -1.884 0.588)
				(xy -1.87 0.565) (xy -1.85 0.536) (xy -1.826 0.499) (xy -1.797 0.455) (xy -1.763 0.405) (xy -1.73 0.358)
				(xy -1.7 0.313) (xy -1.671 0.271) (xy -1.645 0.232) (xy -1.621 0.197) (xy -1.601 0.166) (xy -1.584 0.141)
				(xy -1.572 0.121) (xy -1.565 0.109) (xy -1.563 0.105) (xy -1.563 0.099) (xy -1.566 0.087) (xy -1.572 0.07)
				(xy -1.58 0.045) (xy -1.592 0.013) (xy -1.607 -0.026) (xy -1.626 -0.074) (xy -1.648 -0.13) (xy -1.654 -0.145)
				(xy -1.676 -0.199) (xy -1.695 -0.245) (xy -1.71 -0.282) (xy -1.723 -0.313) (xy -1.733 -0.337) (xy -1.741 -0.356)
				(xy -1.748 -0.369) (xy -1.753 -0.379) (xy -1.758 -0.385) (xy -1.761 -0.388) (xy -1.763 -0.389) (xy -1.767 -0.39)
				(xy -1.774 -0.392) (xy -1.784 -0.395) (xy -1.799 -0.398) (xy -1.818 -0.402) (xy -1.843 -0.407) (xy -1.873 -0.413)
				(xy -1.91 -0.42) (xy -1.954 -0.429) (xy -2.005 -0.438) (xy -2.065 -0.449) (xy -2.133 -0.462) (xy -2.211 -0.477)
				(xy -2.22 -0.478) (xy -2.26 -0.486) (xy -2.29 -0.491) (xy -2.313 -0.496) (xy -2.33 -0.499) (xy -2.341 -0.502)
				(xy -2.349 -0.504) (xy -2.353 -0.506) (xy -2.356 -0.508) (xy -2.359 -0.51) (xy -2.36 -0.511) (xy -2.361 -0.514)
				(xy -2.363 -0.518) (xy -2.364 -0.526) (xy -2.365 -0.536) (xy -2.366 -0.551) (xy -2.366 -0.571) (xy -2.367 -0.597)
				(xy -2.367 -0.629) (xy -2.368 -0.668) (xy -2.368 -0.715) (xy -2.368 -0.771) (xy -2.368 -0.834) (xy -2.368 -1.148)
				(xy -2.356 -1.155) (xy -2.349 -1.158) (xy -2.333 -1.162) (xy -2.309 -1.167) (xy -2.278 -1.173) (xy -2.24 -1.181)
				(xy -2.197 -1.189) (xy -2.149 -1.198) (xy -2.098 -1.208) (xy -2.051 -1.217) (xy -1.996 -1.227) (xy -1.945 -1.237)
				(xy -1.897 -1.246) (xy -1.854 -1.254) (xy -1.817 -1.262) (xy -1.787 -1.268) (xy -1.764 -1.273) (xy -1.75 -1.277)
				(xy -1.745 -1.279) (xy -1.741 -1.285) (xy -1.733 -1.3) (xy -1.722 -1.322) (xy -1.709 -1.35) (xy -1.694 -1.382)
				(xy -1.677 -1.419) (xy -1.66 -1.458) (xy -1.642 -1.498) (xy -1.625 -1.539) (xy -1.608 -1.58) (xy -1.592 -1.618)
				(xy -1.578 -1.653) (xy -1.565 -1.684) (xy -1.556 -1.709) (xy -1.549 -1.729) (xy -1.546 -1.74) (xy -1.546 -1.742)
				(xy -1.549 -1.749) (xy -1.558 -1.763) (xy -1.571 -1.784) (xy -1.588 -1.811) (xy -1.61 -1.843) (xy -1.634 -1.88)
				(xy -1.661 -1.92) (xy -1.691 -1.963) (xy -1.722 -2.008) (xy -1.762 -2.067) (xy -1.796 -2.117) (xy -1.825 -2.16)
				(xy -1.848 -2.196) (xy -1.867 -2.225) (xy -1.881 -2.247) (xy -1.89 -2.262) (xy -1.895 -2.272) (xy -1.895 -2.275)
				(xy -1.894 -2.279) (xy -1.891 -2.285) (xy -1.884 -2.293) (xy -1.875 -2.305) (xy -1.861 -2.32) (xy -1.843 -2.339)
				(xy -1.82 -2.363) (xy -1.792 -2.392) (xy -1.758 -2.426) (xy -1.718 -2.466) (xy -1.676 -2.509) (xy -1.627 -2.557)
				(xy -1.585 -2.599) (xy -1.549 -2.634) (xy -1.52 -2.663) (xy -1.495 -2.686) (xy -1.476 -2.704) (xy -1.462 -2.716)
				(xy -1.452 -2.724) (xy -1.446 -2.728) (xy -1.444 -2.728) (xy -1.437 -2.726) (xy -1.423 -2.717) (xy -1.401 -2.703)
				(xy -1.372 -2.685) (xy -1.337 -2.661) (xy -1.295 -2.634) (xy -1.248 -2.602) (xy -1.196 -2.566) (xy -1.173 -2.551)
				(xy -1.118 -2.513) (xy -1.071 -2.481) (xy -1.031 -2.454) (xy -0.998 -2.432) (xy -0.97 -2.413) (xy -0.948 -2.399)
				(xy -0.931 -2.389) (xy -0.917 -2.381) (xy -0.907 -2.376) (xy -0.901 -2.373) (xy -0.897 -2.373) (xy -0.888 -2.375)
				(xy -0.87 -2.38) (xy -0.845 -2.39) (xy -0.813 -2.402) (xy -0.774 -2.417) (xy -0.73 -2.434) (xy -0.681 -2.454)
				(xy -0.629 -2.475) (xy -0.586 -2.493) (xy -0.55 -2.508) (xy -0.522 -2.52) (xy -0.499 -2.529) (xy -0.482 -2.537)
				(xy -0.47 -2.543) (xy -0.461 -2.548) (xy -0.455 -2.551) (xy -0.452 -2.554) (xy -0.449 -2.557) (xy -0.448 -2.56)
				(xy -0.447 -2.566) (xy -0.443 -2.582) (xy -0.438 -2.605) (xy -0.432 -2.637) (xy -0.425 -2.674) (xy -0.417 -2.717)
				(xy -0.407 -2.765) (xy -0.398 -2.817) (xy -0.388 -2.871) (xy -0.387 -2.876) (xy -0.375 -2.94) (xy -0.364 -2.995)
				(xy -0.356 -3.042) (xy -0.348 -3.081) (xy -0.342 -3.112) (xy -0.337 -3.137) (xy -0.332 -3.157) (xy -0.328 -3.171)
				(xy -0.325 -3.181) (xy -0.323 -3.188) (xy -0.32 -3.191) (xy -0.32 -3.192) (xy -0.317 -3.194) (xy -0.313 -3.195)
				(xy -0.307 -3.197) (xy -0.298 -3.198) (xy -0.286 -3.199) (xy -0.269 -3.199) (xy -0.247 -3.2) (xy -0.219 -3.2)
				(xy -0.184 -3.201) (xy -0.142 -3.201) (xy -0.092 -3.201) (xy -0.033 -3.201) (xy -0.001 -3.201) (xy 0.063 -3.201)
			)
			(stroke
				(width 0.01)
				(type solid)
			)
			(fill yes)
			(layer "F.Mask")
		)
	)
	(footprint "antmicro-footprints:LED_0603_1608Metric_G"
		(layer "F.Cu")
		(at 205.286328 84.820008 180)
		(descr "LED SMD 0603 Green")
		(tags "LED SMD 0603 Green")
		(property "Reference" "D8"
			(at 0.786328 0.620008 180)
			(layer "F.SilkS")
			(effects
				(font
					(size 0.7 0.7)
					(thickness 0.15)
				)
				(justify left bottom)
			)
		)
		(property "Value" "LED_G_0603_KP-1608CGCK"
			(at 0 1.6 180)
			(layer "F.Fab")
			(effects
				(font
					(size 0.7 0.7)
					(thickness 0.15)
				)
				(justify left bottom)
			)
		)
		(property "Author" "Antmicro"
			(at 410.572656 169.640016 0)
			(layer "F.Fab")
			(hide yes)
			(effects
				(font
					(size 1 1)
					(thickness 0.15)
				)
			)
		)
		(property "License" "Apache-2.0"
			(at 410.572656 169.640016 0)
			(layer "F.Fab")
			(hide yes)
			(effects
				(font
					(size 1 1)
					(thickness 0.15)
				)
			)
		)
		(property "MPN" "KP-1608CGCK"
			(at 410.572656 169.640016 0)
			(layer "F.Fab")
			(hide yes)
			(effects
				(font
					(size 1 1)
					(thickness 0.15)
				)
			)
		)
		(property "Manufacturer" "Kingbright"
			(at 410.572656 169.640016 0)
			(layer "F.Fab")
			(hide yes)
			(effects
				(font
					(size 1 1)
					(thickness 0.15)
				)
			)
		)
		(sheetname "Config SPI flash")
		(sheetfile "config-spi.kicad_sch")
		(attr smd)
		(fp_line
			(start 1.25 0.32)
			(end 1.25 -0.32)
			(stroke
				(width 0.15)
				(type solid)
			)
			(layer "F.SilkS")
		)
		(fp_line
			(start 0.093672 -8e-06)
			(end 0.293672 -8e-06)
			(stroke
				(width 0.1)
				(type solid)
			)
			(layer "F.SilkS")
		)
		(fp_line
			(start 0.093672 -8e-06)
			(end -0.106328 0.199992)
			(stroke
				(width 0.1)
				(type solid)
			)
			(layer "F.SilkS")
		)
		(fp_line
			(start 0.093672 -0.200008)
			(end 0.093672 0.199992)
			(stroke
				(width 0.1)
				(type solid)
			)
			(layer "F.SilkS")
		)
		(fp_line
			(start -0.106328 -8e-06)
			(end -0.29 0)
			(stroke
				(width 0.1)
				(type solid)
			)
			(layer "F.SilkS")
		)
		(fp_line
			(start -0.106328 -0.200008)
			(end 0.093672 -8e-06)
			(stroke
				(width 0.1)
				(type solid)
			)
			(layer "F.SilkS")
		)
		(fp_line
			(start -0.106328 -0.200008)
			(end -0.106328 0.199992)
			(stroke
				(width 0.1)
				(type solid)
			)
			(layer "F.SilkS")
		)
		(fp_line
			(start -0.27 0.351)
			(end 0.27 0.351)
			(stroke
				(width 0.15)
				(type solid)
			)
			(layer "F.SilkS")
		)
		(fp_line
			(start -0.27 -0.35)
			(end 0.27 -0.35)
			(stroke
				(width 0.15)
				(type solid)
			)
			(layer "F.SilkS")
		)
		(fp_rect
			(start 1.26 0.65)
			(end -1.26 -0.65)
			(stroke
				(width 0.05)
				(type solid)
			)
			(fill no)
			(layer "F.CrtYd")
		)
		(fp_line
			(start 0.199 0.202)
			(end 0.199 -0.1)
			(stroke
				(width 0.15)
				(type solid)
			)
			(layer "F.Fab")
		)
		(fp_line
			(start 0.199 0)
			(end 0.597 0)
			(stroke
				(width 0.15)
				(type solid)
			)
			(layer "F.Fab")
		)
		(fp_line
			(start 0.199 -0.2)
			(end 0.199 -0.1)
			(stroke
				(width 0.15)
				(type solid)
			)
			(layer "F.Fab")
		)
		(fp_line
			(start 0.101 0)
			(end -0.201 -0.2)
			(stroke
				(width 0.15)
				(type solid)
			)
			(layer "F.Fab")
		)
		(fp_line
			(start -0.201 0.202)
			(end 0.101 0)
			(stroke
				(width 0.15)
				(type solid)
			)
			(layer "F.Fab")
		)
		(fp_line
			(start -0.201 0)
			(end -0.201 0.202)
			(stroke
				(width 0.15)
				(type solid)
			)
			(layer "F.Fab")
		)
		(fp_line
			(start -0.201 -0.2)
			(end -0.201 0)
			(stroke
				(width 0.15)
				(type solid)
			)
			(layer "F.Fab")
		)
		(fp_line
			(start -0.599 0)
			(end -0.201 0)
			(stroke
				(width 0.15)
				(type solid)
			)
			(layer "F.Fab")
		)
		(fp_rect
			(start -0.848 -0.4)
			(end 0.85 0.402)
			(stroke
				(width 0.15)
				(type solid)
			)
			(fill no)
			(layer "F.Fab")
		)
		(pad "1" smd rect
			(at -0.75 0)
			(size 0.8 0.8)
			(layers "F.Cu" "F.Mask" "F.Paste")
			(net 459 "3V3_SYS")
			(pinfunction "1")
			(pintype "passive")
		)
		(pad "2" smd rect
			(at 0.75 0)
			(size 0.8 0.8)
			(layers "F.Cu" "F.Mask" "F.Paste")
			(net 54 "Net-(D8-Pad2)")
			(pinfunction "2")
			(pintype "passive")
		)
	)
	(footprint "antmicro-footprints:C_0402_1005Metric"
		(layer "F.Cu")
		(at 191.386328 101.374306 90)
		(descr "Capacitor SMD 0402")
		(tags "capacitor SMD 0402")
		(property "Reference" "C111"
			(at 2.974306 0.413672 90)
			(layer "F.SilkS")
			(effects
				(font
					(size 0.7 0.7)
					(thickness 0.15)
				)
				(justify left bottom)
			)
		)
		(property "Value" "C_10n_0402"
			(at 0 1.4 90)
			(layer "F.Fab")
			(effects
				(font
					(size 0.7 0.7)
					(thickness 0.15)
				)
				(justify left bottom)
			)
		)
		(property "Description" " "
			(at 0 0 90)
			(layer "F.Fab")
			(hide yes)
			(effects
				(font
					(size 1.27 1.27)
					(thickness 0.15)
				)
			)
		)
		(property "Author" "Antmicro"
			(at 292.760634 -90.012022 0)
			(layer "F.Fab")
			(hide yes)
			(effects
				(font
					(size 1 1)
					(thickness 0.15)
				)
			)
		)
		(property "Dielectric" "X7R"
			(at 292.760634 -90.012022 0)
			(layer "F.Fab")
			(hide yes)
			(effects
				(font
					(size 1 1)
					(thickness 0.15)
				)
			)
		)
		(property "License" "Apache-2.0"
			(at 292.760634 -90.012022 0)
			(layer "F.Fab")
			(hide yes)
			(effects
				(font
					(size 1 1)
					(thickness 0.15)
				)
			)
		)
		(property "MPN" "GRM155R71H103KA88D"
			(at 292.760634 -90.012022 0)
			(layer "F.Fab")
			(hide yes)
			(effects
				(font
					(size 1 1)
					(thickness 0.15)
				)
			)
		)
		(property "Manufacturer" "Murata"
			(at 292.760634 -90.012022 0)
			(layer "F.Fab")
			(hide yes)
			(effects
				(font
					(size 1 1)
					(thickness 0.15)
				)
			)
		)
		(property "Val" "10n"
			(at 292.760634 -90.012022 0)
			(layer "F.Fab")
			(hide yes)
			(effects
				(font
					(size 1 1)
					(thickness 0.15)
				)
			)
		)
		(property "Voltage" "50V"
			(at 292.760634 -90.012022 0)
			(layer "F.Fab")
			(hide yes)
			(effects
				(font
					(size 1 1)
					(thickness 0.15)
				)
			)
		)
		(sheetname "Ethernet")
		(sheetfile "ethernet.kicad_sch")
		(attr smd)
		(fp_rect
			(start -0.94 -0.47)
			(end 0.94 0.47)
			(stroke
				(width 0.05)
				(type solid)
			)
			(fill no)
			(layer "F.CrtYd")
		)
		(fp_rect
			(start -0.499 -0.249)
			(end 0.499 0.249)
			(stroke
				(width 0.15)
				(type solid)
			)
			(fill no)
			(layer "F.Fab")
		)
		(pad "1" smd roundrect
			(at -0.484 0 90)
			(size 0.59 0.64)
			(layers "F.Cu" "F.Mask" "F.Paste")
			(roundrect_rratio 0.25)
			(net 530 "/Ethernet/AVDDL_PLL")
			(pintype "passive")
		)
		(pad "2" smd roundrect
			(at 0.484 0 90)
			(size 0.59 0.64)
			(layers "F.Cu" "F.Mask" "F.Paste")
			(roundrect_rratio 0.25)
			(net 5 "GND")
			(pintype "passive")
		)
	)
	(footprint "antmicro-footprints:QFN-48-1EP_7x7x0.9mm_P0.5mm_EP3.5x3.5mm"
		(layer "F.Cu")
		(at 200.436328 103.047157 90)
		(property "Reference" "U6"
			(at 0 -4.3 90)
			(layer "F.SilkS")
			(effects
				(font
					(size 0.7 0.7)
					(thickness 0.15)
				)
				(justify left bottom)
			)
		)
		(property "Value" "KSZ9031RNXCA"
			(at 0 5.1 90)
			(layer "F.Fab")
			(hide yes)
			(effects
				(font
					(size 0.7 0.7)
					(thickness 0.15)
				)
				(justify left bottom)
			)
		)
		(property "Description" "Ethernet Controller, 1000 Mbps, IEEE 802.3, 1.14 V, 3.465 V, QFN, 48 Pins"
			(at 0 0 90)
			(layer "F.Fab")
			(hide yes)
			(effects
				(font
					(size 1.27 1.27)
					(thickness 0.15)
				)
			)
		)
		(property "Author" "Antmicro"
			(at 303.483485 -97.389171 0)
			(layer "F.Fab")
			(hide yes)
			(effects
				(font
					(size 1 1)
					(thickness 0.15)
				)
			)
		)
		(property "License" "Apache-2.0"
			(at 303.483485 -97.389171 0)
			(layer "F.Fab")
			(hide yes)
			(effects
				(font
					(size 1 1)
					(thickness 0.15)
				)
			)
		)
		(property "MPN" "KSZ9031RNXCA"
			(at 303.483485 -97.389171 0)
			(layer "F.Fab")
			(hide yes)
			(effects
				(font
					(size 1 1)
					(thickness 0.15)
				)
			)
		)
		(property "Manufacturer" "Microchip Technology"
			(at 303.483485 -97.389171 0)
			(layer "F.Fab")
			(hide yes)
			(effects
				(font
					(size 1 1)
					(thickness 0.15)
				)
			)
		)
		(sheetname "Ethernet")
		(sheetfile "ethernet.kicad_sch")
		(attr smd)
		(fp_line
			(start 3.648 -3.65)
			(end 3.648 -3.25)
			(stroke
				(width 0.15)
				(type solid)
			)
			(layer "F.SilkS")
		)
		(fp_line
			(start 3.249 -3.65)
			(end 3.648 -3.65)
			(stroke
				(width 0.15)
				(type solid)
			)
			(layer "F.SilkS")
		)
		(fp_line
			(start -3.3 -3.65)
			(end -3.65 -3.65)
			(stroke
				(width 0.15)
				(type solid)
			)
			(layer "F.SilkS")
		)
		(fp_line
			(start -3.65 -3.3)
			(end -3.65 -3.65)
			(stroke
				(width 0.15)
				(type solid)
			)
			(layer "F.SilkS")
		)
		(fp_line
			(start 3.648 3.648)
			(end 3.648 3.249)
			(stroke
				(width 0.15)
				(type solid)
			)
			(layer "F.SilkS")
		)
		(fp_line
			(start 3.249 3.648)
			(end 3.648 3.648)
			(stroke
				(width 0.15)
				(type solid)
			)
			(layer "F.SilkS")
		)
		(fp_line
			(start -3.25 3.648)
			(end -3.65 3.648)
			(stroke
				(width 0.15)
				(type solid)
			)
			(layer "F.SilkS")
		)
		(fp_line
			(start -3.65 3.648)
			(end -3.65 3.249)
			(stroke
				(width 0.15)
				(type solid)
			)
			(layer "F.SilkS")
		)
		(fp_circle
			(center -3.7 -3.05)
			(end -3.65 -3.05)
			(stroke
				(width 0.15)
				(type solid)
			)
			(fill yes)
			(layer "F.SilkS")
		)
		(fp_rect
			(start -4.15 -4.15)
			(end 4.15 4.15)
			(stroke
				(width 0.05)
				(type solid)
			)
			(fill no)
			(layer "F.CrtYd")
		)
		(fp_line
			(start 3.499 -3.5)
			(end -2.5 -3.5)
			(stroke
				(width 0.15)
				(type solid)
			)
			(layer "F.Fab")
		)
		(fp_line
			(start -2.5 -3.5)
			(end -3.5 -2.5)
			(stroke
				(width 0.15)
				(type solid)
			)
			(layer "F.Fab")
		)
		(fp_line
			(start -3.5 -2.5)
			(end -3.5 3.499)
			(stroke
				(width 0.15)
				(type solid)
			)
			(layer "F.Fab")
		)
		(fp_line
			(start 3.499 3.499)
			(end 3.499 -3.5)
			(stroke
				(width 0.15)
				(type solid)
			)
			(layer "F.Fab")
		)
		(fp_line
			(start -3.5 3.499)
			(end 3.499 3.499)
			(stroke
				(width 0.15)
				(type solid)
			)
			(layer "F.Fab")
		)
		(pad "1" smd oval
			(at -3.5 -2.75 180)
			(size 0.3 0.9)
			(layers "F.Cu" "F.Mask" "F.Paste")
			(net 531 "/Ethernet/AVDDH")
			(pinfunction "AVDDH")
			(pintype "power_in")
		)
		(pad "2" smd oval
			(at -3.5 -2.25 180)
			(size 0.3 0.9)
			(layers "F.Cu" "F.Mask" "F.Paste")
			(net 522 "/Ethernet/ETH1_P")
			(pinfunction "TXRXP_A")
			(pintype "bidirectional")
		)
		(pad "3" smd oval
			(at -3.5 -1.75 180)
			(size 0.3 0.9)
			(layers "F.Cu" "F.Mask" "F.Paste")
			(net 525 "/Ethernet/ETH1_N")
			(pinfunction "TXRXM_A")
			(pintype "bidirectional")
		)
		(pad "4" smd oval
			(at -3.5 -1.25 180)
			(size 0.3 0.9)
			(layers "F.Cu" "F.Mask" "F.Paste")
			(net 529 "/Ethernet/AVDDL")
			(pinfunction "AVDDL")
			(pintype "power_in")
		)
		(pad "5" smd oval
			(at -3.5 -0.75 180)
			(size 0.3 0.9)
			(layers "F.Cu" "F.Mask" "F.Paste")
			(net 520 "/Ethernet/ETH2_P")
			(pinfunction "TXRXP_B")
			(pintype "bidirectional")
		)
		(pad "6" smd oval
			(at -3.5 -0.25 180)
			(size 0.3 0.9)
			(layers "F.Cu" "F.Mask" "F.Paste")
			(net 524 "/Ethernet/ETH2_N")
			(pinfunction "TXRXM_B")
			(pintype "bidirectional")
		)
		(pad "7" smd oval
			(at -3.5 0.248 180)
			(size 0.3 0.9)
			(layers "F.Cu" "F.Mask" "F.Paste")
			(net 519 "/Ethernet/ETH3_P")
			(pinfunction "TXRXP_C")
			(pintype "bidirectional")
		)
		(pad "8" smd oval
			(at -3.5 0.748 180)
			(size 0.3 0.9)
			(layers "F.Cu" "F.Mask" "F.Paste")
			(net 526 "/Ethernet/ETH3_N")
			(pinfunction "TXRXM_C")
			(pintype "bidirectional")
		)
		(pad "9" smd oval
			(at -3.5 1.249 180)
			(size 0.3 0.9)
			(layers "F.Cu" "F.Mask" "F.Paste")
			(net 529 "/Ethernet/AVDDL")
			(pinfunction "AVDDL")
			(pintype "passive")
		)
		(pad "10" smd oval
			(at -3.5 1.749 180)
			(size 0.3 0.9)
			(layers "F.Cu" "F.Mask" "F.Paste")
			(net 523 "/Ethernet/ETH4_P")
			(pinfunction "TXRXP_D")
			(pintype "bidirectional")
		)
		(pad "11" smd oval
			(at -3.5 2.249 180)
			(size 0.3 0.9)
			(layers "F.Cu" "F.Mask" "F.Paste")
			(net 527 "/Ethernet/ETH4_N")
			(pinfunction "TXRXM_D")
			(pintype "bidirectional")
		)
		(pad "12" smd oval
			(at -3.5 2.749 180)
			(size 0.3 0.9)
			(layers "F.Cu" "F.Mask" "F.Paste")
			(net 531 "/Ethernet/AVDDH")
			(pinfunction "AVDDH")
			(pintype "passive")
		)
		(pad "13" smd oval
			(at -2.75 3.499 90)
			(size 0.3 0.9)
			(layers "F.Cu" "F.Mask" "F.Paste")
			(net 638 "unconnected-(U6-NC-Pad13)")
			(pinfunction "NC")
			(pintype "no_connect")
		)
		(pad "14" smd oval
			(at -2.25 3.499 90)
			(size 0.3 0.9)
			(layers "F.Cu" "F.Mask" "F.Paste")
			(net 602 "1V2_SYS")
			(pinfunction "DVDDL")
			(pintype "power_in")
		)
		(pad "15" smd oval
			(at -1.75 3.499 90)
			(size 0.3 0.9)
			(layers "F.Cu" "F.Mask" "F.Paste")
			(net 13 "LED_SPD")
			(pinfunction "LED2/PHYAD1")
			(pintype "bidirectional")
		)
		(pad "16" smd oval
			(at -1.25 3.499 90)
			(size 0.3 0.9)
			(layers "F.Cu" "F.Mask" "F.Paste")
			(net 459 "3V3_SYS")
			(pinfunction "DVDDH")
			(pintype "power_in")
		)
		(pad "17" smd oval
			(at -0.75 3.499 90)
			(size 0.3 0.9)
			(layers "F.Cu" "F.Mask" "F.Paste")
			(net 12 "LED_LINK")
			(pinfunction "LED1/PHAD0/PME_N1")
			(pintype "bidirectional")
		)
		(pad "18" smd oval
			(at -0.25 3.499 90)
			(size 0.3 0.9)
			(layers "F.Cu" "F.Mask" "F.Paste")
			(net 602 "1V2_SYS")
			(pinfunction "DVDDL")
			(pintype "passive")
		)
		(pad "19" smd oval
			(at 0.248 3.499 90)
			(size 0.3 0.9)
			(layers "F.Cu" "F.Mask" "F.Paste")
			(net 32 "ETH_TXD0")
			(pinfunction "TXD0")
			(pintype "input")
		)
		(pad "20" smd oval
			(at 0.748 3.499 90)
			(size 0.3 0.9)
			(layers "F.Cu" "F.Mask" "F.Paste")
			(net 27 "ETH_TXD1")
			(pinfunction "TXD1")
			(pintype "input")
		)
		(pad "21" smd oval
			(at 1.249 3.499 90)
			(size 0.3 0.9)
			(layers "F.Cu" "F.Mask" "F.Paste")
			(net 28 "ETH_TXD2")
			(pinfunction "TXD2")
			(pintype "input")
		)
		(pad "22" smd oval
			(at 1.749 3.499 90)
			(size 0.3 0.9)
			(layers "F.Cu" "F.Mask" "F.Paste")
			(net 29 "ETH_TXD3")
			(pinfunction "TXD3")
			(pintype "input")
		)
		(pad "23" smd oval
			(at 2.249 3.499 90)
			(size 0.3 0.9)
			(layers "F.Cu" "F.Mask" "F.Paste")
			(net 602 "1V2_SYS")
			(pinfunction "DVDDL")
			(pintype "passive")
		)
		(pad "24" smd oval
			(at 2.749 3.499 90)
			(size 0.3 0.9)
			(layers "F.Cu" "F.Mask" "F.Paste")
			(net 30 "ETH_TX_CLK")
			(pinfunction "GTX_CLK")
			(pintype "input")
		)
		(pad "25" smd oval
			(at 3.499 2.749 180)
			(size 0.3 0.9)
			(layers "F.Cu" "F.Mask" "F.Paste")
			(net 31 "ETH_TX_EN")
			(pinfunction "TX_EN")
			(pintype "input")
		)
		(pad "26" smd oval
			(at 3.499 2.249 180)
			(size 0.3 0.9)
			(layers "F.Cu" "F.Mask" "F.Paste")
			(net 602 "1V2_SYS")
			(pinfunction "DVDDL")
			(pintype "passive")
		)
		(pad "27" smd oval
			(at 3.499 1.749 180)
			(size 0.3 0.9)
			(layers "F.Cu" "F.Mask" "F.Paste")
			(net 33 "ETH_RXD3")
			(pinfunction "RXD3/MODE3")
			(pintype "input")
		)
		(pad "28" smd oval
			(at 3.499 1.249 180)
			(size 0.3 0.9)
			(layers "F.Cu" "F.Mask" "F.Paste")
			(net 37 "ETH_RXD2")
			(pinfunction "RXD2/MODE2")
			(pintype "input")
		)
		(pad "29" smd oval
			(at 3.499 0.748 180)
			(size 0.3 0.9)
			(layers "F.Cu" "F.Mask" "F.Paste")
			(net 5 "GND")
			(pinfunction "VSS")
			(pintype "power_in")
		)
		(pad "30" smd oval
			(at 3.499 0.248 180)
			(size 0.3 0.9)
			(layers "F.Cu" "F.Mask" "F.Paste")
			(net 602 "1V2_SYS")
			(pinfunction "DVDDL")
			(pintype "passive")
		)
		(pad "31" smd oval
			(at 3.499 -0.25 180)
			(size 0.3 0.9)
			(layers "F.Cu" "F.Mask" "F.Paste")
			(net 23 "ETH_RXD1")
			(pinfunction "RXD1/MODE1")
			(pintype "input")
		)
		(pad "32" smd oval
			(at 3.499 -0.75 180)
			(size 0.3 0.9)
			(layers "F.Cu" "F.Mask" "F.Paste")
			(net 22 "ETH_RXD0")
			(pinfunction "RXD0/MODE0")
			(pintype "input")
		)
		(pad "33" smd oval
			(at 3.499 -1.25 180)
			(size 0.3 0.9)
			(layers "F.Cu" "F.Mask" "F.Paste")
			(net 34 "ETH_RX_DV")
			(pinfunction "RX_DV/CLK125_EN")
			(pintype "input")
		)
		(pad "34" smd oval
			(at 3.499 -1.75 180)
			(size 0.3 0.9)
			(layers "F.Cu" "F.Mask" "F.Paste")
			(net 459 "3V3_SYS")
			(pinfunction "DVDDH")
			(pintype "passive")
		)
		(pad "35" smd oval
			(at 3.499 -2.25 180)
			(size 0.3 0.9)
			(layers "F.Cu" "F.Mask" "F.Paste")
			(net 36 "ETH_RX_CLK")
			(pinfunction "RX_CLK/PHYAD2")
			(pintype "input")
		)
		(pad "36" smd oval
			(at 3.499 -2.75 180)
			(size 0.3 0.9)
			(layers "F.Cu" "F.Mask" "F.Paste")
			(net 35 "ETH_MDC")
			(pinfunction "MDC")
			(pintype "input")
		)
		(pad "37" smd oval
			(at 2.749 -3.5 90)
			(size 0.3 0.9)
			(layers "F.Cu" "F.Mask" "F.Paste")
			(net 25 "ETH_MDIO")
			(pinfunction "MDIO")
			(pintype "input")
		)
		(pad "38" smd oval
			(at 2.249 -3.5 90)
			(size 0.3 0.9)
			(layers "F.Cu" "F.Mask" "F.Paste")
			(net 541 "ETH_INT_N")
			(pinfunction "~{INT/PME}")
			(pintype "input")
		)
		(pad "39" smd oval
			(at 1.749 -3.5 90)
			(size 0.3 0.9)
			(layers "F.Cu" "F.Mask" "F.Paste")
			(net 602 "1V2_SYS")
			(pinfunction "DVDDL")
			(pintype "passive")
		)
		(pad "40" smd oval
			(at 1.249 -3.5 90)
			(size 0.3 0.9)
			(layers "F.Cu" "F.Mask" "F.Paste")
			(net 459 "3V3_SYS")
			(pinfunction "DVDDH")
			(pintype "passive")
		)
		(pad "41" smd oval
			(at 0.748 -3.5 90)
			(size 0.3 0.9)
			(layers "F.Cu" "F.Mask" "F.Paste")
			(net 26 "ETH_REF_CLK")
			(pinfunction "CLK125_NDO/LED_MODE")
			(pintype "input")
		)
		(pad "42" smd oval
			(at 0.248 -3.5 90)
			(size 0.3 0.9)
			(layers "F.Cu" "F.Mask" "F.Paste")
			(net 24 "ETH_RSTN")
			(pinfunction "~{RESET}")
			(pintype "input")
		)
		(pad "43" smd oval
			(at -0.25 -3.5 90)
			(size 0.3 0.9)
			(layers "F.Cu" "F.Mask" "F.Paste")
			(net 642 "unconnected-(U6-LDO_O-Pad43)")
			(pinfunction "LDO_O")
			(pintype "input+no_connect")
		)
		(pad "44" smd oval
			(at -0.75 -3.5 90)
			(size 0.3 0.9)
			(layers "F.Cu" "F.Mask" "F.Paste")
			(net 530 "/Ethernet/AVDDL_PLL")
			(pinfunction "AVDDL_PLL")
			(pintype "power_in")
		)
		(pad "45" smd oval
			(at -1.25 -3.5 90)
			(size 0.3 0.9)
			(layers "F.Cu" "F.Mask" "F.Paste")
			(net 656 "ETH_XO")
			(pinfunction "XO")
			(pintype "input")
		)
		(pad "46" smd oval
			(at -1.75 -3.5 90)
			(size 0.3 0.9)
			(layers "F.Cu" "F.Mask" "F.Paste")
			(net 657 "ETH_XI")
			(pinfunction "XI")
			(pintype "input")
		)
		(pad "47" smd oval
			(at -2.25 -3.5 90)
			(size 0.3 0.9)
			(layers "F.Cu" "F.Mask" "F.Paste")
			(net 645 "unconnected-(U6-NC-Pad47)")
			(pinfunction "NC")
			(pintype "no_connect")
		)
		(pad "48" smd oval
			(at -2.75 -3.5 90)
			(size 0.3 0.9)
			(layers "F.Cu" "F.Mask" "F.Paste")
			(net 261 "Net-(U6-ISET)")
			(pinfunction "ISET")
			(pintype "output")
		)
		(pad "49" smd rect
			(at 0 0 90)
			(size 3.5 3.5)
			(layers "F.Cu" "F.Mask" "F.Paste")
			(net 5 "GND")
			(pinfunction "PAD_GND")
			(pintype "power_in")
		)
	)
	(footprint "antmicro-footprints:Resonator_SMD_Abracon_ABM8G_3.2x2.5mm"
		(layer "F.Cu")
		(at 190.686328 105.274306 180)
		(property "Reference" "Y2"
			(at 3.286328 -0.325694 0)
			(layer "F.SilkS")
			(effects
				(font
					(size 0.7 0.7)
					(thickness 0.15)
				)
				(justify left bottom)
			)
		)
		(property "Value" "Oscillator_SMD_25MHz_KX-7"
			(at -1.75 2.548 180)
			(layer "F.Fab")
			(effects
				(font
					(size 0.7 0.7)
					(thickness 0.15)
				)
				(justify left bottom)
			)
		)
		(property "Description" "Crystal, 25 MHz, SMD, 3.2mm x 2.5mm, 30 ppm, 18 pF, 20 ppm, ABM8G"
			(at 0 0 180)
			(layer "F.Fab")
			(hide yes)
			(effects
				(font
					(size 1.27 1.27)
					(thickness 0.15)
				)
			)
		)
		(property "Author" "Antmicro"
			(at 381.372656 210.548612 0)
			(layer "F.Fab")
			(hide yes)
			(effects
				(font
					(size 1 1)
					(thickness 0.15)
				)
			)
		)
		(property "License" "Apache-2.0"
			(at 381.372656 210.548612 0)
			(layer "F.Fab")
			(hide yes)
			(effects
				(font
					(size 1 1)
					(thickness 0.15)
				)
			)
		)
		(property "MPN" "ABM8G-25.000MHZ-18-D2Y-T3"
			(at 381.372656 210.548612 0)
			(layer "F.Fab")
			(hide yes)
			(effects
				(font
					(size 1 1)
					(thickness 0.15)
				)
			)
		)
		(property "Manufacturer" "Abracon"
			(at 381.372656 210.548612 0)
			(layer "F.Fab")
			(hide yes)
			(effects
				(font
					(size 1 1)
					(thickness 0.15)
				)
			)
		)
		(property "Val" "25 MHz"
			(at 381.372656 210.548612 0)
			(layer "F.Fab")
			(hide yes)
			(effects
				(font
					(size 1 1)
					(thickness 0.15)
				)
			)
		)
		(sheetname "Ethernet")
		(sheetfile "ethernet.kicad_sch")
		(attr smd)
		(fp_line
			(start 1.6 0.3)
			(end 1.6 -0.2)
			(stroke
				(width 0.15)
				(type solid)
			)
			(layer "F.SilkS")
		)
		(fp_line
			(start -0.35 1.25)
			(end 0.45 1.25)
			(stroke
				(width 0.15)
				(type solid)
			)
			(layer "F.SilkS")
		)
		(fp_line
			(start -0.35 -1.25)
			(end 0.45 -1.25)
			(stroke
				(width 0.15)
				(type solid)
			)
			(layer "F.SilkS")
		)
		(fp_line
			(start -1.6 0.3)
			(end -1.6 -0.2)
			(stroke
				(width 0.15)
				(type solid)
			)
			(layer "F.SilkS")
		)
		(fp_circle
			(center -1.75 1.5)
			(end -1.7 1.5)
			(stroke
				(width 0.15)
				(type solid)
			)
			(fill no)
			(layer "F.SilkS")
		)
		(fp_rect
			(start -1.907 -1.55)
			(end 2.006 1.649)
			(stroke
				(width 0.05)
				(type solid)
			)
			(fill no)
			(layer "F.CrtYd")
		)
		(pad "1" smd roundrect
			(at -1.101 0.949 180)
			(size 1.3 1.1)
			(layers "F.Cu" "F.Mask" "F.Paste")
			(roundrect_rratio 0)
			(chamfer_ratio 0.2)
			(chamfer bottom_left)
			(net 656 "ETH_XO")
			(pintype "passive")
		)
		(pad "2" smd rect
			(at 1.199 0.949 180)
			(size 1.3 1.1)
			(layers "F.Cu" "F.Mask" "F.Paste")
			(net 5 "GND")
			(pinfunction "SH")
			(pintype "passive")
		)
		(pad "3" smd rect
			(at 1.199 -0.85 180)
			(size 1.3 1.1)
			(layers "F.Cu" "F.Mask" "F.Paste")
			(net 657 "ETH_XI")
			(pintype "passive")
		)
		(pad "4" smd rect
			(at -1.101 -0.85 180)
			(size 1.3 1.1)
			(layers "F.Cu" "F.Mask" "F.Paste")
			(net 5 "GND")
			(pinfunction "SH")
			(pintype "passive")
		)
	)
	(footprint "antmicro-footprints:R_0402_1005Metric"
		(layer "F.Cu")
		(at 180.1885 117.001)
		(descr "Resistor SMD 0402")
		(tags "resistor SMD 0402")
		(property "Reference" "R49"
			(at 0.8115 0.399 0)
			(layer "F.SilkS")
			(effects
				(font
					(size 0.7 0.7)
					(thickness 0.15)
				)
				(justify left bottom)
			)
		)
		(property "Value" "R_0R_0402"
			(at 0 1.4 0)
			(layer "F.Fab")
			(effects
				(font
					(size 0.7 0.7)
					(thickness 0.15)
				)
				(justify left bottom)
			)
		)
		(property "Description" "0R resistor in 0402 package with unspecified tolerance"
			(at 0 0 0)
			(layer "F.Fab")
			(hide yes)
			(effects
				(font
					(size 1.27 1.27)
					(thickness 0.15)
				)
			)
		)
		(property "Author" "Antmicro"
			(at 0 0 0)
			(layer "F.Fab")
			(hide yes)
			(effects
				(font
					(size 1 1)
					(thickness 0.15)
				)
			)
		)
		(property "Current" "1A"
			(at 0 0 0)
			(layer "F.Fab")
			(hide yes)
			(effects
				(font
					(size 1 1)
					(thickness 0.15)
				)
			)
		)
		(property "License" "Apache-2.0"
			(at 0 0 0)
			(layer "F.Fab")
			(hide yes)
			(effects
				(font
					(size 1 1)
					(thickness 0.15)
				)
			)
		)
		(property "MPN" "ERJ2GE0R00X"
			(at 0 0 0)
			(layer "F.Fab")
			(hide yes)
			(effects
				(font
					(size 1 1)
					(thickness 0.15)
				)
			)
		)
		(property "Manufacturer" "Panasonic"
			(at 0 0 0)
			(layer "F.Fab")
			(hide yes)
			(effects
				(font
					(size 1 1)
					(thickness 0.15)
				)
			)
		)
		(property "Tolerance" ""
			(at 0 0 0)
			(layer "F.Fab")
			(hide yes)
			(effects
				(font
					(size 1 1)
					(thickness 0.15)
				)
			)
		)
		(property "Val" "0R"
			(at 0 0 0)
			(layer "F.Fab")
			(hide yes)
			(effects
				(font
					(size 1 1)
					(thickness 0.15)
				)
			)
		)
		(sheetname "Config SPI flash")
		(sheetfile "config-spi.kicad_sch")
		(attr smd)
		(fp_rect
			(start -0.93 -0.47)
			(end 0.93 0.47)
			(stroke
				(width 0.05)
				(type solid)
			)
			(fill no)
			(layer "F.CrtYd")
		)
		(fp_rect
			(start -0.5 -0.25)
			(end 0.5 0.25)
			(stroke
				(width 0.15)
				(type solid)
			)
			(fill no)
			(layer "F.Fab")
		)
		(pad "1" smd roundrect
			(at -0.485 0)
			(size 0.59 0.64)
			(layers "F.Cu" "F.Mask" "F.Paste")
			(roundrect_rratio 0.25)
			(net 257 "Net-(U5-*HOLD{slash}IO3)")
			(pintype "passive")
		)
		(pad "2" smd roundrect
			(at 0.485 0)
			(size 0.59 0.64)
			(layers "F.Cu" "F.Mask" "F.Paste")
			(roundrect_rratio 0.25)
			(net 18 "QSPI_DQ3")
			(pintype "passive")
		)
	)
	(footprint "antmicro-footprints:LED_0603_1608Metric_G"
		(layer "F.Cu")
		(at 192.186328 64.020008 180)
		(descr "LED SMD 0603 Green")
		(tags "LED SMD 0603 Green")
		(property "Reference" "D1"
			(at 0.786328 0.620008 180)
			(layer "F.SilkS")
			(effects
				(font
					(size 0.7 0.7)
					(thickness 0.15)
				)
				(justify left bottom)
			)
		)
		(property "Value" "LED_G_0603_KP-1608CGCK"
			(at 0 1.6 180)
			(layer "F.Fab")
			(effects
				(font
					(size 0.7 0.7)
					(thickness 0.15)
				)
				(justify left bottom)
			)
		)
		(property "Author" "Antmicro"
			(at 384.372656 128.040016 0)
			(layer "F.Fab")
			(hide yes)
			(effects
				(font
					(size 1 1)
					(thickness 0.15)
				)
			)
		)
		(property "License" "Apache-2.0"
			(at 384.372656 128.040016 0)
			(layer "F.Fab")
			(hide yes)
			(effects
				(font
					(size 1 1)
					(thickness 0.15)
				)
			)
		)
		(property "MPN" "KP-1608CGCK"
			(at 384.372656 128.040016 0)
			(layer "F.Fab")
			(hide yes)
			(effects
				(font
					(size 1 1)
					(thickness 0.15)
				)
			)
		)
		(property "Manufacturer" "Kingbright"
			(at 384.372656 128.040016 0)
			(layer "F.Fab")
			(hide yes)
			(effects
				(font
					(size 1 1)
					(thickness 0.15)
				)
			)
		)
		(sheetname "Interfaces")
		(sheetfile "interfaces.kicad_sch")
		(attr smd)
		(fp_line
			(start 1.25 0.32)
			(end 1.25 -0.32)
			(stroke
				(width 0.15)
				(type solid)
			)
			(layer "F.SilkS")
		)
		(fp_line
			(start 0.093672 -8e-06)
			(end 0.293672 -8e-06)
			(stroke
				(width 0.1)
				(type solid)
			)
			(layer "F.SilkS")
		)
		(fp_line
			(start 0.093672 -8e-06)
			(end -0.106328 0.199992)
			(stroke
				(width 0.1)
				(type solid)
			)
			(layer "F.SilkS")
		)
		(fp_line
			(start 0.093672 -0.200008)
			(end 0.093672 0.199992)
			(stroke
				(width 0.1)
				(type solid)
			)
			(layer "F.SilkS")
		)
		(fp_line
			(start -0.106328 -8e-06)
			(end -0.29 0)
			(stroke
				(width 0.1)
				(type solid)
			)
			(layer "F.SilkS")
		)
		(fp_line
			(start -0.106328 -0.200008)
			(end 0.093672 -8e-06)
			(stroke
				(width 0.1)
				(type solid)
			)
			(layer "F.SilkS")
		)
		(fp_line
			(start -0.106328 -0.200008)
			(end -0.106328 0.199992)
			(stroke
				(width 0.1)
				(type solid)
			)
			(layer "F.SilkS")
		)
		(fp_line
			(start -0.27 0.351)
			(end 0.27 0.351)
			(stroke
				(width 0.15)
				(type solid)
			)
			(layer "F.SilkS")
		)
		(fp_line
			(start -0.27 -0.35)
			(end 0.27 -0.35)
			(stroke
				(width 0.15)
				(type solid)
			)
			(layer "F.SilkS")
		)
		(fp_rect
			(start 1.26 0.65)
			(end -1.26 -0.65)
			(stroke
				(width 0.05)
				(type solid)
			)
			(fill no)
			(layer "F.CrtYd")
		)
		(fp_line
			(start 0.199 0.202)
			(end 0.199 -0.1)
			(stroke
				(width 0.15)
				(type solid)
			)
			(layer "F.Fab")
		)
		(fp_line
			(start 0.199 0)
			(end 0.597 0)
			(stroke
				(width 0.15)
				(type solid)
			)
			(layer "F.Fab")
		)
		(fp_line
			(start 0.199 -0.2)
			(end 0.199 -0.1)
			(stroke
				(width 0.15)
				(type solid)
			)
			(layer "F.Fab")
		)
		(fp_line
			(start 0.101 0)
			(end -0.201 -0.2)
			(stroke
				(width 0.15)
				(type solid)
			)
			(layer "F.Fab")
		)
		(fp_line
			(start -0.201 0.202)
			(end 0.101 0)
			(stroke
				(width 0.15)
				(type solid)
			)
			(layer "F.Fab")
		)
		(fp_line
			(start -0.201 0)
			(end -0.201 0.202)
			(stroke
				(width 0.15)
				(type solid)
			)
			(layer "F.Fab")
		)
		(fp_line
			(start -0.201 -0.2)
			(end -0.201 0)
			(stroke
				(width 0.15)
				(type solid)
			)
			(layer "F.Fab")
		)
		(fp_line
			(start -0.599 0)
			(end -0.201 0)
			(stroke
				(width 0.15)
				(type solid)
			)
			(layer "F.Fab")
		)
		(fp_rect
			(start -0.848 -0.4)
			(end 0.85 0.402)
			(stroke
				(width 0.15)
				(type solid)
			)
			(fill no)
			(layer "F.Fab")
		)
		(pad "1" smd rect
			(at -0.75 0)
			(size 0.8 0.8)
			(layers "F.Cu" "F.Mask" "F.Paste")
			(net 459 "3V3_SYS")
			(pinfunction "1")
			(pintype "passive")
		)
		(pad "2" smd rect
			(at 0.75 0)
			(size 0.8 0.8)
			(layers "F.Cu" "F.Mask" "F.Paste")
			(net 206 "Net-(D1-Pad2)")
			(pinfunction "2")
			(pintype "passive")
		)
	)
	(footprint "antmicro-footprints:LED_0603_1608Metric_G"
		(layer "F.Cu")
		(at 196.386328 64.020008 180)
		(descr "LED SMD 0603 Green")
		(tags "LED SMD 0603 Green")
		(property "Reference" "D3"
			(at 0.786328 0.620008 180)
			(layer "F.SilkS")
			(effects
				(font
					(size 0.7 0.7)
					(thickness 0.15)
				)
				(justify left bottom)
			)
		)
		(property "Value" "LED_G_0603_KP-1608CGCK"
			(at 0 1.6 180)
			(layer "F.Fab")
			(effects
				(font
					(size 0.7 0.7)
					(thickness 0.15)
				)
				(justify left bottom)
			)
		)
		(property "Author" "Antmicro"
			(at 392.772656 128.040016 0)
			(layer "F.Fab")
			(hide yes)
			(effects
				(font
					(size 1 1)
					(thickness 0.15)
				)
			)
		)
		(property "License" "Apache-2.0"
			(at 392.772656 128.040016 0)
			(layer "F.Fab")
			(hide yes)
			(effects
				(font
					(size 1 1)
					(thickness 0.15)
				)
			)
		)
		(property "MPN" "KP-1608CGCK"
			(at 392.772656 128.040016 0)
			(layer "F.Fab")
			(hide yes)
			(effects
				(font
					(size 1 1)
					(thickness 0.15)
				)
			)
		)
		(property "Manufacturer" "Kingbright"
			(at 392.772656 128.040016 0)
			(layer "F.Fab")
			(hide yes)
			(effects
				(font
					(size 1 1)
					(thickness 0.15)
				)
			)
		)
		(sheetname "Interfaces")
		(sheetfile "interfaces.kicad_sch")
		(attr smd)
		(fp_line
			(start 1.25 0.32)
			(end 1.25 -0.32)
			(stroke
				(width 0.15)
				(type solid)
			)
			(layer "F.SilkS")
		)
		(fp_line
			(start 0.093672 -8e-06)
			(end 0.293672 -8e-06)
			(stroke
				(width 0.1)
				(type solid)
			)
			(layer "F.SilkS")
		)
		(fp_line
			(start 0.093672 -8e-06)
			(end -0.106328 0.199992)
			(stroke
				(width 0.1)
				(type solid)
			)
			(layer "F.SilkS")
		)
		(fp_line
			(start 0.093672 -0.200008)
			(end 0.093672 0.199992)
			(stroke
				(width 0.1)
				(type solid)
			)
			(layer "F.SilkS")
		)
		(fp_line
			(start -0.106328 -8e-06)
			(end -0.29 0)
			(stroke
				(width 0.1)
				(type solid)
			)
			(layer "F.SilkS")
		)
		(fp_line
			(start -0.106328 -0.200008)
			(end 0.093672 -8e-06)
			(stroke
				(width 0.1)
				(type solid)
			)
			(layer "F.SilkS")
		)
		(fp_line
			(start -0.106328 -0.200008)
			(end -0.106328 0.199992)
			(stroke
				(width 0.1)
				(type solid)
			)
			(layer "F.SilkS")
		)
		(fp_line
			(start -0.27 0.351)
			(end 0.27 0.351)
			(stroke
				(width 0.15)
				(type solid)
			)
			(layer "F.SilkS")
		)
		(fp_line
			(start -0.27 -0.35)
			(end 0.27 -0.35)
			(stroke
				(width 0.15)
				(type solid)
			)
			(layer "F.SilkS")
		)
		(fp_rect
			(start 1.26 0.65)
			(end -1.26 -0.65)
			(stroke
				(width 0.05)
				(type solid)
			)
			(fill no)
			(layer "F.CrtYd")
		)
		(fp_line
			(start 0.199 0.202)
			(end 0.199 -0.1)
			(stroke
				(width 0.15)
				(type solid)
			)
			(layer "F.Fab")
		)
		(fp_line
			(start 0.199 0)
			(end 0.597 0)
			(stroke
				(width 0.15)
				(type solid)
			)
			(layer "F.Fab")
		)
		(fp_line
			(start 0.199 -0.2)
			(end 0.199 -0.1)
			(stroke
				(width 0.15)
				(type solid)
			)
			(layer "F.Fab")
		)
		(fp_line
			(start 0.101 0)
			(end -0.201 -0.2)
			(stroke
				(width 0.15)
				(type solid)
			)
			(layer "F.Fab")
		)
		(fp_line
			(start -0.201 0.202)
			(end 0.101 0)
			(stroke
				(width 0.15)
				(type solid)
			)
			(layer "F.Fab")
		)
		(fp_line
			(start -0.201 0)
			(end -0.201 0.202)
			(stroke
				(width 0.15)
				(type solid)
			)
			(layer "F.Fab")
		)
		(fp_line
			(start -0.201 -0.2)
			(end -0.201 0)
			(stroke
				(width 0.15)
				(type solid)
			)
			(layer "F.Fab")
		)
		(fp_line
			(start -0.599 0)
			(end -0.201 0)
			(stroke
				(width 0.15)
				(type solid)
			)
			(layer "F.Fab")
		)
		(fp_rect
			(start -0.848 -0.4)
			(end 0.85 0.402)
			(stroke
				(width 0.15)
				(type solid)
			)
			(fill no)
			(layer "F.Fab")
		)
		(pad "1" smd rect
			(at -0.75 0)
			(size 0.8 0.8)
			(layers "F.Cu" "F.Mask" "F.Paste")
			(net 459 "3V3_SYS")
			(pinfunction "1")
			(pintype "passive")
		)
		(pad "2" smd rect
			(at 0.75 0)
			(size 0.8 0.8)
			(layers "F.Cu" "F.Mask" "F.Paste")
			(net 73 "Net-(D3-Pad2)")
			(pinfunction "2")
			(pintype "passive")
		)
	)
	(footprint "antmicro-footprints:LED_0603_1608Metric_G"
		(layer "F.Cu")
		(at 204.886328 64.020008 180)
		(descr "LED SMD 0603 Green")
		(tags "LED SMD 0603 Green")
		(property "Reference" "D5"
			(at 0.786328 0.620008 180)
			(layer "F.SilkS")
			(effects
				(font
					(size 0.7 0.7)
					(thickness 0.15)
				)
				(justify left bottom)
			)
		)
		(property "Value" "LED_G_0603_KP-1608CGCK"
			(at 0 1.6 180)
			(layer "F.Fab")
			(effects
				(font
					(size 0.7 0.7)
					(thickness 0.15)
				)
				(justify left bottom)
			)
		)
		(property "Author" "Antmicro"
			(at 409.772656 128.040016 0)
			(layer "F.Fab")
			(hide yes)
			(effects
				(font
					(size 1 1)
					(thickness 0.15)
				)
			)
		)
		(property "License" "Apache-2.0"
			(at 409.772656 128.040016 0)
			(layer "F.Fab")
			(hide yes)
			(effects
				(font
					(size 1 1)
					(thickness 0.15)
				)
			)
		)
		(property "MPN" "KP-1608CGCK"
			(at 409.772656 128.040016 0)
			(layer "F.Fab")
			(hide yes)
			(effects
				(font
					(size 1 1)
					(thickness 0.15)
				)
			)
		)
		(property "Manufacturer" "Kingbright"
			(at 409.772656 128.040016 0)
			(layer "F.Fab")
			(hide yes)
			(effects
				(font
					(size 1 1)
					(thickness 0.15)
				)
			)
		)
		(sheetname "Interfaces")
		(sheetfile "interfaces.kicad_sch")
		(attr smd)
		(fp_line
			(start 1.25 0.32)
			(end 1.25 -0.32)
			(stroke
				(width 0.15)
				(type solid)
			)
			(layer "F.SilkS")
		)
		(fp_line
			(start 0.093672 -8e-06)
			(end 0.293672 -8e-06)
			(stroke
				(width 0.1)
				(type solid)
			)
			(layer "F.SilkS")
		)
		(fp_line
			(start 0.093672 -8e-06)
			(end -0.106328 0.199992)
			(stroke
				(width 0.1)
				(type solid)
			)
			(layer "F.SilkS")
		)
		(fp_line
			(start 0.093672 -0.200008)
			(end 0.093672 0.199992)
			(stroke
				(width 0.1)
				(type solid)
			)
			(layer "F.SilkS")
		)
		(fp_line
			(start -0.106328 -8e-06)
			(end -0.29 0)
			(stroke
				(width 0.1)
				(type solid)
			)
			(layer "F.SilkS")
		)
		(fp_line
			(start -0.106328 -0.200008)
			(end 0.093672 -8e-06)
			(stroke
				(width 0.1)
				(type solid)
			)
			(layer "F.SilkS")
		)
		(fp_line
			(start -0.106328 -0.200008)
			(end -0.106328 0.199992)
			(stroke
				(width 0.1)
				(type solid)
			)
			(layer "F.SilkS")
		)
		(fp_line
			(start -0.27 0.351)
			(end 0.27 0.351)
			(stroke
				(width 0.15)
				(type solid)
			)
			(layer "F.SilkS")
		)
		(fp_line
			(start -0.27 -0.35)
			(end 0.27 -0.35)
			(stroke
				(width 0.15)
				(type solid)
			)
			(layer "F.SilkS")
		)
		(fp_rect
			(start 1.26 0.65)
			(end -1.26 -0.65)
			(stroke
				(width 0.05)
				(type solid)
			)
			(fill no)
			(layer "F.CrtYd")
		)
		(fp_line
			(start 0.199 0.202)
			(end 0.199 -0.1)
			(stroke
				(width 0.15)
				(type solid)
			)
			(layer "F.Fab")
		)
		(fp_line
			(start 0.199 0)
			(end 0.597 0)
			(stroke
				(width 0.15)
				(type solid)
			)
			(layer "F.Fab")
		)
		(fp_line
			(start 0.199 -0.2)
			(end 0.199 -0.1)
			(stroke
				(width 0.15)
				(type solid)
			)
			(layer "F.Fab")
		)
		(fp_line
			(start 0.101 0)
			(end -0.201 -0.2)
			(stroke
				(width 0.15)
				(type solid)
			)
			(layer "F.Fab")
		)
		(fp_line
			(start -0.201 0.202)
			(end 0.101 0)
			(stroke
				(width 0.15)
				(type solid)
			)
			(layer "F.Fab")
		)
		(fp_line
			(start -0.201 0)
			(end -0.201 0.202)
			(stroke
				(width 0.15)
				(type solid)
			)
			(layer "F.Fab")
		)
		(fp_line
			(start -0.201 -0.2)
			(end -0.201 0)
			(stroke
				(width 0.15)
				(type solid)
			)
			(layer "F.Fab")
		)
		(fp_line
			(start -0.599 0)
			(end -0.201 0)
			(stroke
				(width 0.15)
				(type solid)
			)
			(layer "F.Fab")
		)
		(fp_rect
			(start -0.848 -0.4)
			(end 0.85 0.402)
			(stroke
				(width 0.15)
				(type solid)
			)
			(fill no)
			(layer "F.Fab")
		)
		(pad "1" smd rect
			(at -0.75 0)
			(size 0.8 0.8)
			(layers "F.Cu" "F.Mask" "F.Paste")
			(net 459 "3V3_SYS")
			(pinfunction "1")
			(pintype "passive")
		)
		(pad "2" smd rect
			(at 0.75 0)
			(size 0.8 0.8)
			(layers "F.Cu" "F.Mask" "F.Paste")
			(net 52 "Net-(D5-Pad2)")
			(pinfunction "2")
			(pintype "passive")
		)
	)
	(footprint "antmicro-footprints:LED_0603_1608Metric_G"
		(layer "F.Cu")
		(at 208.486328 64.020008 180)
		(descr "LED SMD 0603 Green")
		(tags "LED SMD 0603 Green")
		(property "Reference" "D6"
			(at 0.786328 0.620008 180)
			(layer "F.SilkS")
			(effects
				(font
					(size 0.7 0.7)
					(thickness 0.15)
				)
				(justify left bottom)
			)
		)
		(property "Value" "LED_G_0603_KP-1608CGCK"
			(at 0 1.6 180)
			(layer "F.Fab")
			(effects
				(font
					(size 0.7 0.7)
					(thickness 0.15)
				)
				(justify left bottom)
			)
		)
		(property "Author" "Antmicro"
			(at 416.972656 128.040016 0)
			(layer "F.Fab")
			(hide yes)
			(effects
				(font
					(size 1 1)
					(thickness 0.15)
				)
			)
		)
		(property "License" "Apache-2.0"
			(at 416.972656 128.040016 0)
			(layer "F.Fab")
			(hide yes)
			(effects
				(font
					(size 1 1)
					(thickness 0.15)
				)
			)
		)
		(property "MPN" "KP-1608CGCK"
			(at 416.972656 128.040016 0)
			(layer "F.Fab")
			(hide yes)
			(effects
				(font
					(size 1 1)
					(thickness 0.15)
				)
			)
		)
		(property "Manufacturer" "Kingbright"
			(at 416.972656 128.040016 0)
			(layer "F.Fab")
			(hide yes)
			(effects
				(font
					(size 1 1)
					(thickness 0.15)
				)
			)
		)
		(sheetname "Interfaces")
		(sheetfile "interfaces.kicad_sch")
		(attr smd)
		(fp_line
			(start 1.25 0.32)
			(end 1.25 -0.32)
			(stroke
				(width 0.15)
				(type solid)
			)
			(layer "F.SilkS")
		)
		(fp_line
			(start 0.093672 -8e-06)
			(end 0.293672 -8e-06)
			(stroke
				(width 0.1)
				(type solid)
			)
			(layer "F.SilkS")
		)
		(fp_line
			(start 0.093672 -8e-06)
			(end -0.106328 0.199992)
			(stroke
				(width 0.1)
				(type solid)
			)
			(layer "F.SilkS")
		)
		(fp_line
			(start 0.093672 -0.200008)
			(end 0.093672 0.199992)
			(stroke
				(width 0.1)
				(type solid)
			)
			(layer "F.SilkS")
		)
		(fp_line
			(start -0.106328 -8e-06)
			(end -0.29 0)
			(stroke
				(width 0.1)
				(type solid)
			)
			(layer "F.SilkS")
		)
		(fp_line
			(start -0.106328 -0.200008)
			(end 0.093672 -8e-06)
			(stroke
				(width 0.1)
				(type solid)
			)
			(layer "F.SilkS")
		)
		(fp_line
			(start -0.106328 -0.200008)
			(end -0.106328 0.199992)
			(stroke
				(width 0.1)
				(type solid)
			)
			(layer "F.SilkS")
		)
		(fp_line
			(start -0.27 0.351)
			(end 0.27 0.351)
			(stroke
				(width 0.15)
				(type solid)
			)
			(layer "F.SilkS")
		)
		(fp_line
			(start -0.27 -0.35)
			(end 0.27 -0.35)
			(stroke
				(width 0.15)
				(type solid)
			)
			(layer "F.SilkS")
		)
		(fp_rect
			(start 1.26 0.65)
			(end -1.26 -0.65)
			(stroke
				(width 0.05)
				(type solid)
			)
			(fill no)
			(layer "F.CrtYd")
		)
		(fp_line
			(start 0.199 0.202)
			(end 0.199 -0.1)
			(stroke
				(width 0.15)
				(type solid)
			)
			(layer "F.Fab")
		)
		(fp_line
			(start 0.199 0)
			(end 0.597 0)
			(stroke
				(width 0.15)
				(type solid)
			)
			(layer "F.Fab")
		)
		(fp_line
			(start 0.199 -0.2)
			(end 0.199 -0.1)
			(stroke
				(width 0.15)
				(type solid)
			)
			(layer "F.Fab")
		)
		(fp_line
			(start 0.101 0)
			(end -0.201 -0.2)
			(stroke
				(width 0.15)
				(type solid)
			)
			(layer "F.Fab")
		)
		(fp_line
			(start -0.201 0.202)
			(end 0.101 0)
			(stroke
				(width 0.15)
				(type solid)
			)
			(layer "F.Fab")
		)
		(fp_line
			(start -0.201 0)
			(end -0.201 0.202)
			(stroke
				(width 0.15)
				(type solid)
			)
			(layer "F.Fab")
		)
		(fp_line
			(start -0.201 -0.2)
			(end -0.201 0)
			(stroke
				(width 0.15)
				(type solid)
			)
			(layer "F.Fab")
		)
		(fp_line
			(start -0.599 0)
			(end -0.201 0)
			(stroke
				(width 0.15)
				(type solid)
			)
			(layer "F.Fab")
		)
		(fp_rect
			(start -0.848 -0.4)
			(end 0.85 0.402)
			(stroke
				(width 0.15)
				(type solid)
			)
			(fill no)
			(layer "F.Fab")
		)
		(pad "1" smd rect
			(at -0.75 0)
			(size 0.8 0.8)
			(layers "F.Cu" "F.Mask" "F.Paste")
			(net 459 "3V3_SYS")
			(pinfunction "1")
			(pintype "passive")
		)
		(pad "2" smd rect
			(at 0.75 0)
			(size 0.8 0.8)
			(layers "F.Cu" "F.Mask" "F.Paste")
			(net 53 "Net-(D6-Pad2)")
			(pinfunction "2")
			(pintype "passive")
		)
	)
	(footprint "antmicro-footprints:R_0402_1005Metric"
		(layer "F.Cu")
		(at 190.736328 71.697157 -90)
		(descr "Resistor SMD 0402")
		(tags "resistor SMD 0402")
		(property "Reference" "R26"
			(at 1.102843 -1.263672 270)
			(layer "F.SilkS")
			(effects
				(font
					(size 0.7 0.7)
					(thickness 0.15)
				)
				(justify left bottom)
			)
		)
		(property "Value" "R_330R_0402"
			(at 0 1.4 270)
			(layer "F.Fab")
			(effects
				(font
					(size 0.7 0.7)
					(thickness 0.15)
				)
				(justify left bottom)
			)
		)
		(property "Description" "330R resistor in 0402 package with 1% tolerance"
			(at 0 0 270)
			(layer "F.Fab")
			(hide yes)
			(effects
				(font
					(size 1.27 1.27)
					(thickness 0.15)
				)
			)
		)
		(property "Author" "Antmicro"
			(at 119.039171 262.433485 0)
			(layer "F.Fab")
			(hide yes)
			(effects
				(font
					(size 1 1)
					(thickness 0.15)
				)
			)
		)
		(property "License" "Apache-2.0"
			(at 119.039171 262.433485 0)
			(layer "F.Fab")
			(hide yes)
			(effects
				(font
					(size 1 1)
					(thickness 0.15)
				)
			)
		)
		(property "MPN" "CR0402-FX-3300GLF"
			(at 119.039171 262.433485 0)
			(layer "F.Fab")
			(hide yes)
			(effects
				(font
					(size 1 1)
					(thickness 0.15)
				)
			)
		)
		(property "Manufacturer" "Bourns"
			(at 119.039171 262.433485 0)
			(layer "F.Fab")
			(hide yes)
			(effects
				(font
					(size 1 1)
					(thickness 0.15)
				)
			)
		)
		(property "Tolerance" "1%"
			(at 119.039171 262.433485 0)
			(layer "F.Fab")
			(hide yes)
			(effects
				(font
					(size 1 1)
					(thickness 0.15)
				)
			)
		)
		(property "Val" "330R"
			(at 119.039171 262.433485 0)
			(layer "F.Fab")
			(hide yes)
			(effects
				(font
					(size 1 1)
					(thickness 0.15)
				)
			)
		)
		(sheetname "Interfaces")
		(sheetfile "interfaces.kicad_sch")
		(attr smd)
		(fp_rect
			(start -0.93 -0.47)
			(end 0.93 0.47)
			(stroke
				(width 0.05)
				(type solid)
			)
			(fill no)
			(layer "F.CrtYd")
		)
		(fp_rect
			(start -0.5 -0.25)
			(end 0.5 0.25)
			(stroke
				(width 0.15)
				(type solid)
			)
			(fill no)
			(layer "F.Fab")
		)
		(pad "1" smd roundrect
			(at -0.485 0 270)
			(size 0.59 0.64)
			(layers "F.Cu" "F.Mask" "F.Paste")
			(roundrect_rratio 0.25)
			(net 206 "Net-(D1-Pad2)")
			(pintype "passive")
		)
		(pad "2" smd roundrect
			(at 0.485 0 270)
			(size 0.59 0.64)
			(layers "F.Cu" "F.Mask" "F.Paste")
			(roundrect_rratio 0.25)
			(net 209 "Net-(Q1-D)")
			(pintype "passive")
		)
	)
	(footprint "antmicro-footprints:R_0402_1005Metric"
		(layer "F.Cu")
		(at 198.736328 71.697157 -90)
		(descr "Resistor SMD 0402")
		(tags "resistor SMD 0402")
		(property "Reference" "R27"
			(at 1.102843 -1.263672 270)
			(layer "F.SilkS")
			(effects
				(font
					(size 0.7 0.7)
					(thickness 0.15)
				)
				(justify left bottom)
			)
		)
		(property "Value" "R_330R_0402"
			(at 0 1.4 270)
			(layer "F.Fab")
			(effects
				(font
					(size 0.7 0.7)
					(thickness 0.15)
				)
				(justify left bottom)
			)
		)
		(property "Description" "330R resistor in 0402 package with 1% tolerance"
			(at 0 0 270)
			(layer "F.Fab")
			(hide yes)
			(effects
				(font
					(size 1.27 1.27)
					(thickness 0.15)
				)
			)
		)
		(property "Author" "Antmicro"
			(at 127.039171 270.433485 0)
			(layer "F.Fab")
			(hide yes)
			(effects
				(font
					(size 1 1)
					(thickness 0.15)
				)
			)
		)
		(property "License" "Apache-2.0"
			(at 127.039171 270.433485 0)
			(layer "F.Fab")
			(hide yes)
			(effects
				(font
					(size 1 1)
					(thickness 0.15)
				)
			)
		)
		(property "MPN" "CR0402-FX-3300GLF"
			(at 127.039171 270.433485 0)
			(layer "F.Fab")
			(hide yes)
			(effects
				(font
					(size 1 1)
					(thickness 0.15)
				)
			)
		)
		(property "Manufacturer" "Bourns"
			(at 127.039171 270.433485 0)
			(layer "F.Fab")
			(hide yes)
			(effects
				(font
					(size 1 1)
					(thickness 0.15)
				)
			)
		)
		(property "Tolerance" "1%"
			(at 127.039171 270.433485 0)
			(layer "F.Fab")
			(hide yes)
			(effects
				(font
					(size 1 1)
					(thickness 0.15)
				)
			)
		)
		(property "Val" "330R"
			(at 127.039171 270.433485 0)
			(layer "F.Fab")
			(hide yes)
			(effects
				(font
					(size 1 1)
					(thickness 0.15)
				)
			)
		)
		(sheetname "Interfaces")
		(sheetfile "interfaces.kicad_sch")
		(attr smd)
		(fp_rect
			(start -0.93 -0.47)
			(end 0.93 0.47)
			(stroke
				(width 0.05)
				(type solid)
			)
			(fill no)
			(layer "F.CrtYd")
		)
		(fp_rect
			(start -0.5 -0.25)
			(end 0.5 0.25)
			(stroke
				(width 0.15)
				(type solid)
			)
			(fill no)
			(layer "F.Fab")
		)
		(pad "1" smd roundrect
			(at -0.485 0 270)
			(size 0.59 0.64)
			(layers "F.Cu" "F.Mask" "F.Paste")
			(roundrect_rratio 0.25)
			(net 72 "Net-(D2-Pad2)")
			(pintype "passive")
		)
		(pad "2" smd roundrect
			(at 0.485 0 270)
			(size 0.59 0.64)
			(layers "F.Cu" "F.Mask" "F.Paste")
			(roundrect_rratio 0.25)
			(net 211 "Net-(Q2-D)")
			(pintype "passive")
		)
	)
	(footprint "antmicro-footprints:R_0402_1005Metric"
		(layer "F.Cu")
		(at 194.736328 71.697157 -90)
		(descr "Resistor SMD 0402")
		(tags "resistor SMD 0402")
		(property "Reference" "R28"
			(at 1.102843 -1.263672 270)
			(layer "F.SilkS")
			(effects
				(font
					(size 0.7 0.7)
					(thickness 0.15)
				)
				(justify left bottom)
			)
		)
		(property "Value" "R_330R_0402"
			(at 0 1.4 270)
			(layer "F.Fab")
			(effects
				(font
					(size 0.7 0.7)
					(thickness 0.15)
				)
				(justify left bottom)
			)
		)
		(property "Description" "330R resistor in 0402 package with 1% tolerance"
			(at 0 0 270)
			(layer "F.Fab")
			(hide yes)
			(effects
				(font
					(size 1.27 1.27)
					(thickness 0.15)
				)
			)
		)
		(property "Author" "Antmicro"
			(at 123.039171 266.433485 0)
			(layer "F.Fab")
			(hide yes)
			(effects
				(font
					(size 1 1)
					(thickness 0.15)
				)
			)
		)
		(property "License" "Apache-2.0"
			(at 123.039171 266.433485 0)
			(layer "F.Fab")
			(hide yes)
			(effects
				(font
					(size 1 1)
					(thickness 0.15)
				)
			)
		)
		(property "MPN" "CR0402-FX-3300GLF"
			(at 123.039171 266.433485 0)
			(layer "F.Fab")
			(hide yes)
			(effects
				(font
					(size 1 1)
					(thickness 0.15)
				)
			)
		)
		(property "Manufacturer" "Bourns"
			(at 123.039171 266.433485 0)
			(layer "F.Fab")
			(hide yes)
			(effects
				(font
					(size 1 1)
					(thickness 0.15)
				)
			)
		)
		(property "Tolerance" "1%"
			(at 123.039171 266.433485 0)
			(layer "F.Fab")
			(hide yes)
			(effects
				(font
					(size 1 1)
					(thickness 0.15)
				)
			)
		)
		(property "Val" "330R"
			(at 123.039171 266.433485 0)
			(layer "F.Fab")
			(hide yes)
			(effects
				(font
					(size 1 1)
					(thickness 0.15)
				)
			)
		)
		(sheetname "Interfaces")
		(sheetfile "interfaces.kicad_sch")
		(attr smd)
		(fp_rect
			(start -0.93 -0.47)
			(end 0.93 0.47)
			(stroke
				(width 0.05)
				(type solid)
			)
			(fill no)
			(layer "F.CrtYd")
		)
		(fp_rect
			(start -0.5 -0.25)
			(end 0.5 0.25)
			(stroke
				(width 0.15)
				(type solid)
			)
			(fill no)
			(layer "F.Fab")
		)
		(pad "1" smd roundrect
			(at -0.485 0 270)
			(size 0.59 0.64)
			(layers "F.Cu" "F.Mask" "F.Paste")
			(roundrect_rratio 0.25)
			(net 73 "Net-(D3-Pad2)")
			(pintype "passive")
		)
		(pad "2" smd roundrect
			(at 0.485 0 270)
			(size 0.59 0.64)
			(layers "F.Cu" "F.Mask" "F.Paste")
			(roundrect_rratio 0.25)
			(net 228 "Net-(Q3-D)")
			(pintype "passive")
		)
	)
	(footprint "antmicro-footprints:R_0402_1005Metric"
		(layer "F.Cu")
		(at 202.736328 71.697157 -90)
		(descr "Resistor SMD 0402")
		(tags "resistor SMD 0402")
		(property "Reference" "R29"
			(at 1.102843 -1.263672 270)
			(layer "F.SilkS")
			(effects
				(font
					(size 0.7 0.7)
					(thickness 0.15)
				)
				(justify left bottom)
			)
		)
		(property "Value" "R_330R_0402"
			(at 0 1.4 270)
			(layer "F.Fab")
			(effects
				(font
					(size 0.7 0.7)
					(thickness 0.15)
				)
				(justify left bottom)
			)
		)
		(property "Description" "330R resistor in 0402 package with 1% tolerance"
			(at 0 0 270)
			(layer "F.Fab")
			(hide yes)
			(effects
				(font
					(size 1.27 1.27)
					(thickness 0.15)
				)
			)
		)
		(property "Author" "Antmicro"
			(at 131.039171 274.433485 0)
			(layer "F.Fab")
			(hide yes)
			(effects
				(font
					(size 1 1)
					(thickness 0.15)
				)
			)
		)
		(property "License" "Apache-2.0"
			(at 131.039171 274.433485 0)
			(layer "F.Fab")
			(hide yes)
			(effects
				(font
					(size 1 1)
					(thickness 0.15)
				)
			)
		)
		(property "MPN" "CR0402-FX-3300GLF"
			(at 131.039171 274.433485 0)
			(layer "F.Fab")
			(hide yes)
			(effects
				(font
					(size 1 1)
					(thickness 0.15)
				)
			)
		)
		(property "Manufacturer" "Bourns"
			(at 131.039171 274.433485 0)
			(layer "F.Fab")
			(hide yes)
			(effects
				(font
					(size 1 1)
					(thickness 0.15)
				)
			)
		)
		(property "Tolerance" "1%"
			(at 131.039171 274.433485 0)
			(layer "F.Fab")
			(hide yes)
			(effects
				(font
					(size 1 1)
					(thickness 0.15)
				)
			)
		)
		(property "Val" "330R"
			(at 131.039171 274.433485 0)
			(layer "F.Fab")
			(hide yes)
			(effects
				(font
					(size 1 1)
					(thickness 0.15)
				)
			)
		)
		(sheetname "Interfaces")
		(sheetfile "interfaces.kicad_sch")
		(attr smd)
		(fp_rect
			(start -0.93 -0.47)
			(end 0.93 0.47)
			(stroke
				(width 0.05)
				(type solid)
			)
			(fill no)
			(layer "F.CrtYd")
		)
		(fp_rect
			(start -0.5 -0.25)
			(end 0.5 0.25)
			(stroke
				(width 0.15)
				(type solid)
			)
			(fill no)
			(layer "F.Fab")
		)
		(pad "1" smd roundrect
			(at -0.485 0 270)
			(size 0.59 0.64)
			(layers "F.Cu" "F.Mask" "F.Paste")
			(roundrect_rratio 0.25)
			(net 52 "Net-(D5-Pad2)")
			(pintype "passive")
		)
		(pad "2" smd roundrect
			(at 0.485 0 270)
			(size 0.59 0.64)
			(layers "F.Cu" "F.Mask" "F.Paste")
			(roundrect_rratio 0.25)
			(net 230 "Net-(Q4-D)")
			(pintype "passive")
		)
	)
	(footprint "antmicro-footprints:R_0402_1005Metric"
		(layer "F.Cu")
		(at 206.736328 71.697157 -90)
		(descr "Resistor SMD 0402")
		(tags "resistor SMD 0402")
		(property "Reference" "R30"
			(at 1.102843 -1.263672 270)
			(layer "F.SilkS")
			(effects
				(font
					(size 0.7 0.7)
					(thickness 0.15)
				)
				(justify left bottom)
			)
		)
		(property "Value" "R_330R_0402"
			(at 0 1.4 270)
			(layer "F.Fab")
			(effects
				(font
					(size 0.7 0.7)
					(thickness 0.15)
				)
				(justify left bottom)
			)
		)
		(property "Description" "330R resistor in 0402 package with 1% tolerance"
			(at 0 0 270)
			(layer "F.Fab")
			(hide yes)
			(effects
				(font
					(size 1.27 1.27)
					(thickness 0.15)
				)
			)
		)
		(property "Author" "Antmicro"
			(at 135.039171 278.433485 0)
			(layer "F.Fab")
			(hide yes)
			(effects
				(font
					(size 1 1)
					(thickness 0.15)
				)
			)
		)
		(property "License" "Apache-2.0"
			(at 135.039171 278.433485 0)
			(layer "F.Fab")
			(hide yes)
			(effects
				(font
					(size 1 1)
					(thickness 0.15)
				)
			)
		)
		(property "MPN" "CR0402-FX-3300GLF"
			(at 135.039171 278.433485 0)
			(layer "F.Fab")
			(hide yes)
			(effects
				(font
					(size 1 1)
					(thickness 0.15)
				)
			)
		)
		(property "Manufacturer" "Bourns"
			(at 135.039171 278.433485 0)
			(layer "F.Fab")
			(hide yes)
			(effects
				(font
					(size 1 1)
					(thickness 0.15)
				)
			)
		)
		(property "Tolerance" "1%"
			(at 135.039171 278.433485 0)
			(layer "F.Fab")
			(hide yes)
			(effects
				(font
					(size 1 1)
					(thickness 0.15)
				)
			)
		)
		(property "Val" "330R"
			(at 135.039171 278.433485 0)
			(layer "F.Fab")
			(hide yes)
			(effects
				(font
					(size 1 1)
					(thickness 0.15)
				)
			)
		)
		(sheetname "Interfaces")
		(sheetfile "interfaces.kicad_sch")
		(attr smd)
		(fp_rect
			(start -0.93 -0.47)
			(end 0.93 0.47)
			(stroke
				(width 0.05)
				(type solid)
			)
			(fill no)
			(layer "F.CrtYd")
		)
		(fp_rect
			(start -0.5 -0.25)
			(end 0.5 0.25)
			(stroke
				(width 0.15)
				(type solid)
			)
			(fill no)
			(layer "F.Fab")
		)
		(pad "1" smd roundrect
			(at -0.485 0 270)
			(size 0.59 0.64)
			(layers "F.Cu" "F.Mask" "F.Paste")
			(roundrect_rratio 0.25)
			(net 53 "Net-(D6-Pad2)")
			(pintype "passive")
		)
		(pad "2" smd roundrect
			(at 0.485 0 270)
			(size 0.59 0.64)
			(layers "F.Cu" "F.Mask" "F.Paste")
			(roundrect_rratio 0.25)
			(net 231 "Net-(Q5-D)")
			(pintype "passive")
		)
	)
	(footprint "antmicro-footprints:SC70-3"
		(layer "F.Cu")
		(at 190.736328 74.697157 90)
		(property "Reference" "Q1"
			(at -0.602843 -1.336328 90)
			(layer "F.SilkS")
			(effects
				(font
					(size 0.7 0.7)
					(thickness 0.15)
				)
				(justify left bottom)
			)
		)
		(property "Value" "BSS138PW"
			(at 0 2.3 90)
			(layer "F.Fab")
			(effects
				(font
					(size 0.7 0.7)
					(thickness 0.15)
				)
				(justify left bottom)
			)
		)
		(property "Description" "60 V, 320 mA N-channel enhancement mode Trench MOSFET, SC-70-3 aka SOT-323 package"
			(at 0 0 90)
			(layer "F.Fab")
			(hide yes)
			(effects
				(font
					(size 1.27 1.27)
					(thickness 0.15)
				)
			)
		)
		(property "Author" "Antmicro"
			(at 265.433485 -116.039171 0)
			(layer "F.Fab")
			(hide yes)
			(effects
				(font
					(size 1 1)
					(thickness 0.15)
				)
			)
		)
		(property "License" "Apache-2.0"
			(at 265.433485 -116.039171 0)
			(layer "F.Fab")
			(hide yes)
			(effects
				(font
					(size 1 1)
					(thickness 0.15)
				)
			)
		)
		(property "MPN" "BSS138PW"
			(at 265.433485 -116.039171 0)
			(layer "F.Fab")
			(hide yes)
			(effects
				(font
					(size 1 1)
					(thickness 0.15)
				)
			)
		)
		(property "Manufacturer" "Nexperia"
			(at 265.433485 -116.039171 0)
			(layer "F.Fab")
			(hide yes)
			(effects
				(font
					(size 1 1)
					(thickness 0.15)
				)
			)
		)
		(sheetname "Interfaces")
		(sheetfile "interfaces.kicad_sch")
		(attr smd)
		(fp_line
			(start -0.3 -1)
			(end 0.627 -0.999)
			(stroke
				(width 0.15)
				(type solid)
			)
			(layer "F.SilkS")
		)
		(fp_line
			(start 0.627 -0.6)
			(end 0.627 -0.999)
			(stroke
				(width 0.15)
				(type solid)
			)
			(layer "F.SilkS")
		)
		(fp_line
			(start 0.627 0.6)
			(end 0.627 1.001)
			(stroke
				(width 0.15)
				(type solid)
			)
			(layer "F.SilkS")
		)
		(fp_line
			(start -0.3 1)
			(end 0.627 1.001)
			(stroke
				(width 0.15)
				(type solid)
			)
			(layer "F.SilkS")
		)
		(fp_line
			(start 0.9 -1.3)
			(end 0.9 -0.4)
			(stroke
				(width 0.05)
				(type solid)
			)
			(layer "F.CrtYd")
		)
		(fp_line
			(start -0.9 -1.3)
			(end 0.9 -1.3)
			(stroke
				(width 0.05)
				(type solid)
			)
			(layer "F.CrtYd")
		)
		(fp_line
			(start -0.9 -1.3)
			(end -0.9 -1)
			(stroke
				(width 0.05)
				(type solid)
			)
			(layer "F.CrtYd")
		)
		(fp_line
			(start -0.9 -1)
			(end -1.4 -1)
			(stroke
				(width 0.05)
				(type solid)
			)
			(layer "F.CrtYd")
		)
		(fp_line
			(start 1.4 -0.4)
			(end 1.4 0.4)
			(stroke
				(width 0.05)
				(type solid)
			)
			(layer "F.CrtYd")
		)
		(fp_line
			(start 0.9 -0.4)
			(end 1.4 -0.4)
			(stroke
				(width 0.05)
				(type solid)
			)
			(layer "F.CrtYd")
		)
		(fp_line
			(start 1.4 0.4)
			(end 0.9 0.4)
			(stroke
				(width 0.05)
				(type solid)
			)
			(layer "F.CrtYd")
		)
		(fp_line
			(start 0.9 0.4)
			(end 0.9 1.3)
			(stroke
				(width 0.05)
				(type solid)
			)
			(layer "F.CrtYd")
		)
		(fp_line
			(start -0.9 1)
			(end -1.4 1)
			(stroke
				(width 0.05)
				(type solid)
			)
			(layer "F.CrtYd")
		)
		(fp_line
			(start -1.4 1)
			(end -1.4 -1)
			(stroke
				(width 0.05)
				(type solid)
			)
			(layer "F.CrtYd")
		)
		(fp_line
			(start 0.9 1.3)
			(end -0.9 1.3)
			(stroke
				(width 0.05)
				(type solid)
			)
			(layer "F.CrtYd")
		)
		(fp_line
			(start -0.9 1.3)
			(end -0.9 1)
			(stroke
				(width 0.05)
				(type solid)
			)
			(layer "F.CrtYd")
		)
		(fp_rect
			(start -0.623 -0.999)
			(end 0.627 1.001)
			(stroke
				(width 0.15)
				(type solid)
			)
			(fill no)
			(layer "F.Fab")
		)
		(pad "1" smd rect
			(at -0.95 -0.65 180)
			(size 0.6 0.8)
			(layers "F.Cu" "F.Mask" "F.Paste")
			(net 56 "USR_LED1")
			(pinfunction "G")
			(pintype "bidirectional")
		)
		(pad "2" smd rect
			(at -0.95 0.65 180)
			(size 0.6 0.8)
			(layers "F.Cu" "F.Mask" "F.Paste")
			(net 5 "GND")
			(pinfunction "S")
			(pintype "bidirectional")
		)
		(pad "3" smd rect
			(at 0.95 0 180)
			(size 0.6 0.8)
			(layers "F.Cu" "F.Mask" "F.Paste")
			(net 209 "Net-(Q1-D)")
			(pinfunction "D")
			(pintype "bidirectional")
		)
	)
	(footprint "antmicro-footprints:SC70-3"
		(layer "F.Cu")
		(at 198.736328 74.697157 90)
		(property "Reference" "Q2"
			(at -0.602843 -1.336328 90)
			(layer "F.SilkS")
			(effects
				(font
					(size 0.7 0.7)
					(thickness 0.15)
				)
				(justify left bottom)
			)
		)
		(property "Value" "BSS138PW"
			(at 0 2.3 90)
			(layer "F.Fab")
			(effects
				(font
					(size 0.7 0.7)
					(thickness 0.15)
				)
				(justify left bottom)
			)
		)
		(property "Description" "60 V, 320 mA N-channel enhancement mode Trench MOSFET, SC-70-3 aka SOT-323 package"
			(at 0 0 90)
			(layer "F.Fab")
			(hide yes)
			(effects
				(font
					(size 1.27 1.27)
					(thickness 0.15)
				)
			)
		)
		(property "Author" "Antmicro"
			(at 273.433485 -124.039171 0)
			(layer "F.Fab")
			(hide yes)
			(effects
				(font
					(size 1 1)
					(thickness 0.15)
				)
			)
		)
		(property "License" "Apache-2.0"
			(at 273.433485 -124.039171 0)
			(layer "F.Fab")
			(hide yes)
			(effects
				(font
					(size 1 1)
					(thickness 0.15)
				)
			)
		)
		(property "MPN" "BSS138PW"
			(at 273.433485 -124.039171 0)
			(layer "F.Fab")
			(hide yes)
			(effects
				(font
					(size 1 1)
					(thickness 0.15)
				)
			)
		)
		(property "Manufacturer" "Nexperia"
			(at 273.433485 -124.039171 0)
			(layer "F.Fab")
			(hide yes)
			(effects
				(font
					(size 1 1)
					(thickness 0.15)
				)
			)
		)
		(sheetname "Interfaces")
		(sheetfile "interfaces.kicad_sch")
		(attr smd)
		(fp_line
			(start -0.3 -1)
			(end 0.627 -0.999)
			(stroke
				(width 0.15)
				(type solid)
			)
			(layer "F.SilkS")
		)
		(fp_line
			(start 0.627 -0.6)
			(end 0.627 -0.999)
			(stroke
				(width 0.15)
				(type solid)
			)
			(layer "F.SilkS")
		)
		(fp_line
			(start 0.627 0.6)
			(end 0.627 1.001)
			(stroke
				(width 0.15)
				(type solid)
			)
			(layer "F.SilkS")
		)
		(fp_line
			(start -0.3 1)
			(end 0.627 1.001)
			(stroke
				(width 0.15)
				(type solid)
			)
			(layer "F.SilkS")
		)
		(fp_line
			(start 0.9 -1.3)
			(end 0.9 -0.4)
			(stroke
				(width 0.05)
				(type solid)
			)
			(layer "F.CrtYd")
		)
		(fp_line
			(start -0.9 -1.3)
			(end 0.9 -1.3)
			(stroke
				(width 0.05)
				(type solid)
			)
			(layer "F.CrtYd")
		)
		(fp_line
			(start -0.9 -1.3)
			(end -0.9 -1)
			(stroke
				(width 0.05)
				(type solid)
			)
			(layer "F.CrtYd")
		)
		(fp_line
			(start -0.9 -1)
			(end -1.4 -1)
			(stroke
				(width 0.05)
				(type solid)
			)
			(layer "F.CrtYd")
		)
		(fp_line
			(start 1.4 -0.4)
			(end 1.4 0.4)
			(stroke
				(width 0.05)
				(type solid)
			)
			(layer "F.CrtYd")
		)
		(fp_line
			(start 0.9 -0.4)
			(end 1.4 -0.4)
			(stroke
				(width 0.05)
				(type solid)
			)
			(layer "F.CrtYd")
		)
		(fp_line
			(start 1.4 0.4)
			(end 0.9 0.4)
			(stroke
				(width 0.05)
				(type solid)
			)
			(layer "F.CrtYd")
		)
		(fp_line
			(start 0.9 0.4)
			(end 0.9 1.3)
			(stroke
				(width 0.05)
				(type solid)
			)
			(layer "F.CrtYd")
		)
		(fp_line
			(start -0.9 1)
			(end -1.4 1)
			(stroke
				(width 0.05)
				(type solid)
			)
			(layer "F.CrtYd")
		)
		(fp_line
			(start -1.4 1)
			(end -1.4 -1)
			(stroke
				(width 0.05)
				(type solid)
			)
			(layer "F.CrtYd")
		)
		(fp_line
			(start 0.9 1.3)
			(end -0.9 1.3)
			(stroke
				(width 0.05)
				(type solid)
			)
			(layer "F.CrtYd")
		)
		(fp_line
			(start -0.9 1.3)
			(end -0.9 1)
			(stroke
				(width 0.05)
				(type solid)
			)
			(layer "F.CrtYd")
		)
		(fp_rect
			(start -0.623 -0.999)
			(end 0.627 1.001)
			(stroke
				(width 0.15)
				(type solid)
			)
			(fill no)
			(layer "F.Fab")
		)
		(pad "1" smd rect
			(at -0.95 -0.65 180)
			(size 0.6 0.8)
			(layers "F.Cu" "F.Mask" "F.Paste")
			(net 57 "USR_LED3")
			(pinfunction "G")
			(pintype "bidirectional")
		)
		(pad "2" smd rect
			(at -0.95 0.65 180)
			(size 0.6 0.8)
			(layers "F.Cu" "F.Mask" "F.Paste")
			(net 5 "GND")
			(pinfunction "S")
			(pintype "bidirectional")
		)
		(pad "3" smd rect
			(at 0.95 0 180)
			(size 0.6 0.8)
			(layers "F.Cu" "F.Mask" "F.Paste")
			(net 211 "Net-(Q2-D)")
			(pinfunction "D")
			(pintype "bidirectional")
		)
	)
	(footprint "antmicro-footprints:SC70-3"
		(layer "F.Cu")
		(at 194.736328 74.697157 90)
		(property "Reference" "Q3"
			(at -0.602843 -1.336328 90)
			(layer "F.SilkS")
			(effects
				(font
					(size 0.7 0.7)
					(thickness 0.15)
				)
				(justify left bottom)
			)
		)
		(property "Value" "BSS138PW"
			(at 0 2.3 90)
			(layer "F.Fab")
			(effects
				(font
					(size 0.7 0.7)
					(thickness 0.15)
				)
				(justify left bottom)
			)
		)
		(property "Description" "60 V, 320 mA N-channel enhancement mode Trench MOSFET, SC-70-3 aka SOT-323 package"
			(at 0 0 90)
			(layer "F.Fab")
			(hide yes)
			(effects
				(font
					(size 1.27 1.27)
					(thickness 0.15)
				)
			)
		)
		(property "Author" "Antmicro"
			(at 269.433485 -120.039171 0)
			(layer "F.Fab")
			(hide yes)
			(effects
				(font
					(size 1 1)
					(thickness 0.15)
				)
			)
		)
		(property "License" "Apache-2.0"
			(at 269.433485 -120.039171 0)
			(layer "F.Fab")
			(hide yes)
			(effects
				(font
					(size 1 1)
					(thickness 0.15)
				)
			)
		)
		(property "MPN" "BSS138PW"
			(at 269.433485 -120.039171 0)
			(layer "F.Fab")
			(hide yes)
			(effects
				(font
					(size 1 1)
					(thickness 0.15)
				)
			)
		)
		(property "Manufacturer" "Nexperia"
			(at 269.433485 -120.039171 0)
			(layer "F.Fab")
			(hide yes)
			(effects
				(font
					(size 1 1)
					(thickness 0.15)
				)
			)
		)
		(sheetname "Interfaces")
		(sheetfile "interfaces.kicad_sch")
		(attr smd)
		(fp_line
			(start -0.3 -1)
			(end 0.627 -0.999)
			(stroke
				(width 0.15)
				(type solid)
			)
			(layer "F.SilkS")
		)
		(fp_line
			(start 0.627 -0.6)
			(end 0.627 -0.999)
			(stroke
				(width 0.15)
				(type solid)
			)
			(layer "F.SilkS")
		)
		(fp_line
			(start 0.627 0.6)
			(end 0.627 1.001)
			(stroke
				(width 0.15)
				(type solid)
			)
			(layer "F.SilkS")
		)
		(fp_line
			(start -0.3 1)
			(end 0.627 1.001)
			(stroke
				(width 0.15)
				(type solid)
			)
			(layer "F.SilkS")
		)
		(fp_line
			(start 0.9 -1.3)
			(end 0.9 -0.4)
			(stroke
				(width 0.05)
				(type solid)
			)
			(layer "F.CrtYd")
		)
		(fp_line
			(start -0.9 -1.3)
			(end 0.9 -1.3)
			(stroke
				(width 0.05)
				(type solid)
			)
			(layer "F.CrtYd")
		)
		(fp_line
			(start -0.9 -1.3)
			(end -0.9 -1)
			(stroke
				(width 0.05)
				(type solid)
			)
			(layer "F.CrtYd")
		)
		(fp_line
			(start -0.9 -1)
			(end -1.4 -1)
			(stroke
				(width 0.05)
				(type solid)
			)
			(layer "F.CrtYd")
		)
		(fp_line
			(start 1.4 -0.4)
			(end 1.4 0.4)
			(stroke
				(width 0.05)
				(type solid)
			)
			(layer "F.CrtYd")
		)
		(fp_line
			(start 0.9 -0.4)
			(end 1.4 -0.4)
			(stroke
				(width 0.05)
				(type solid)
			)
			(layer "F.CrtYd")
		)
		(fp_line
			(start 1.4 0.4)
			(end 0.9 0.4)
			(stroke
				(width 0.05)
				(type solid)
			)
			(layer "F.CrtYd")
		)
		(fp_line
			(start 0.9 0.4)
			(end 0.9 1.3)
			(stroke
				(width 0.05)
				(type solid)
			)
			(layer "F.CrtYd")
		)
		(fp_line
			(start -0.9 1)
			(end -1.4 1)
			(stroke
				(width 0.05)
				(type solid)
			)
			(layer "F.CrtYd")
		)
		(fp_line
			(start -1.4 1)
			(end -1.4 -1)
			(stroke
				(width 0.05)
				(type solid)
			)
			(layer "F.CrtYd")
		)
		(fp_line
			(start 0.9 1.3)
			(end -0.9 1.3)
			(stroke
				(width 0.05)
				(type solid)
			)
			(layer "F.CrtYd")
		)
		(fp_line
			(start -0.9 1.3)
			(end -0.9 1)
			(stroke
				(width 0.05)
				(type solid)
			)
			(layer "F.CrtYd")
		)
		(fp_rect
			(start -0.623 -0.999)
			(end 0.627 1.001)
			(stroke
				(width 0.15)
				(type solid)
			)
			(fill no)
			(layer "F.Fab")
		)
		(pad "1" smd rect
			(at -0.95 -0.65 180)
			(size 0.6 0.8)
			(layers "F.Cu" "F.Mask" "F.Paste")
			(net 59 "USR_LED2")
			(pinfunction "G")
			(pintype "bidirectional")
		)
		(pad "2" smd rect
			(at -0.95 0.65 180)
			(size 0.6 0.8)
			(layers "F.Cu" "F.Mask" "F.Paste")
			(net 5 "GND")
			(pinfunction "S")
			(pintype "bidirectional")
		)
		(pad "3" smd rect
			(at 0.95 0 180)
			(size 0.6 0.8)
			(layers "F.Cu" "F.Mask" "F.Paste")
			(net 228 "Net-(Q3-D)")
			(pinfunction "D")
			(pintype "bidirectional")
		)
	)
	(footprint "antmicro-footprints:SC70-3"
		(layer "F.Cu")
		(at 202.736328 74.697157 90)
		(property "Reference" "Q4"
			(at -0.602843 -1.336328 90)
			(layer "F.SilkS")
			(effects
				(font
					(size 0.7 0.7)
					(thickness 0.15)
				)
				(justify left bottom)
			)
		)
		(property "Value" "BSS138PW"
			(at 0 2.3 90)
			(layer "F.Fab")
			(effects
				(font
					(size 0.7 0.7)
					(thickness 0.15)
				)
				(justify left bottom)
			)
		)
		(property "Description" "60 V, 320 mA N-channel enhancement mode Trench MOSFET, SC-70-3 aka SOT-323 package"
			(at 0 0 90)
			(layer "F.Fab")
			(hide yes)
			(effects
				(font
					(size 1.27 1.27)
					(thickness 0.15)
				)
			)
		)
		(property "Author" "Antmicro"
			(at 277.433485 -128.039171 0)
			(layer "F.Fab")
			(hide yes)
			(effects
				(font
					(size 1 1)
					(thickness 0.15)
				)
			)
		)
		(property "License" "Apache-2.0"
			(at 277.433485 -128.039171 0)
			(layer "F.Fab")
			(hide yes)
			(effects
				(font
					(size 1 1)
					(thickness 0.15)
				)
			)
		)
		(property "MPN" "BSS138PW"
			(at 277.433485 -128.039171 0)
			(layer "F.Fab")
			(hide yes)
			(effects
				(font
					(size 1 1)
					(thickness 0.15)
				)
			)
		)
		(property "Manufacturer" "Nexperia"
			(at 277.433485 -128.039171 0)
			(layer "F.Fab")
			(hide yes)
			(effects
				(font
					(size 1 1)
					(thickness 0.15)
				)
			)
		)
		(sheetname "Interfaces")
		(sheetfile "interfaces.kicad_sch")
		(attr smd)
		(fp_line
			(start -0.3 -1)
			(end 0.627 -0.999)
			(stroke
				(width 0.15)
				(type solid)
			)
			(layer "F.SilkS")
		)
		(fp_line
			(start 0.627 -0.6)
			(end 0.627 -0.999)
			(stroke
				(width 0.15)
				(type solid)
			)
			(layer "F.SilkS")
		)
		(fp_line
			(start 0.627 0.6)
			(end 0.627 1.001)
			(stroke
				(width 0.15)
				(type solid)
			)
			(layer "F.SilkS")
		)
		(fp_line
			(start -0.3 1)
			(end 0.627 1.001)
			(stroke
				(width 0.15)
				(type solid)
			)
			(layer "F.SilkS")
		)
		(fp_line
			(start 0.9 -1.3)
			(end 0.9 -0.4)
			(stroke
				(width 0.05)
				(type solid)
			)
			(layer "F.CrtYd")
		)
		(fp_line
			(start -0.9 -1.3)
			(end 0.9 -1.3)
			(stroke
				(width 0.05)
				(type solid)
			)
			(layer "F.CrtYd")
		)
		(fp_line
			(start -0.9 -1.3)
			(end -0.9 -1)
			(stroke
				(width 0.05)
				(type solid)
			)
			(layer "F.CrtYd")
		)
		(fp_line
			(start -0.9 -1)
			(end -1.4 -1)
			(stroke
				(width 0.05)
				(type solid)
			)
			(layer "F.CrtYd")
		)
		(fp_line
			(start 1.4 -0.4)
			(end 1.4 0.4)
			(stroke
				(width 0.05)
				(type solid)
			)
			(layer "F.CrtYd")
		)
		(fp_line
			(start 0.9 -0.4)
			(end 1.4 -0.4)
			(stroke
				(width 0.05)
				(type solid)
			)
			(layer "F.CrtYd")
		)
		(fp_line
			(start 1.4 0.4)
			(end 0.9 0.4)
			(stroke
				(width 0.05)
				(type solid)
			)
			(layer "F.CrtYd")
		)
		(fp_line
			(start 0.9 0.4)
			(end 0.9 1.3)
			(stroke
				(width 0.05)
				(type solid)
			)
			(layer "F.CrtYd")
		)
		(fp_line
			(start -0.9 1)
			(end -1.4 1)
			(stroke
				(width 0.05)
				(type solid)
			)
			(layer "F.CrtYd")
		)
		(fp_line
			(start -1.4 1)
			(end -1.4 -1)
			(stroke
				(width 0.05)
				(type solid)
			)
			(layer "F.CrtYd")
		)
		(fp_line
			(start 0.9 1.3)
			(end -0.9 1.3)
			(stroke
				(width 0.05)
				(type solid)
			)
			(layer "F.CrtYd")
		)
		(fp_line
			(start -0.9 1.3)
			(end -0.9 1)
			(stroke
				(width 0.05)
				(type solid)
			)
			(layer "F.CrtYd")
		)
		(fp_rect
			(start -0.623 -0.999)
			(end 0.627 1.001)
			(stroke
				(width 0.15)
				(type solid)
			)
			(fill no)
			(layer "F.Fab")
		)
		(pad "1" smd rect
			(at -0.95 -0.65 180)
			(size 0.6 0.8)
			(layers "F.Cu" "F.Mask" "F.Paste")
			(net 61 "USR_LED4")
			(pinfunction "G")
			(pintype "bidirectional")
		)
		(pad "2" smd rect
			(at -0.95 0.65 180)
			(size 0.6 0.8)
			(layers "F.Cu" "F.Mask" "F.Paste")
			(net 5 "GND")
			(pinfunction "S")
			(pintype "bidirectional")
		)
		(pad "3" smd rect
			(at 0.95 0 180)
			(size 0.6 0.8)
			(layers "F.Cu" "F.Mask" "F.Paste")
			(net 230 "Net-(Q4-D)")
			(pinfunction "D")
			(pintype "bidirectional")
		)
	)
	(footprint "antmicro-footprints:SC70-3"
		(layer "F.Cu")
		(at 206.736328 74.697157 90)
		(property "Reference" "Q5"
			(at -0.602843 -1.336328 90)
			(layer "F.SilkS")
			(effects
				(font
					(size 0.7 0.7)
					(thickness 0.15)
				)
				(justify left bottom)
			)
		)
		(property "Value" "BSS138PW"
			(at 0 2.3 90)
			(layer "F.Fab")
			(effects
				(font
					(size 0.7 0.7)
					(thickness 0.15)
				)
				(justify left bottom)
			)
		)
		(property "Description" "60 V, 320 mA N-channel enhancement mode Trench MOSFET, SC-70-3 aka SOT-323 package"
			(at 0 0 90)
			(layer "F.Fab")
			(hide yes)
			(effects
				(font
					(size 1.27 1.27)
					(thickness 0.15)
				)
			)
		)
		(property "Author" "Antmicro"
			(at 281.433485 -132.039171 0)
			(layer "F.Fab")
			(hide yes)
			(effects
				(font
					(size 1 1)
					(thickness 0.15)
				)
			)
		)
		(property "License" "Apache-2.0"
			(at 281.433485 -132.039171 0)
			(layer "F.Fab")
			(hide yes)
			(effects
				(font
					(size 1 1)
					(thickness 0.15)
				)
			)
		)
		(property "MPN" "BSS138PW"
			(at 281.433485 -132.039171 0)
			(layer "F.Fab")
			(hide yes)
			(effects
				(font
					(size 1 1)
					(thickness 0.15)
				)
			)
		)
		(property "Manufacturer" "Nexperia"
			(at 281.433485 -132.039171 0)
			(layer "F.Fab")
			(hide yes)
			(effects
				(font
					(size 1 1)
					(thickness 0.15)
				)
			)
		)
		(sheetname "Interfaces")
		(sheetfile "interfaces.kicad_sch")
		(attr smd)
		(fp_line
			(start -0.3 -1)
			(end 0.627 -0.999)
			(stroke
				(width 0.15)
				(type solid)
			)
			(layer "F.SilkS")
		)
		(fp_line
			(start 0.627 -0.6)
			(end 0.627 -0.999)
			(stroke
				(width 0.15)
				(type solid)
			)
			(layer "F.SilkS")
		)
		(fp_line
			(start 0.627 0.6)
			(end 0.627 1.001)
			(stroke
				(width 0.15)
				(type solid)
			)
			(layer "F.SilkS")
		)
		(fp_line
			(start -0.3 1)
			(end 0.627 1.001)
			(stroke
				(width 0.15)
				(type solid)
			)
			(layer "F.SilkS")
		)
		(fp_line
			(start 0.9 -1.3)
			(end 0.9 -0.4)
			(stroke
				(width 0.05)
				(type solid)
			)
			(layer "F.CrtYd")
		)
		(fp_line
			(start -0.9 -1.3)
			(end 0.9 -1.3)
			(stroke
				(width 0.05)
				(type solid)
			)
			(layer "F.CrtYd")
		)
		(fp_line
			(start -0.9 -1.3)
			(end -0.9 -1)
			(stroke
				(width 0.05)
				(type solid)
			)
			(layer "F.CrtYd")
		)
		(fp_line
			(start -0.9 -1)
			(end -1.4 -1)
			(stroke
				(width 0.05)
				(type solid)
			)
			(layer "F.CrtYd")
		)
		(fp_line
			(start 1.4 -0.4)
			(end 1.4 0.4)
			(stroke
				(width 0.05)
				(type solid)
			)
			(layer "F.CrtYd")
		)
		(fp_line
			(start 0.9 -0.4)
			(end 1.4 -0.4)
			(stroke
				(width 0.05)
				(type solid)
			)
			(layer "F.CrtYd")
		)
		(fp_line
			(start 1.4 0.4)
			(end 0.9 0.4)
			(stroke
				(width 0.05)
				(type solid)
			)
			(layer "F.CrtYd")
		)
		(fp_line
			(start 0.9 0.4)
			(end 0.9 1.3)
			(stroke
				(width 0.05)
				(type solid)
			)
			(layer "F.CrtYd")
		)
		(fp_line
			(start -0.9 1)
			(end -1.4 1)
			(stroke
				(width 0.05)
				(type solid)
			)
			(layer "F.CrtYd")
		)
		(fp_line
			(start -1.4 1)
			(end -1.4 -1)
			(stroke
				(width 0.05)
				(type solid)
			)
			(layer "F.CrtYd")
		)
		(fp_line
			(start 0.9 1.3)
			(end -0.9 1.3)
			(stroke
				(width 0.05)
				(type solid)
			)
			(layer "F.CrtYd")
		)
		(fp_line
			(start -0.9 1.3)
			(end -0.9 1)
			(stroke
				(width 0.05)
				(type solid)
			)
			(layer "F.CrtYd")
		)
		(fp_rect
			(start -0.623 -0.999)
			(end 0.627 1.001)
			(stroke
				(width 0.15)
				(type solid)
			)
			(fill no)
			(layer "F.Fab")
		)
		(pad "1" smd rect
			(at -0.95 -0.65 180)
			(size 0.6 0.8)
			(layers "F.Cu" "F.Mask" "F.Paste")
			(net 63 "USR_LED5")
			(pinfunction "G")
			(pintype "bidirectional")
		)
		(pad "2" smd rect
			(at -0.95 0.65 180)
			(size 0.6 0.8)
			(layers "F.Cu" "F.Mask" "F.Paste")
			(net 5 "GND")
			(pinfunction "S")
			(pintype "bidirectional")
		)
		(pad "3" smd rect
			(at 0.95 0 180)
			(size 0.6 0.8)
			(layers "F.Cu" "F.Mask" "F.Paste")
			(net 231 "Net-(Q5-D)")
			(pinfunction "D")
			(pintype "bidirectional")
		)
	)
	(footprint "antmicro-footprints:SW_B3U-1000P_SMD"
		(layer "F.Cu")
		(at 192.136328 67.947157 90)
		(property "Reference" "USR_BTN1"
			(at 0 -1.8 90)
			(layer "F.SilkS")
			(effects
				(font
					(size 0.7 0.7)
					(thickness 0.15)
				)
				(justify left bottom)
			)
		)
		(property "Value" "SW_B3U-1000P"
			(at 0 2.5 90)
			(layer "F.Fab")
			(effects
				(font
					(size 0.7 0.7)
					(thickness 0.15)
				)
				(justify left bottom)
			)
		)
		(property "Description" "Tactile Switch, B3U, Top Actuated, Surface Mount, Round Button, 153 gf, 50mA at 12VDC"
			(at 0 0 90)
			(layer "F.Fab")
			(hide yes)
			(effects
				(font
					(size 1.27 1.27)
					(thickness 0.15)
				)
			)
		)
		(property "Author" "Antmicro"
			(at 260.083485 -124.189171 0)
			(layer "F.Fab")
			(hide yes)
			(effects
				(font
					(size 1 1)
					(thickness 0.15)
				)
			)
		)
		(property "License" "Apache-2.0"
			(at 260.083485 -124.189171 0)
			(layer "F.Fab")
			(hide yes)
			(effects
				(font
					(size 1 1)
					(thickness 0.15)
				)
			)
		)
		(property "MPN" "B3U-1000P"
			(at 260.083485 -124.189171 0)
			(layer "F.Fab")
			(hide yes)
			(effects
				(font
					(size 1 1)
					(thickness 0.15)
				)
			)
		)
		(property "Manufacturer" "Omron"
			(at 260.083485 -124.189171 0)
			(layer "F.Fab")
			(hide yes)
			(effects
				(font
					(size 1 1)
					(thickness 0.15)
				)
			)
		)
		(sheetname "Interfaces")
		(sheetfile "interfaces.kicad_sch")
		(attr smd)
		(fp_line
			(start 1.6 -1.4)
			(end 1.1 -1.4)
			(stroke
				(width 0.15)
				(type solid)
			)
			(layer "F.SilkS")
		)
		(fp_line
			(start 1.6 -1.4)
			(end 1.6 -0.95)
			(stroke
				(width 0.15)
				(type solid)
			)
			(layer "F.SilkS")
		)
		(fp_line
			(start -1.6 -1.4)
			(end -1.1 -1.4)
			(stroke
				(width 0.15)
				(type solid)
			)
			(layer "F.SilkS")
		)
		(fp_line
			(start -1.6 -1.4)
			(end -1.601 -0.95)
			(stroke
				(width 0.15)
				(type solid)
			)
			(layer "F.SilkS")
		)
		(fp_line
			(start -1.601 -0.95)
			(end -2 -0.95)
			(stroke
				(width 0.15)
				(type solid)
			)
			(layer "F.SilkS")
		)
		(fp_line
			(start 1.6 1.4)
			(end 1.6 0.95)
			(stroke
				(width 0.15)
				(type solid)
			)
			(layer "F.SilkS")
		)
		(fp_line
			(start 1.6 1.4)
			(end 1.1 1.4)
			(stroke
				(width 0.15)
				(type solid)
			)
			(layer "F.SilkS")
		)
		(fp_line
			(start -1.6 1.4)
			(end -1.6 0.95)
			(stroke
				(width 0.15)
				(type solid)
			)
			(layer "F.SilkS")
		)
		(fp_line
			(start -1.6 1.4)
			(end -1.1 1.4)
			(stroke
				(width 0.15)
				(type solid)
			)
			(layer "F.SilkS")
		)
		(fp_rect
			(start -2.249 -1.55)
			(end 2.25 1.549)
			(stroke
				(width 0.05)
				(type solid)
			)
			(fill no)
			(layer "F.CrtYd")
		)
		(fp_rect
			(start -1.5 -1.29)
			(end 1.499 1.289)
			(stroke
				(width 0.15)
				(type solid)
			)
			(fill no)
			(layer "F.Fab")
		)
		(pad "1" smd rect
			(at -1.7 0 90)
			(size 0.8 1.7)
			(layers "F.Cu" "F.Mask" "F.Paste")
			(net 390 "USR_BTN1")
			(pinfunction "1")
			(pintype "passive")
		)
		(pad "2" smd rect
			(at 1.699 0 90)
			(size 0.8 1.7)
			(layers "F.Cu" "F.Mask" "F.Paste")
			(net 5 "GND")
			(pinfunction "2")
			(pintype "passive")
		)
	)
	(footprint "antmicro-footprints:SW_B3U-1000P_SMD"
		(layer "F.Cu")
		(at 196.536328 67.947157 90)
		(property "Reference" "USR_BTN2"
			(at 0 -1.8 90)
			(layer "F.SilkS")
			(effects
				(font
					(size 0.7 0.7)
					(thickness 0.15)
				)
				(justify left bottom)
			)
		)
		(property "Value" "SW_B3U-1000P"
			(at 0 2.5 90)
			(layer "F.Fab")
			(effects
				(font
					(size 0.7 0.7)
					(thickness 0.15)
				)
				(justify left bottom)
			)
		)
		(property "Description" "Tactile Switch, B3U, Top Actuated, Surface Mount, Round Button, 153 gf, 50mA at 12VDC"
			(at 0 0 90)
			(layer "F.Fab")
			(hide yes)
			(effects
				(font
					(size 1.27 1.27)
					(thickness 0.15)
				)
			)
		)
		(property "Author" "Antmicro"
			(at 264.483485 -128.589171 0)
			(layer "F.Fab")
			(hide yes)
			(effects
				(font
					(size 1 1)
					(thickness 0.15)
				)
			)
		)
		(property "License" "Apache-2.0"
			(at 264.483485 -128.589171 0)
			(layer "F.Fab")
			(hide yes)
			(effects
				(font
					(size 1 1)
					(thickness 0.15)
				)
			)
		)
		(property "MPN" "B3U-1000P"
			(at 264.483485 -128.589171 0)
			(layer "F.Fab")
			(hide yes)
			(effects
				(font
					(size 1 1)
					(thickness 0.15)
				)
			)
		)
		(property "Manufacturer" "Omron"
			(at 264.483485 -128.589171 0)
			(layer "F.Fab")
			(hide yes)
			(effects
				(font
					(size 1 1)
					(thickness 0.15)
				)
			)
		)
		(sheetname "Interfaces")
		(sheetfile "interfaces.kicad_sch")
		(attr smd)
		(fp_line
			(start 1.6 -1.4)
			(end 1.1 -1.4)
			(stroke
				(width 0.15)
				(type solid)
			)
			(layer "F.SilkS")
		)
		(fp_line
			(start 1.6 -1.4)
			(end 1.6 -0.95)
			(stroke
				(width 0.15)
				(type solid)
			)
			(layer "F.SilkS")
		)
		(fp_line
			(start -1.6 -1.4)
			(end -1.1 -1.4)
			(stroke
				(width 0.15)
				(type solid)
			)
			(layer "F.SilkS")
		)
		(fp_line
			(start -1.6 -1.4)
			(end -1.601 -0.95)
			(stroke
				(width 0.15)
				(type solid)
			)
			(layer "F.SilkS")
		)
		(fp_line
			(start -1.601 -0.95)
			(end -2 -0.95)
			(stroke
				(width 0.15)
				(type solid)
			)
			(layer "F.SilkS")
		)
		(fp_line
			(start 1.6 1.4)
			(end 1.6 0.95)
			(stroke
				(width 0.15)
				(type solid)
			)
			(layer "F.SilkS")
		)
		(fp_line
			(start 1.6 1.4)
			(end 1.1 1.4)
			(stroke
				(width 0.15)
				(type solid)
			)
			(layer "F.SilkS")
		)
		(fp_line
			(start -1.6 1.4)
			(end -1.6 0.95)
			(stroke
				(width 0.15)
				(type solid)
			)
			(layer "F.SilkS")
		)
		(fp_line
			(start -1.6 1.4)
			(end -1.1 1.4)
			(stroke
				(width 0.15)
				(type solid)
			)
			(layer "F.SilkS")
		)
		(fp_rect
			(start -2.249 -1.55)
			(end 2.25 1.549)
			(stroke
				(width 0.05)
				(type solid)
			)
			(fill no)
			(layer "F.CrtYd")
		)
		(fp_rect
			(start -1.5 -1.29)
			(end 1.499 1.289)
			(stroke
				(width 0.15)
				(type solid)
			)
			(fill no)
			(layer "F.Fab")
		)
		(pad "1" smd rect
			(at -1.7 0 90)
			(size 0.8 1.7)
			(layers "F.Cu" "F.Mask" "F.Paste")
			(net 391 "USR_BTN2")
			(pinfunction "1")
			(pintype "passive")
		)
		(pad "2" smd rect
			(at 1.699 0 90)
			(size 0.8 1.7)
			(layers "F.Cu" "F.Mask" "F.Paste")
			(net 5 "GND")
			(pinfunction "2")
			(pintype "passive")
		)
	)
	(footprint "antmicro-footprints:SW_B3U-1000P_SMD"
		(layer "F.Cu")
		(at 200.936328 67.947157 90)
		(property "Reference" "USR_BTN3"
			(at 0 -1.8 90)
			(layer "F.SilkS")
			(effects
				(font
					(size 0.7 0.7)
					(thickness 0.15)
				)
				(justify left bottom)
			)
		)
		(property "Value" "SW_B3U-1000P"
			(at 0 2.5 90)
			(layer "F.Fab")
			(effects
				(font
					(size 0.7 0.7)
					(thickness 0.15)
				)
				(justify left bottom)
			)
		)
		(property "Description" "Tactile Switch, B3U, Top Actuated, Surface Mount, Round Button, 153 gf, 50mA at 12VDC"
			(at 0 0 90)
			(layer "F.Fab")
			(hide yes)
			(effects
				(font
					(size 1.27 1.27)
					(thickness 0.15)
				)
			)
		)
		(property "Author" "Antmicro"
			(at 268.883485 -132.989171 0)
			(layer "F.Fab")
			(hide yes)
			(effects
				(font
					(size 1 1)
					(thickness 0.15)
				)
			)
		)
		(property "License" "Apache-2.0"
			(at 268.883485 -132.989171 0)
			(layer "F.Fab")
			(hide yes)
			(effects
				(font
					(size 1 1)
					(thickness 0.15)
				)
			)
		)
		(property "MPN" "B3U-1000P"
			(at 268.883485 -132.989171 0)
			(layer "F.Fab")
			(hide yes)
			(effects
				(font
					(size 1 1)
					(thickness 0.15)
				)
			)
		)
		(property "Manufacturer" "Omron"
			(at 268.883485 -132.989171 0)
			(layer "F.Fab")
			(hide yes)
			(effects
				(font
					(size 1 1)
					(thickness 0.15)
				)
			)
		)
		(sheetname "Interfaces")
		(sheetfile "interfaces.kicad_sch")
		(attr smd)
		(fp_line
			(start 1.6 -1.4)
			(end 1.1 -1.4)
			(stroke
				(width 0.15)
				(type solid)
			)
			(layer "F.SilkS")
		)
		(fp_line
			(start 1.6 -1.4)
			(end 1.6 -0.95)
			(stroke
				(width 0.15)
				(type solid)
			)
			(layer "F.SilkS")
		)
		(fp_line
			(start -1.6 -1.4)
			(end -1.1 -1.4)
			(stroke
				(width 0.15)
				(type solid)
			)
			(layer "F.SilkS")
		)
		(fp_line
			(start -1.6 -1.4)
			(end -1.601 -0.95)
			(stroke
				(width 0.15)
				(type solid)
			)
			(layer "F.SilkS")
		)
		(fp_line
			(start -1.601 -0.95)
			(end -2 -0.95)
			(stroke
				(width 0.15)
				(type solid)
			)
			(layer "F.SilkS")
		)
		(fp_line
			(start 1.6 1.4)
			(end 1.6 0.95)
			(stroke
				(width 0.15)
				(type solid)
			)
			(layer "F.SilkS")
		)
		(fp_line
			(start 1.6 1.4)
			(end 1.1 1.4)
			(stroke
				(width 0.15)
				(type solid)
			)
			(layer "F.SilkS")
		)
		(fp_line
			(start -1.6 1.4)
			(end -1.6 0.95)
			(stroke
				(width 0.15)
				(type solid)
			)
			(layer "F.SilkS")
		)
		(fp_line
			(start -1.6 1.4)
			(end -1.1 1.4)
			(stroke
				(width 0.15)
				(type solid)
			)
			(layer "F.SilkS")
		)
		(fp_rect
			(start -2.249 -1.55)
			(end 2.25 1.549)
			(stroke
				(width 0.05)
				(type solid)
			)
			(fill no)
			(layer "F.CrtYd")
		)
		(fp_rect
			(start -1.5 -1.29)
			(end 1.499 1.289)
			(stroke
				(width 0.15)
				(type solid)
			)
			(fill no)
			(layer "F.Fab")
		)
		(pad "1" smd rect
			(at -1.7 0 90)
			(size 0.8 1.7)
			(layers "F.Cu" "F.Mask" "F.Paste")
			(net 392 "USR_BTN3")
			(pinfunction "1")
			(pintype "passive")
		)
		(pad "2" smd rect
			(at 1.699 0 90)
			(size 0.8 1.7)
			(layers "F.Cu" "F.Mask" "F.Paste")
			(net 5 "GND")
			(pinfunction "2")
			(pintype "passive")
		)
	)
	(footprint "antmicro-footprints:R_0402_1005Metric"
		(layer "F.Cu")
		(at 192.736328 71.697157 90)
		(descr "Resistor SMD 0402")
		(tags "resistor SMD 0402")
		(property "Reference" "R9"
			(at -1.102843 1.263672 90)
			(layer "F.SilkS")
			(effects
				(font
					(size 0.7 0.7)
					(thickness 0.15)
				)
				(justify left bottom)
			)
		)
		(property "Value" "R_4k7_0402"
			(at 0 1.4 90)
			(layer "F.Fab")
			(effects
				(font
					(size 0.7 0.7)
					(thickness 0.15)
				)
				(justify left bottom)
			)
		)
		(property "Description" "4k7 resistor in 0402 package with 1% tolerance"
			(at 0 0 90)
			(layer "F.Fab")
			(hide yes)
			(effects
				(font
					(size 1.27 1.27)
					(thickness 0.15)
				)
			)
		)
		(property "Author" "Antmicro"
			(at 264.433485 -121.039171 0)
			(layer "F.Fab")
			(hide yes)
			(effects
				(font
					(size 1 1)
					(thickness 0.15)
				)
			)
		)
		(property "License" "Apache-2.0"
			(at 264.433485 -121.039171 0)
			(layer "F.Fab")
			(hide yes)
			(effects
				(font
					(size 1 1)
					(thickness 0.15)
				)
			)
		)
		(property "MPN" "CR0402-FX-4701GLF"
			(at 264.433485 -121.039171 0)
			(layer "F.Fab")
			(hide yes)
			(effects
				(font
					(size 1 1)
					(thickness 0.15)
				)
			)
		)
		(property "Manufacturer" "Bourns"
			(at 264.433485 -121.039171 0)
			(layer "F.Fab")
			(hide yes)
			(effects
				(font
					(size 1 1)
					(thickness 0.15)
				)
			)
		)
		(property "Tolerance" "1%"
			(at 264.433485 -121.039171 0)
			(layer "F.Fab")
			(hide yes)
			(effects
				(font
					(size 1 1)
					(thickness 0.15)
				)
			)
		)
		(property "Val" "4k7"
			(at 264.433485 -121.039171 0)
			(layer "F.Fab")
			(hide yes)
			(effects
				(font
					(size 1 1)
					(thickness 0.15)
				)
			)
		)
		(sheetname "Interfaces")
		(sheetfile "interfaces.kicad_sch")
		(attr smd)
		(fp_rect
			(start -0.93 -0.47)
			(end 0.93 0.47)
			(stroke
				(width 0.05)
				(type solid)
			)
			(fill no)
			(layer "F.CrtYd")
		)
		(fp_rect
			(start -0.5 -0.25)
			(end 0.5 0.25)
			(stroke
				(width 0.15)
				(type solid)
			)
			(fill no)
			(layer "F.Fab")
		)
		(pad "1" smd roundrect
			(at -0.485 0 90)
			(size 0.59 0.64)
			(layers "F.Cu" "F.Mask" "F.Paste")
			(roundrect_rratio 0.25)
			(net 459 "3V3_SYS")
			(pintype "passive")
		)
		(pad "2" smd roundrect
			(at 0.485 0 90)
			(size 0.59 0.64)
			(layers "F.Cu" "F.Mask" "F.Paste")
			(roundrect_rratio 0.25)
			(net 390 "USR_BTN1")
			(pintype "passive")
		)
	)
	(footprint "antmicro-footprints:R_0402_1005Metric"
		(layer "F.Cu")
		(at 196.736328 71.697157 90)
		(descr "Resistor SMD 0402")
		(tags "resistor SMD 0402")
		(property "Reference" "R10"
			(at -1.102843 1.263672 90)
			(layer "F.SilkS")
			(effects
				(font
					(size 0.7 0.7)
					(thickness 0.15)
				)
				(justify left bottom)
			)
		)
		(property "Value" "R_4k7_0402"
			(at 0 1.4 90)
			(layer "F.Fab")
			(effects
				(font
					(size 0.7 0.7)
					(thickness 0.15)
				)
				(justify left bottom)
			)
		)
		(property "Description" "4k7 resistor in 0402 package with 1% tolerance"
			(at 0 0 90)
			(layer "F.Fab")
			(hide yes)
			(effects
				(font
					(size 1.27 1.27)
					(thickness 0.15)
				)
			)
		)
		(property "Author" "Antmicro"
			(at 268.433485 -125.039171 0)
			(layer "F.Fab")
			(hide yes)
			(effects
				(font
					(size 1 1)
					(thickness 0.15)
				)
			)
		)
		(property "License" "Apache-2.0"
			(at 268.433485 -125.039171 0)
			(layer "F.Fab")
			(hide yes)
			(effects
				(font
					(size 1 1)
					(thickness 0.15)
				)
			)
		)
		(property "MPN" "CR0402-FX-4701GLF"
			(at 268.433485 -125.039171 0)
			(layer "F.Fab")
			(hide yes)
			(effects
				(font
					(size 1 1)
					(thickness 0.15)
				)
			)
		)
		(property "Manufacturer" "Bourns"
			(at 268.433485 -125.039171 0)
			(layer "F.Fab")
			(hide yes)
			(effects
				(font
					(size 1 1)
					(thickness 0.15)
				)
			)
		)
		(property "Tolerance" "1%"
			(at 268.433485 -125.039171 0)
			(layer "F.Fab")
			(hide yes)
			(effects
				(font
					(size 1 1)
					(thickness 0.15)
				)
			)
		)
		(property "Val" "4k7"
			(at 268.433485 -125.039171 0)
			(layer "F.Fab")
			(hide yes)
			(effects
				(font
					(size 1 1)
					(thickness 0.15)
				)
			)
		)
		(sheetname "Interfaces")
		(sheetfile "interfaces.kicad_sch")
		(attr smd)
		(fp_rect
			(start -0.93 -0.47)
			(end 0.93 0.47)
			(stroke
				(width 0.05)
				(type solid)
			)
			(fill no)
			(layer "F.CrtYd")
		)
		(fp_rect
			(start -0.5 -0.25)
			(end 0.5 0.25)
			(stroke
				(width 0.15)
				(type solid)
			)
			(fill no)
			(layer "F.Fab")
		)
		(pad "1" smd roundrect
			(at -0.485 0 90)
			(size 0.59 0.64)
			(layers "F.Cu" "F.Mask" "F.Paste")
			(roundrect_rratio 0.25)
			(net 459 "3V3_SYS")
			(pintype "passive")
		)
		(pad "2" smd roundrect
			(at 0.485 0 90)
			(size 0.59 0.64)
			(layers "F.Cu" "F.Mask" "F.Paste")
			(roundrect_rratio 0.25)
			(net 391 "USR_BTN2")
			(pintype "passive")
		)
	)
	(footprint "antmicro-footprints:R_0402_1005Metric"
		(layer "F.Cu")
		(at 200.736328 71.697157 90)
		(descr "Resistor SMD 0402")
		(tags "resistor SMD 0402")
		(property "Reference" "R11"
			(at -1.102843 1.263672 90)
			(layer "F.SilkS")
			(effects
				(font
					(size 0.7 0.7)
					(thickness 0.15)
				)
				(justify left bottom)
			)
		)
		(property "Value" "R_4k7_0402"
			(at 0 1.4 90)
			(layer "F.Fab")
			(effects
				(font
					(size 0.7 0.7)
					(thickness 0.15)
				)
				(justify left bottom)
			)
		)
		(property "Description" "4k7 resistor in 0402 package with 1% tolerance"
			(at 0 0 90)
			(layer "F.Fab")
			(hide yes)
			(effects
				(font
					(size 1.27 1.27)
					(thickness 0.15)
				)
			)
		)
		(property "Author" "Antmicro"
			(at 272.433485 -129.039171 0)
			(layer "F.Fab")
			(hide yes)
			(effects
				(font
					(size 1 1)
					(thickness 0.15)
				)
			)
		)
		(property "License" "Apache-2.0"
			(at 272.433485 -129.039171 0)
			(layer "F.Fab")
			(hide yes)
			(effects
				(font
					(size 1 1)
					(thickness 0.15)
				)
			)
		)
		(property "MPN" "CR0402-FX-4701GLF"
			(at 272.433485 -129.039171 0)
			(layer "F.Fab")
			(hide yes)
			(effects
				(font
					(size 1 1)
					(thickness 0.15)
				)
			)
		)
		(property "Manufacturer" "Bourns"
			(at 272.433485 -129.039171 0)
			(layer "F.Fab")
			(hide yes)
			(effects
				(font
					(size 1 1)
					(thickness 0.15)
				)
			)
		)
		(property "Tolerance" "1%"
			(at 272.433485 -129.039171 0)
			(layer "F.Fab")
			(hide yes)
			(effects
				(font
					(size 1 1)
					(thickness 0.15)
				)
			)
		)
		(property "Val" "4k7"
			(at 272.433485 -129.039171 0)
			(layer "F.Fab")
			(hide yes)
			(effects
				(font
					(size 1 1)
					(thickness 0.15)
				)
			)
		)
		(sheetname "Interfaces")
		(sheetfile "interfaces.kicad_sch")
		(attr smd)
		(fp_rect
			(start -0.93 -0.47)
			(end 0.93 0.47)
			(stroke
				(width 0.05)
				(type solid)
			)
			(fill no)
			(layer "F.CrtYd")
		)
		(fp_rect
			(start -0.5 -0.25)
			(end 0.5 0.25)
			(stroke
				(width 0.15)
				(type solid)
			)
			(fill no)
			(layer "F.Fab")
		)
		(pad "1" smd roundrect
			(at -0.485 0 90)
			(size 0.59 0.64)
			(layers "F.Cu" "F.Mask" "F.Paste")
			(roundrect_rratio 0.25)
			(net 459 "3V3_SYS")
			(pintype "passive")
		)
		(pad "2" smd roundrect
			(at 0.485 0 90)
			(size 0.59 0.64)
			(layers "F.Cu" "F.Mask" "F.Paste")
			(roundrect_rratio 0.25)
			(net 392 "USR_BTN3")
			(pintype "passive")
		)
	)
	(footprint "antmicro-footprints:R_0402_1005Metric"
		(layer "F.Cu")
		(at 204.736328 71.697157 90)
		(descr "Resistor SMD 0402")
		(tags "resistor SMD 0402")
		(property "Reference" "R12"
			(at -1.102843 1.263672 90)
			(layer "F.SilkS")
			(effects
				(font
					(size 0.7 0.7)
					(thickness 0.15)
				)
				(justify left bottom)
			)
		)
		(property "Value" "R_4k7_0402"
			(at 0 1.4 90)
			(layer "F.Fab")
			(effects
				(font
					(size 0.7 0.7)
					(thickness 0.15)
				)
				(justify left bottom)
			)
		)
		(property "Description" "4k7 resistor in 0402 package with 1% tolerance"
			(at 0 0 90)
			(layer "F.Fab")
			(hide yes)
			(effects
				(font
					(size 1.27 1.27)
					(thickness 0.15)
				)
			)
		)
		(property "Author" "Antmicro"
			(at 276.433485 -133.039171 0)
			(layer "F.Fab")
			(hide yes)
			(effects
				(font
					(size 1 1)
					(thickness 0.15)
				)
			)
		)
		(property "License" "Apache-2.0"
			(at 276.433485 -133.039171 0)
			(layer "F.Fab")
			(hide yes)
			(effects
				(font
					(size 1 1)
					(thickness 0.15)
				)
			)
		)
		(property "MPN" "CR0402-FX-4701GLF"
			(at 276.433485 -133.039171 0)
			(layer "F.Fab")
			(hide yes)
			(effects
				(font
					(size 1 1)
					(thickness 0.15)
				)
			)
		)
		(property "Manufacturer" "Bourns"
			(at 276.433485 -133.039171 0)
			(layer "F.Fab")
			(hide yes)
			(effects
				(font
					(size 1 1)
					(thickness 0.15)
				)
			)
		)
		(property "Tolerance" "1%"
			(at 276.433485 -133.039171 0)
			(layer "F.Fab")
			(hide yes)
			(effects
				(font
					(size 1 1)
					(thickness 0.15)
				)
			)
		)
		(property "Val" "4k7"
			(at 276.433485 -133.039171 0)
			(layer "F.Fab")
			(hide yes)
			(effects
				(font
					(size 1 1)
					(thickness 0.15)
				)
			)
		)
		(sheetname "Interfaces")
		(sheetfile "interfaces.kicad_sch")
		(attr smd)
		(fp_rect
			(start -0.93 -0.47)
			(end 0.93 0.47)
			(stroke
				(width 0.05)
				(type solid)
			)
			(fill no)
			(layer "F.CrtYd")
		)
		(fp_rect
			(start -0.5 -0.25)
			(end 0.5 0.25)
			(stroke
				(width 0.15)
				(type solid)
			)
			(fill no)
			(layer "F.Fab")
		)
		(pad "1" smd roundrect
			(at -0.485 0 90)
			(size 0.59 0.64)
			(layers "F.Cu" "F.Mask" "F.Paste")
			(roundrect_rratio 0.25)
			(net 459 "3V3_SYS")
			(pintype "passive")
		)
		(pad "2" smd roundrect
			(at 0.485 0 90)
			(size 0.59 0.64)
			(layers "F.Cu" "F.Mask" "F.Paste")
			(roundrect_rratio 0.25)
			(net 436 "USR_BTN4")
			(pintype "passive")
		)
	)
	(footprint "antmicro-footprints:SW_B3U-1000P_SMD"
		(layer "F.Cu")
		(at 205.336328 67.997157 90)
		(property "Reference" "USR_BTN4"
			(at 0 -1.8 90)
			(layer "F.SilkS")
			(effects
				(font
					(size 0.7 0.7)
					(thickness 0.15)
				)
				(justify left bottom)
			)
		)
		(property "Value" "SW_B3U-1000P"
			(at 0 2.5 90)
			(layer "F.Fab")
			(effects
				(font
					(size 0.7 0.7)
					(thickness 0.15)
				)
				(justify left bottom)
			)
		)
		(property "Description" "Tactile Switch, B3U, Top Actuated, Surface Mount, Round Button, 153 gf, 50mA at 12VDC"
			(at 0 0 90)
			(layer "F.Fab")
			(hide yes)
			(effects
				(font
					(size 1.27 1.27)
					(thickness 0.15)
				)
			)
		)
		(property "Author" "Antmicro"
			(at 273.333485 -137.339171 0)
			(layer "F.Fab")
			(hide yes)
			(effects
				(font
					(size 1 1)
					(thickness 0.15)
				)
			)
		)
		(property "License" "Apache-2.0"
			(at 273.333485 -137.339171 0)
			(layer "F.Fab")
			(hide yes)
			(effects
				(font
					(size 1 1)
					(thickness 0.15)
				)
			)
		)
		(property "MPN" "B3U-1000P"
			(at 273.333485 -137.339171 0)
			(layer "F.Fab")
			(hide yes)
			(effects
				(font
					(size 1 1)
					(thickness 0.15)
				)
			)
		)
		(property "Manufacturer" "Omron"
			(at 273.333485 -137.339171 0)
			(layer "F.Fab")
			(hide yes)
			(effects
				(font
					(size 1 1)
					(thickness 0.15)
				)
			)
		)
		(sheetname "Interfaces")
		(sheetfile "interfaces.kicad_sch")
		(attr smd)
		(fp_line
			(start 1.6 -1.4)
			(end 1.1 -1.4)
			(stroke
				(width 0.15)
				(type solid)
			)
			(layer "F.SilkS")
		)
		(fp_line
			(start 1.6 -1.4)
			(end 1.6 -0.95)
			(stroke
				(width 0.15)
				(type solid)
			)
			(layer "F.SilkS")
		)
		(fp_line
			(start -1.6 -1.4)
			(end -1.1 -1.4)
			(stroke
				(width 0.15)
				(type solid)
			)
			(layer "F.SilkS")
		)
		(fp_line
			(start -1.6 -1.4)
			(end -1.601 -0.95)
			(stroke
				(width 0.15)
				(type solid)
			)
			(layer "F.SilkS")
		)
		(fp_line
			(start -1.601 -0.95)
			(end -2 -0.95)
			(stroke
				(width 0.15)
				(type solid)
			)
			(layer "F.SilkS")
		)
		(fp_line
			(start 1.6 1.4)
			(end 1.6 0.95)
			(stroke
				(width 0.15)
				(type solid)
			)
			(layer "F.SilkS")
		)
		(fp_line
			(start 1.6 1.4)
			(end 1.1 1.4)
			(stroke
				(width 0.15)
				(type solid)
			)
			(layer "F.SilkS")
		)
		(fp_line
			(start -1.6 1.4)
			(end -1.6 0.95)
			(stroke
				(width 0.15)
				(type solid)
			)
			(layer "F.SilkS")
		)
		(fp_line
			(start -1.6 1.4)
			(end -1.1 1.4)
			(stroke
				(width 0.15)
				(type solid)
			)
			(layer "F.SilkS")
		)
		(fp_rect
			(start -2.249 -1.55)
			(end 2.25 1.549)
			(stroke
				(width 0.05)
				(type solid)
			)
			(fill no)
			(layer "F.CrtYd")
		)
		(fp_rect
			(start -1.5 -1.29)
			(end 1.499 1.289)
			(stroke
				(width 0.15)
				(type solid)
			)
			(fill no)
			(layer "F.Fab")
		)
		(pad "1" smd rect
			(at -1.7 0 90)
			(size 0.8 1.7)
			(layers "F.Cu" "F.Mask" "F.Paste")
			(net 436 "USR_BTN4")
			(pinfunction "1")
			(pintype "passive")
		)
		(pad "2" smd rect
			(at 1.699 0 90)
			(size 0.8 1.7)
			(layers "F.Cu" "F.Mask" "F.Paste")
			(net 5 "GND")
			(pinfunction "2")
			(pintype "passive")
		)
	)
	(footprint "antmicro-footprints:LED_0603_1608Metric_G"
		(layer "F.Cu")
		(at 200.586328 64.020008 180)
		(descr "LED SMD 0603 Green")
		(tags "LED SMD 0603 Green")
		(property "Reference" "D2"
			(at 0.786328 0.620008 180)
			(layer "F.SilkS")
			(effects
				(font
					(size 0.7 0.7)
					(thickness 0.15)
				)
				(justify left bottom)
			)
		)
		(property "Value" "LED_G_0603_KP-1608CGCK"
			(at 0 1.6 180)
			(layer "F.Fab")
			(effects
				(font
					(size 0.7 0.7)
					(thickness 0.15)
				)
				(justify left bottom)
			)
		)
		(property "Author" "Antmicro"
			(at 401.172656 128.040016 0)
			(layer "F.Fab")
			(hide yes)
			(effects
				(font
					(size 1 1)
					(thickness 0.15)
				)
			)
		)
		(property "License" "Apache-2.0"
			(at 401.172656 128.040016 0)
			(layer "F.Fab")
			(hide yes)
			(effects
				(font
					(size 1 1)
					(thickness 0.15)
				)
			)
		)
		(property "MPN" "KP-1608CGCK"
			(at 401.172656 128.040016 0)
			(layer "F.Fab")
			(hide yes)
			(effects
				(font
					(size 1 1)
					(thickness 0.15)
				)
			)
		)
		(property "Manufacturer" "Kingbright"
			(at 401.172656 128.040016 0)
			(layer "F.Fab")
			(hide yes)
			(effects
				(font
					(size 1 1)
					(thickness 0.15)
				)
			)
		)
		(sheetname "Interfaces")
		(sheetfile "interfaces.kicad_sch")
		(attr smd)
		(fp_line
			(start 1.25 0.32)
			(end 1.25 -0.32)
			(stroke
				(width 0.15)
				(type solid)
			)
			(layer "F.SilkS")
		)
		(fp_line
			(start 0.093672 -8e-06)
			(end 0.293672 -8e-06)
			(stroke
				(width 0.1)
				(type solid)
			)
			(layer "F.SilkS")
		)
		(fp_line
			(start 0.093672 -8e-06)
			(end -0.106328 0.199992)
			(stroke
				(width 0.1)
				(type solid)
			)
			(layer "F.SilkS")
		)
		(fp_line
			(start 0.093672 -0.200008)
			(end 0.093672 0.199992)
			(stroke
				(width 0.1)
				(type solid)
			)
			(layer "F.SilkS")
		)
		(fp_line
			(start -0.106328 -8e-06)
			(end -0.29 0)
			(stroke
				(width 0.1)
				(type solid)
			)
			(layer "F.SilkS")
		)
		(fp_line
			(start -0.106328 -0.200008)
			(end 0.093672 -8e-06)
			(stroke
				(width 0.1)
				(type solid)
			)
			(layer "F.SilkS")
		)
		(fp_line
			(start -0.106328 -0.200008)
			(end -0.106328 0.199992)
			(stroke
				(width 0.1)
				(type solid)
			)
			(layer "F.SilkS")
		)
		(fp_line
			(start -0.27 0.351)
			(end 0.27 0.351)
			(stroke
				(width 0.15)
				(type solid)
			)
			(layer "F.SilkS")
		)
		(fp_line
			(start -0.27 -0.35)
			(end 0.27 -0.35)
			(stroke
				(width 0.15)
				(type solid)
			)
			(layer "F.SilkS")
		)
		(fp_rect
			(start 1.26 0.65)
			(end -1.26 -0.65)
			(stroke
				(width 0.05)
				(type solid)
			)
			(fill no)
			(layer "F.CrtYd")
		)
		(fp_line
			(start 0.199 0.202)
			(end 0.199 -0.1)
			(stroke
				(width 0.15)
				(type solid)
			)
			(layer "F.Fab")
		)
		(fp_line
			(start 0.199 0)
			(end 0.597 0)
			(stroke
				(width 0.15)
				(type solid)
			)
			(layer "F.Fab")
		)
		(fp_line
			(start 0.199 -0.2)
			(end 0.199 -0.1)
			(stroke
				(width 0.15)
				(type solid)
			)
			(layer "F.Fab")
		)
		(fp_line
			(start 0.101 0)
			(end -0.201 -0.2)
			(stroke
				(width 0.15)
				(type solid)
			)
			(layer "F.Fab")
		)
		(fp_line
			(start -0.201 0.202)
			(end 0.101 0)
			(stroke
				(width 0.15)
				(type solid)
			)
			(layer "F.Fab")
		)
		(fp_line
			(start -0.201 0)
			(end -0.201 0.202)
			(stroke
				(width 0.15)
				(type solid)
			)
			(layer "F.Fab")
		)
		(fp_line
			(start -0.201 -0.2)
			(end -0.201 0)
			(stroke
				(width 0.15)
				(type solid)
			)
			(layer "F.Fab")
		)
		(fp_line
			(start -0.599 0)
			(end -0.201 0)
			(stroke
				(width 0.15)
				(type solid)
			)
			(layer "F.Fab")
		)
		(fp_rect
			(start -0.848 -0.4)
			(end 0.85 0.402)
			(stroke
				(width 0.15)
				(type solid)
			)
			(fill no)
			(layer "F.Fab")
		)
		(pad "1" smd rect
			(at -0.75 0)
			(size 0.8 0.8)
			(layers "F.Cu" "F.Mask" "F.Paste")
			(net 459 "3V3_SYS")
			(pinfunction "1")
			(pintype "passive")
		)
		(pad "2" smd rect
			(at 0.75 0)
			(size 0.8 0.8)
			(layers "F.Cu" "F.Mask" "F.Paste")
			(net 72 "Net-(D2-Pad2)")
			(pinfunction "2")
			(pintype "passive")
		)
	)
	(footprint "antmicro-footprints:R_0402_1005Metric"
		(layer "F.Cu")
		(at 205.286328 79.320008 -90)
		(descr "Resistor SMD 0402")
		(tags "resistor SMD 0402")
		(property "Reference" "R62"
			(at 3.079992 -0.413672 270)
			(layer "F.SilkS")
			(effects
				(font
					(size 0.7 0.7)
					(thickness 0.15)
				)
				(justify left bottom)
			)
		)
		(property "Value" "R_0R_0402"
			(at 0 1.4 270)
			(layer "F.Fab")
			(effects
				(font
					(size 0.7 0.7)
					(thickness 0.15)
				)
				(justify left bottom)
			)
		)
		(property "Description" "0R resistor in 0402 package with unspecified tolerance"
			(at 0 0 270)
			(layer "F.Fab")
			(hide yes)
			(effects
				(font
					(size 1.27 1.27)
					(thickness 0.15)
				)
			)
		)
		(property "Author" "Antmicro"
			(at 125.96632 284.606336 0)
			(layer "F.Fab")
			(hide yes)
			(effects
				(font
					(size 1 1)
					(thickness 0.15)
				)
			)
		)
		(property "Current" "1A"
			(at 125.96632 284.606336 0)
			(layer "F.Fab")
			(hide yes)
			(effects
				(font
					(size 1 1)
					(thickness 0.15)
				)
			)
		)
		(property "License" "Apache-2.0"
			(at 125.96632 284.606336 0)
			(layer "F.Fab")
			(hide yes)
			(effects
				(font
					(size 1 1)
					(thickness 0.15)
				)
			)
		)
		(property "MPN" "ERJ2GE0R00X"
			(at 125.96632 284.606336 0)
			(layer "F.Fab")
			(hide yes)
			(effects
				(font
					(size 1 1)
					(thickness 0.15)
				)
			)
		)
		(property "Manufacturer" "Panasonic"
			(at 125.96632 284.606336 0)
			(layer "F.Fab")
			(hide yes)
			(effects
				(font
					(size 1 1)
					(thickness 0.15)
				)
			)
		)
		(property "Tolerance" ""
			(at 125.96632 284.606336 0)
			(layer "F.Fab")
			(hide yes)
			(effects
				(font
					(size 1 1)
					(thickness 0.15)
				)
			)
		)
		(property "Val" "0R"
			(at 125.96632 284.606336 0)
			(layer "F.Fab")
			(hide yes)
			(effects
				(font
					(size 1 1)
					(thickness 0.15)
				)
			)
		)
		(sheetname "Config SPI flash")
		(sheetfile "config-spi.kicad_sch")
		(attr smd)
		(fp_rect
			(start -0.93 -0.47)
			(end 0.93 0.47)
			(stroke
				(width 0.05)
				(type solid)
			)
			(fill no)
			(layer "F.CrtYd")
		)
		(fp_rect
			(start -0.5 -0.25)
			(end 0.5 0.25)
			(stroke
				(width 0.15)
				(type solid)
			)
			(fill no)
			(layer "F.Fab")
		)
		(pad "1" smd roundrect
			(at -0.485 0 270)
			(size 0.59 0.64)
			(layers "F.Cu" "F.Mask" "F.Paste")
			(roundrect_rratio 0.25)
			(net 19 "MODE0")
			(pintype "passive")
		)
		(pad "2" smd roundrect
			(at 0.485 0 270)
			(size 0.59 0.64)
			(layers "F.Cu" "F.Mask" "F.Paste")
			(roundrect_rratio 0.25)
			(net 459 "3V3_SYS")
			(pintype "passive")
		)
	)
	(footprint "antmicro-footprints:R_0402_1005Metric"
		(layer "F.Cu")
		(at 206.386328 79.320008 -90)
		(descr "Resistor SMD 0402")
		(tags "resistor SMD 0402")
		(property "Reference" "R63"
			(at 3.079992 -0.413672 270)
			(layer "F.SilkS")
			(effects
				(font
					(size 0.7 0.7)
					(thickness 0.15)
				)
				(justify left bottom)
			)
		)
		(property "Value" "R_0R_0402"
			(at 0 1.4 270)
			(layer "F.Fab")
			(effects
				(font
					(size 0.7 0.7)
					(thickness 0.15)
				)
				(justify left bottom)
			)
		)
		(property "Description" "0R resistor in 0402 package with unspecified tolerance"
			(at 0 0 270)
			(layer "F.Fab")
			(hide yes)
			(effects
				(font
					(size 1.27 1.27)
					(thickness 0.15)
				)
			)
		)
		(property "Author" "Antmicro"
			(at 127.06632 285.706336 0)
			(layer "F.Fab")
			(hide yes)
			(effects
				(font
					(size 1 1)
					(thickness 0.15)
				)
			)
		)
		(property "Current" "1A"
			(at 127.06632 285.706336 0)
			(layer "F.Fab")
			(hide yes)
			(effects
				(font
					(size 1 1)
					(thickness 0.15)
				)
			)
		)
		(property "License" "Apache-2.0"
			(at 127.06632 285.706336 0)
			(layer "F.Fab")
			(hide yes)
			(effects
				(font
					(size 1 1)
					(thickness 0.15)
				)
			)
		)
		(property "MPN" "ERJ2GE0R00X"
			(at 127.06632 285.706336 0)
			(layer "F.Fab")
			(hide yes)
			(effects
				(font
					(size 1 1)
					(thickness 0.15)
				)
			)
		)
		(property "Manufacturer" "Panasonic"
			(at 127.06632 285.706336 0)
			(layer "F.Fab")
			(hide yes)
			(effects
				(font
					(size 1 1)
					(thickness 0.15)
				)
			)
		)
		(property "Tolerance" ""
			(at 127.06632 285.706336 0)
			(layer "F.Fab")
			(hide yes)
			(effects
				(font
					(size 1 1)
					(thickness 0.15)
				)
			)
		)
		(property "Val" "0R"
			(at 127.06632 285.706336 0)
			(layer "F.Fab")
			(hide yes)
			(effects
				(font
					(size 1 1)
					(thickness 0.15)
				)
			)
		)
		(sheetname "Config SPI flash")
		(sheetfile "config-spi.kicad_sch")
		(attr exclude_from_pos_files exclude_from_bom dnp)
		(fp_rect
			(start -0.93 -0.47)
			(end 0.93 0.47)
			(stroke
				(width 0.05)
				(type solid)
			)
			(fill no)
			(layer "F.CrtYd")
		)
		(fp_rect
			(start -0.5 -0.25)
			(end 0.5 0.25)
			(stroke
				(width 0.15)
				(type solid)
			)
			(fill no)
			(layer "F.Fab")
		)
		(pad "1" smd roundrect
			(at -0.485 0 270)
			(size 0.59 0.64)
			(layers "F.Cu" "F.Mask" "F.Paste")
			(roundrect_rratio 0.25)
			(net 19 "MODE0")
			(pintype "passive")
		)
		(pad "2" smd roundrect
			(at 0.485 0 270)
			(size 0.59 0.64)
			(layers "F.Cu" "F.Mask" "F.Paste")
			(roundrect_rratio 0.25)
			(net 5 "GND")
			(pintype "passive")
		)
	)
	(footprint "antmicro-footprints:SC70-3"
		(layer "F.Cu")
		(at 199.686328 84.45)
		(property "Reference" "Q6"
			(at -0.786328 -1.35 0)
			(layer "F.SilkS")
			(effects
				(font
					(size 0.7 0.7)
					(thickness 0.15)
				)
				(justify left bottom)
			)
		)
		(property "Value" "BSS138PW"
			(at 0 2.3 0)
			(layer "F.Fab")
			(effects
				(font
					(size 0.7 0.7)
					(thickness 0.15)
				)
				(justify left bottom)
			)
		)
		(property "Description" "60 V, 320 mA N-channel enhancement mode Trench MOSFET, SC-70-3 aka SOT-323 package"
			(at 0 0 0)
			(layer "F.Fab")
			(hide yes)
			(effects
				(font
					(size 1.27 1.27)
					(thickness 0.15)
				)
			)
		)
		(property "Author" "Antmicro"
			(at 0 0 0)
			(layer "F.Fab")
			(hide yes)
			(effects
				(font
					(size 1 1)
					(thickness 0.15)
				)
			)
		)
		(property "License" "Apache-2.0"
			(at 0 0 0)
			(layer "F.Fab")
			(hide yes)
			(effects
				(font
					(size 1 1)
					(thickness 0.15)
				)
			)
		)
		(property "MPN" "BSS138PW"
			(at 0 0 0)
			(layer "F.Fab")
			(hide yes)
			(effects
				(font
					(size 1 1)
					(thickness 0.15)
				)
			)
		)
		(property "Manufacturer" "Nexperia"
			(at 0 0 0)
			(layer "F.Fab")
			(hide yes)
			(effects
				(font
					(size 1 1)
					(thickness 0.15)
				)
			)
		)
		(sheetname "Config SPI flash")
		(sheetfile "config-spi.kicad_sch")
		(attr smd)
		(fp_line
			(start -0.3 -1)
			(end 0.627 -0.999)
			(stroke
				(width 0.15)
				(type solid)
			)
			(layer "F.SilkS")
		)
		(fp_line
			(start -0.3 1)
			(end 0.627 1.001)
			(stroke
				(width 0.15)
				(type solid)
			)
			(layer "F.SilkS")
		)
		(fp_line
			(start 0.627 -0.6)
			(end 0.627 -0.999)
			(stroke
				(width 0.15)
				(type solid)
			)
			(layer "F.SilkS")
		)
		(fp_line
			(start 0.627 0.6)
			(end 0.627 1.001)
			(stroke
				(width 0.15)
				(type solid)
			)
			(layer "F.SilkS")
		)
		(fp_line
			(start -1.4 1)
			(end -1.4 -1)
			(stroke
				(width 0.05)
				(type solid)
			)
			(layer "F.CrtYd")
		)
		(fp_line
			(start -0.9 -1.3)
			(end -0.9 -1)
			(stroke
				(width 0.05)
				(type solid)
			)
			(layer "F.CrtYd")
		)
		(fp_line
			(start -0.9 -1.3)
			(end 0.9 -1.3)
			(stroke
				(width 0.05)
				(type solid)
			)
			(layer "F.CrtYd")
		)
		(fp_line
			(start -0.9 -1)
			(end -1.4 -1)
			(stroke
				(width 0.05)
				(type solid)
			)
			(layer "F.CrtYd")
		)
		(fp_line
			(start -0.9 1)
			(end -1.4 1)
			(stroke
				(width 0.05)
				(type solid)
			)
			(layer "F.CrtYd")
		)
		(fp_line
			(start -0.9 1.3)
			(end -0.9 1)
			(stroke
				(width 0.05)
				(type solid)
			)
			(layer "F.CrtYd")
		)
		(fp_line
			(start 0.9 -1.3)
			(end 0.9 -0.4)
			(stroke
				(width 0.05)
				(type solid)
			)
			(layer "F.CrtYd")
		)
		(fp_line
			(start 0.9 -0.4)
			(end 1.4 -0.4)
			(stroke
				(width 0.05)
				(type solid)
			)
			(layer "F.CrtYd")
		)
		(fp_line
			(start 0.9 0.4)
			(end 0.9 1.3)
			(stroke
				(width 0.05)
				(type solid)
			)
			(layer "F.CrtYd")
		)
		(fp_line
			(start 0.9 1.3)
			(end -0.9 1.3)
			(stroke
				(width 0.05)
				(type solid)
			)
			(layer "F.CrtYd")
		)
		(fp_line
			(start 1.4 -0.4)
			(end 1.4 0.4)
			(stroke
				(width 0.05)
				(type solid)
			)
			(layer "F.CrtYd")
		)
		(fp_line
			(start 1.4 0.4)
			(end 0.9 0.4)
			(stroke
				(width 0.05)
				(type solid)
			)
			(layer "F.CrtYd")
		)
		(fp_rect
			(start -0.623 -0.999)
			(end 0.627 1.001)
			(stroke
				(width 0.15)
				(type solid)
			)
			(fill no)
			(layer "F.Fab")
		)
		(pad "1" smd rect
			(at -0.95 -0.65 90)
			(size 0.6 0.8)
			(layers "F.Cu" "F.Mask" "F.Paste")
			(net 21 "DONE")
			(pinfunction "G")
			(pintype "bidirectional")
		)
		(pad "2" smd rect
			(at -0.95 0.65 90)
			(size 0.6 0.8)
			(layers "F.Cu" "F.Mask" "F.Paste")
			(net 5 "GND")
			(pinfunction "S")
			(pintype "bidirectional")
		)
		(pad "3" smd rect
			(at 0.95 0 90)
			(size 0.6 0.8)
			(layers "F.Cu" "F.Mask" "F.Paste")
			(net 232 "Net-(Q6-D)")
			(pinfunction "D")
			(pintype "bidirectional")
		)
	)
	(footprint "antmicro-footprints:C_0402_1005Metric"
		(layer "F.Cu")
		(at 205.486328 103.774306 90)
		(descr "Capacitor SMD 0402")
		(tags "capacitor SMD 0402")
		(property "Reference" "C105"
			(at -1.025694 2.413672 90)
			(layer "F.SilkS")
			(effects
				(font
					(size 0.7 0.7)
					(thickness 0.15)
				)
				(justify left bottom)
			)
		)
		(property "Value" "C_470n_0402"
			(at 0 1.4 90)
			(layer "F.Fab")
			(effects
				(font
					(size 0.7 0.7)
					(thickness 0.15)
				)
				(justify left bottom)
			)
		)
		(property "Description" " "
			(at 0 0 90)
			(layer "F.Fab")
			(hide yes)
			(effects
				(font
					(size 1.27 1.27)
					(thickness 0.15)
				)
			)
		)
		(property "Author" "Antmicro"
			(at 309.260634 -101.712022 0)
			(layer "F.Fab")
			(hide yes)
			(effects
				(font
					(size 1 1)
					(thickness 0.15)
				)
			)
		)
		(property "Dielectric" ""
			(at 309.260634 -101.712022 0)
			(layer "F.Fab")
			(hide yes)
			(effects
				(font
					(size 1 1)
					(thickness 0.15)
				)
			)
		)
		(property "License" "Apache-2.0"
			(at 309.260634 -101.712022 0)
			(layer "F.Fab")
			(hide yes)
			(effects
				(font
					(size 1 1)
					(thickness 0.15)
				)
			)
		)
		(property "MPN" "C1005X5R1E474M050BB"
			(at 309.260634 -101.712022 0)
			(layer "F.Fab")
			(hide yes)
			(effects
				(font
					(size 1 1)
					(thickness 0.15)
				)
			)
		)
		(property "Manufacturer" "TDK"
			(at 309.260634 -101.712022 0)
			(layer "F.Fab")
			(hide yes)
			(effects
				(font
					(size 1 1)
					(thickness 0.15)
				)
			)
		)
		(property "Val" "470n"
			(at 309.260634 -101.712022 0)
			(layer "F.Fab")
			(hide yes)
			(effects
				(font
					(size 1 1)
					(thickness 0.15)
				)
			)
		)
		(property "Voltage" ""
			(at 309.260634 -101.712022 0)
			(layer "F.Fab")
			(hide yes)
			(effects
				(font
					(size 1 1)
					(thickness 0.15)
				)
			)
		)
		(sheetname "Ethernet")
		(sheetfile "ethernet.kicad_sch")
		(attr smd)
		(fp_rect
			(start -0.94 -0.47)
			(end 0.94 0.47)
			(stroke
				(width 0.05)
				(type solid)
			)
			(fill no)
			(layer "F.CrtYd")
		)
		(fp_rect
			(start -0.499 -0.249)
			(end 0.499 0.249)
			(stroke
				(width 0.15)
				(type solid)
			)
			(fill no)
			(layer "F.Fab")
		)
		(pad "1" smd roundrect
			(at -0.484 0 90)
			(size 0.59 0.64)
			(layers "F.Cu" "F.Mask" "F.Paste")
			(roundrect_rratio 0.25)
			(net 459 "3V3_SYS")
			(pintype "passive")
		)
		(pad "2" smd roundrect
			(at 0.484 0 90)
			(size 0.59 0.64)
			(layers "F.Cu" "F.Mask" "F.Paste")
			(roundrect_rratio 0.25)
			(net 5 "GND")
			(pintype "passive")
		)
	)
	(footprint "antmicro-footprints:C_0402_1005Metric"
		(layer "F.Cu")
		(at 206.586328 103.774306 90)
		(descr "Capacitor SMD 0402")
		(tags "capacitor SMD 0402")
		(property "Reference" "C117"
			(at -1.025694 2.413672 90)
			(layer "F.SilkS")
			(effects
				(font
					(size 0.7 0.7)
					(thickness 0.15)
				)
				(justify left bottom)
			)
		)
		(property "Value" "C_10n_0402"
			(at 0 1.4 90)
			(layer "F.Fab")
			(effects
				(font
					(size 0.7 0.7)
					(thickness 0.15)
				)
				(justify left bottom)
			)
		)
		(property "Description" " "
			(at 0 0 90)
			(layer "F.Fab")
			(hide yes)
			(effects
				(font
					(size 1.27 1.27)
					(thickness 0.15)
				)
			)
		)
		(property "Author" "Antmicro"
			(at 310.360634 -102.812022 0)
			(layer "F.Fab")
			(hide yes)
			(effects
				(font
					(size 1 1)
					(thickness 0.15)
				)
			)
		)
		(property "Dielectric" "X7R"
			(at 310.360634 -102.812022 0)
			(layer "F.Fab")
			(hide yes)
			(effects
				(font
					(size 1 1)
					(thickness 0.15)
				)
			)
		)
		(property "License" "Apache-2.0"
			(at 310.360634 -102.812022 0)
			(layer "F.Fab")
			(hide yes)
			(effects
				(font
					(size 1 1)
					(thickness 0.15)
				)
			)
		)
		(property "MPN" "GRM155R71H103KA88D"
			(at 310.360634 -102.812022 0)
			(layer "F.Fab")
			(hide yes)
			(effects
				(font
					(size 1 1)
					(thickness 0.15)
				)
			)
		)
		(property "Manufacturer" "Murata"
			(at 310.360634 -102.812022 0)
			(layer "F.Fab")
			(hide yes)
			(effects
				(font
					(size 1 1)
					(thickness 0.15)
				)
			)
		)
		(property "Val" "10n"
			(at 310.360634 -102.812022 0)
			(layer "F.Fab")
			(hide yes)
			(effects
				(font
					(size 1 1)
					(thickness 0.15)
				)
			)
		)
		(property "Voltage" "50V"
			(at 310.360634 -102.812022 0)
			(layer "F.Fab")
			(hide yes)
			(effects
				(font
					(size 1 1)
					(thickness 0.15)
				)
			)
		)
		(sheetname "Ethernet")
		(sheetfile "ethernet.kicad_sch")
		(attr smd)
		(fp_rect
			(start -0.94 -0.47)
			(end 0.94 0.47)
			(stroke
				(width 0.05)
				(type solid)
			)
			(fill no)
			(layer "F.CrtYd")
		)
		(fp_rect
			(start -0.499 -0.249)
			(end 0.499 0.249)
			(stroke
				(width 0.15)
				(type solid)
			)
			(fill no)
			(layer "F.Fab")
		)
		(pad "1" smd roundrect
			(at -0.484 0 90)
			(size 0.59 0.64)
			(layers "F.Cu" "F.Mask" "F.Paste")
			(roundrect_rratio 0.25)
			(net 459 "3V3_SYS")
			(pintype "passive")
		)
		(pad "2" smd roundrect
			(at 0.484 0 90)
			(size 0.59 0.64)
			(layers "F.Cu" "F.Mask" "F.Paste")
			(roundrect_rratio 0.25)
			(net 5 "GND")
			(pintype "passive")
		)
	)
	(footprint "antmicro-footprints:QFN-56-1EP_8x8mm_P0.5mm"
		(layer "F.Cu")
		(at 140.75 107.849 90)
		(descr "QFN 56 Pin")
		(tags "QFN")
		(property "Reference" "U4"
			(at 0 -5.321 90)
			(layer "F.SilkS")
			(effects
				(font
					(size 0.7 0.7)
					(thickness 0.15)
				)
				(justify left bottom)
			)
		)
		(property "Value" "FT4232H_VQFN"
			(at 0 5.32 90)
			(layer "F.Fab")
			(effects
				(font
					(size 0.7 0.7)
					(thickness 0.15)
				)
				(justify left bottom)
			)
		)
		(property "Description" "Interface Bridges, USB to UART, MPSSE, 1.62 V, 1.98 V, VQFN, 56 Pins, -40 °C"
			(at 0 0 90)
			(layer "F.Fab")
			(hide yes)
			(effects
				(font
					(size 1.27 1.27)
					(thickness 0.15)
				)
			)
		)
		(property "Author" "Antmicro"
			(at 248.599 -32.901 0)
			(layer "F.Fab")
			(hide yes)
			(effects
				(font
					(size 1 1)
					(thickness 0.15)
				)
			)
		)
		(property "License" "Apache-2.0"
			(at 248.599 -32.901 0)
			(layer "F.Fab")
			(hide yes)
			(effects
				(font
					(size 1 1)
					(thickness 0.15)
				)
			)
		)
		(property "MPN" "FT4232H-56Q-REEL"
			(at 248.599 -32.901 0)
			(layer "F.Fab")
			(hide yes)
			(effects
				(font
					(size 1 1)
					(thickness 0.15)
				)
			)
		)
		(property "Manufacturer" "FTDI Chip"
			(at 248.599 -32.901 0)
			(layer "F.Fab")
			(hide yes)
			(effects
				(font
					(size 1 1)
					(thickness 0.15)
				)
			)
		)
		(sheetname "Interfaces")
		(sheetfile "interfaces.kicad_sch")
		(attr smd)
		(fp_line
			(start 4.11 -4.111)
			(end 4.11 -3.635)
			(stroke
				(width 0.15)
				(type solid)
			)
			(layer "F.SilkS")
		)
		(fp_line
			(start 3.634 -4.111)
			(end 4.11 -4.111)
			(stroke
				(width 0.15)
				(type solid)
			)
			(layer "F.SilkS")
		)
		(fp_line
			(start -3.635 -4.111)
			(end -4.111 -4.111)
			(stroke
				(width 0.15)
				(type solid)
			)
			(layer "F.SilkS")
		)
		(fp_line
			(start -4.111 -3.635)
			(end -4.111 -4.111)
			(stroke
				(width 0.15)
				(type solid)
			)
			(layer "F.SilkS")
		)
		(fp_line
			(start 4.11 4.11)
			(end 4.11 3.634)
			(stroke
				(width 0.15)
				(type solid)
			)
			(layer "F.SilkS")
		)
		(fp_line
			(start 3.634 4.11)
			(end 4.11 4.11)
			(stroke
				(width 0.15)
				(type solid)
			)
			(layer "F.SilkS")
		)
		(fp_line
			(start -3.635 4.11)
			(end -4.111 4.11)
			(stroke
				(width 0.15)
				(type solid)
			)
			(layer "F.SilkS")
		)
		(fp_line
			(start -4.111 4.11)
			(end -4.111 3.634)
			(stroke
				(width 0.15)
				(type solid)
			)
			(layer "F.SilkS")
		)
		(fp_circle
			(center -4.35 -3.6)
			(end -4.3 -3.6)
			(stroke
				(width 0.15)
				(type solid)
			)
			(fill yes)
			(layer "F.SilkS")
		)
		(fp_rect
			(start 4.4 4.4)
			(end -4.4 -4.4)
			(stroke
				(width 0.05)
				(type solid)
			)
			(fill no)
			(layer "F.CrtYd")
		)
		(fp_line
			(start -4 -3)
			(end -3 -4)
			(stroke
				(width 0.15)
				(type solid)
			)
			(layer "F.Fab")
		)
		(fp_rect
			(start 4 4)
			(end -4 -4)
			(stroke
				(width 0.15)
				(type solid)
			)
			(fill no)
			(layer "F.Fab")
		)
		(pad "" smd roundrect
			(at -2.101 -2.101 90)
			(size 1.13 1.13)
			(layers "F.Paste")
			(roundrect_rratio 0.221239)
		)
		(pad "" smd roundrect
			(at -2.101 -0.7 90)
			(size 1.13 1.13)
			(layers "F.Paste")
			(roundrect_rratio 0.221239)
		)
		(pad "" smd roundrect
			(at -2.101 0.699 90)
			(size 1.13 1.13)
			(layers "F.Paste")
			(roundrect_rratio 0.221239)
		)
		(pad "" smd roundrect
			(at -2.101 2.1 90)
			(size 1.13 1.13)
			(layers "F.Paste")
			(roundrect_rratio 0.221239)
		)
		(pad "" smd roundrect
			(at -0.7 -2.101 90)
			(size 1.13 1.13)
			(layers "F.Paste")
			(roundrect_rratio 0.221239)
		)
		(pad "" smd roundrect
			(at -0.7 -0.7 90)
			(size 1.13 1.13)
			(layers "F.Paste")
			(roundrect_rratio 0.221239)
		)
		(pad "" smd roundrect
			(at -0.7 0.699 90)
			(size 1.13 1.13)
			(layers "F.Paste")
			(roundrect_rratio 0.221239)
		)
		(pad "" smd roundrect
			(at -0.7 2.1 90)
			(size 1.13 1.13)
			(layers "F.Paste")
			(roundrect_rratio 0.221239)
		)
		(pad "" smd roundrect
			(at 0.699 -2.101 90)
			(size 1.13 1.13)
			(layers "F.Paste")
			(roundrect_rratio 0.221239)
		)
		(pad "" smd roundrect
			(at 0.699 -0.7 90)
			(size 1.13 1.13)
			(layers "F.Paste")
			(roundrect_rratio 0.221239)
		)
		(pad "" smd roundrect
			(at 0.699 0.699 90)
			(size 1.13 1.13)
			(layers "F.Paste")
			(roundrect_rratio 0.221239)
		)
		(pad "" smd roundrect
			(at 0.699 2.1 90)
			(size 1.13 1.13)
			(layers "F.Paste")
			(roundrect_rratio 0.221239)
		)
		(pad "" smd roundrect
			(at 2.1 -2.101 90)
			(size 1.13 1.13)
			(layers "F.Paste")
			(roundrect_rratio 0.221239)
		)
		(pad "" smd roundrect
			(at 2.1 -0.7 90)
			(size 1.13 1.13)
			(layers "F.Paste")
			(roundrect_rratio 0.221239)
		)
		(pad "" smd roundrect
			(at 2.1 0.699 90)
			(size 1.13 1.13)
			(layers "F.Paste")
			(roundrect_rratio 0.221239)
		)
		(pad "" smd roundrect
			(at 2.1 2.1 90)
			(size 1.13 1.13)
			(layers "F.Paste")
			(roundrect_rratio 0.221239)
		)
		(pad "1" smd roundrect
			(at -3.938 -3.25 90)
			(size 0.875 0.3)
			(layers "F.Cu" "F.Mask" "F.Paste")
			(roundrect_rratio 0.25)
			(net 549 "unconnected-(U4-EECS-Pad1)")
			(pinfunction "EECS")
			(pintype "bidirectional+no_connect")
		)
		(pad "2" smd roundrect
			(at -3.938 -2.75 90)
			(size 0.875 0.3)
			(layers "F.Cu" "F.Mask" "F.Paste")
			(roundrect_rratio 0.25)
			(net 2 "/Interfaces/1V8_FT")
			(pinfunction "V_{CORE}")
			(pintype "power_in")
		)
		(pad "3" smd roundrect
			(at -3.938 -2.25 90)
			(size 0.875 0.3)
			(layers "F.Cu" "F.Mask" "F.Paste")
			(roundrect_rratio 0.25)
			(net 3 "Net-(U4-OSCI)")
			(pinfunction "OSCI")
			(pintype "input")
		)
		(pad "4" smd roundrect
			(at -3.938 -1.75 90)
			(size 0.875 0.3)
			(layers "F.Cu" "F.Mask" "F.Paste")
			(roundrect_rratio 0.25)
			(net 4 "Net-(U4-OSCO)")
			(pinfunction "OSCO")
			(pintype "output")
		)
		(pad "5" smd roundrect
			(at -3.938 -1.25 90)
			(size 0.875 0.3)
			(layers "F.Cu" "F.Mask" "F.Paste")
			(roundrect_rratio 0.25)
			(net 653 "/Interfaces/VPHY")
			(pinfunction "V_{PHY}")
			(pintype "power_in")
		)
		(pad "6" smd roundrect
			(at -3.938 -0.75 90)
			(size 0.875 0.3)
			(layers "F.Cu" "F.Mask" "F.Paste")
			(roundrect_rratio 0.25)
			(net 239 "Net-(U4-REF)")
			(pinfunction "REF")
			(pintype "input")
		)
		(pad "7" smd roundrect
			(at -3.938 -0.25 90)
			(size 0.875 0.3)
			(layers "F.Cu" "F.Mask" "F.Paste")
			(roundrect_rratio 0.25)
			(net 7 "DBG_USB_N")
			(pinfunction "D-")
			(pintype "bidirectional")
		)
		(pad "8" smd roundrect
			(at -3.938 0.249 90)
			(size 0.875 0.3)
			(layers "F.Cu" "F.Mask" "F.Paste")
			(roundrect_rratio 0.25)
			(net 6 "DBG_USB_P")
			(pinfunction "D+")
			(pintype "bidirectional")
		)
		(pad "9" smd roundrect
			(at -3.938 0.749 90)
			(size 0.875 0.3)
			(layers "F.Cu" "F.Mask" "F.Paste")
			(roundrect_rratio 0.25)
			(net 652 "/Interfaces/VPLL")
			(pinfunction "V_{PLL}")
			(pintype "power_in")
		)
		(pad "10" smd roundrect
			(at -3.938 1.249 90)
			(size 0.875 0.3)
			(layers "F.Cu" "F.Mask" "F.Paste")
			(roundrect_rratio 0.25)
			(net 5 "GND")
			(pinfunction "TEST")
			(pintype "input")
		)
		(pad "11" smd roundrect
			(at -3.938 1.749 90)
			(size 0.875 0.3)
			(layers "F.Cu" "F.Mask" "F.Paste")
			(roundrect_rratio 0.25)
			(net 240 "Net-(U4-~{RESET})")
			(pinfunction "~{RESET}")
			(pintype "input")
		)
		(pad "12" smd roundrect
			(at -3.938 2.249 90)
			(size 0.875 0.3)
			(layers "F.Cu" "F.Mask" "F.Paste")
			(roundrect_rratio 0.25)
			(net 241 "Net-(U4-ADBUS0)")
			(pinfunction "ADBUS0")
			(pintype "bidirectional")
		)
		(pad "13" smd roundrect
			(at -3.938 2.749 90)
			(size 0.875 0.3)
			(layers "F.Cu" "F.Mask" "F.Paste")
			(roundrect_rratio 0.25)
			(net 242 "Net-(U4-ADBUS1)")
			(pinfunction "ADBUS1")
			(pintype "bidirectional")
		)
		(pad "14" smd roundrect
			(at -3.938 3.249 90)
			(size 0.875 0.3)
			(layers "F.Cu" "F.Mask" "F.Paste")
			(roundrect_rratio 0.25)
			(net 243 "Net-(U4-ADBUS2)")
			(pinfunction "ADBUS2")
			(pintype "bidirectional")
		)
		(pad "15" smd roundrect
			(at -3.25 3.937 180)
			(size 0.875 0.3)
			(layers "F.Cu" "F.Mask" "F.Paste")
			(roundrect_rratio 0.25)
			(net 245 "Net-(U4-ADBUS3)")
			(pinfunction "ADBUS3")
			(pintype "bidirectional")
		)
		(pad "16" smd roundrect
			(at -2.75 3.937 180)
			(size 0.875 0.3)
			(layers "F.Cu" "F.Mask" "F.Paste")
			(roundrect_rratio 0.25)
			(net 459 "3V3_SYS")
			(pinfunction "V_{CCIO}")
			(pintype "power_in")
		)
		(pad "17" smd roundrect
			(at -2.25 3.937 180)
			(size 0.875 0.3)
			(layers "F.Cu" "F.Mask" "F.Paste")
			(roundrect_rratio 0.25)
			(net 554 "unconnected-(U4-ADBUS4-Pad17)")
			(pinfunction "ADBUS4")
			(pintype "bidirectional+no_connect")
		)
		(pad "18" smd roundrect
			(at -1.75 3.937 180)
			(size 0.875 0.3)
			(layers "F.Cu" "F.Mask" "F.Paste")
			(roundrect_rratio 0.25)
			(net 265 "Net-(U4-ADBUS5)")
			(pinfunction "ADBUS5")
			(pintype "bidirectional")
		)
		(pad "19" smd roundrect
			(at -1.25 3.937 180)
			(size 0.875 0.3)
			(layers "F.Cu" "F.Mask" "F.Paste")
			(roundrect_rratio 0.25)
			(net 558 "unconnected-(U4-ADBUS6-Pad19)")
			(pinfunction "ADBUS6")
			(pintype "bidirectional+no_connect")
		)
		(pad "20" smd roundrect
			(at -0.75 3.937 180)
			(size 0.875 0.3)
			(layers "F.Cu" "F.Mask" "F.Paste")
			(roundrect_rratio 0.25)
			(net 559 "unconnected-(U4-ADBUS7-Pad20)")
			(pinfunction "ADBUS7")
			(pintype "bidirectional+no_connect")
		)
		(pad "21" smd roundrect
			(at -0.25 3.937 180)
			(size 0.875 0.3)
			(layers "F.Cu" "F.Mask" "F.Paste")
			(roundrect_rratio 0.25)
			(net 5 "GND")
			(pinfunction "GND")
			(pintype "power_in")
		)
		(pad "22" smd roundrect
			(at 0.249 3.937 180)
			(size 0.875 0.3)
			(layers "F.Cu" "F.Mask" "F.Paste")
			(roundrect_rratio 0.25)
			(net 246 "Net-(U4-BDBUS0)")
			(pinfunction "BDBUS0")
			(pintype "bidirectional")
		)
		(pad "23" smd roundrect
			(at 0.749 3.937 180)
			(size 0.875 0.3)
			(layers "F.Cu" "F.Mask" "F.Paste")
			(roundrect_rratio 0.25)
			(net 247 "Net-(U4-BDBUS1)")
			(pinfunction "BDBUS1")
			(pintype "bidirectional")
		)
		(pad "24" smd roundrect
			(at 1.249 3.937 180)
			(size 0.875 0.3)
			(layers "F.Cu" "F.Mask" "F.Paste")
			(roundrect_rratio 0.25)
			(net 248 "Net-(U4-BDBUS2)")
			(pinfunction "BDBUS2")
			(pintype "bidirectional")
		)
		(pad "25" smd roundrect
			(at 1.749 3.937 180)
			(size 0.875 0.3)
			(layers "F.Cu" "F.Mask" "F.Paste")
			(roundrect_rratio 0.25)
			(net 249 "Net-(U4-BDBUS3)")
			(pinfunction "BDBUS3")
			(pintype "bidirectional")
		)
		(pad "26" smd roundrect
			(at 2.249 3.937 180)
			(size 0.875 0.3)
			(layers "F.Cu" "F.Mask" "F.Paste")
			(roundrect_rratio 0.25)
			(net 560 "unconnected-(U4-BDBUS4-Pad26)")
			(pinfunction "BDBUS4")
			(pintype "bidirectional+no_connect")
		)
		(pad "27" smd roundrect
			(at 2.749 3.937 180)
			(size 0.875 0.3)
			(layers "F.Cu" "F.Mask" "F.Paste")
			(roundrect_rratio 0.25)
			(net 250 "Net-(U4-BDBUS5)")
			(pinfunction "BDBUS5")
			(pintype "bidirectional")
		)
		(pad "28" smd roundrect
			(at 3.249 3.937 180)
			(size 0.875 0.3)
			(layers "F.Cu" "F.Mask" "F.Paste")
			(roundrect_rratio 0.25)
			(net 561 "unconnected-(U4-BDBUS6-Pad28)")
			(pinfunction "BDBUS6")
			(pintype "bidirectional+no_connect")
		)
		(pad "29" smd roundrect
			(at 3.937 3.249 90)
			(size 0.875 0.3)
			(layers "F.Cu" "F.Mask" "F.Paste")
			(roundrect_rratio 0.25)
			(net 562 "unconnected-(U4-BDBUS7-Pad29)")
			(pinfunction "BDBUS7")
			(pintype "bidirectional+no_connect")
		)
		(pad "30" smd roundrect
			(at 3.937 2.749 90)
			(size 0.875 0.3)
			(layers "F.Cu" "F.Mask" "F.Paste")
			(roundrect_rratio 0.25)
			(net 563 "unconnected-(U4-~{SUSPEND}-Pad30)")
			(pinfunction "~{SUSPEND}")
			(pintype "output+no_connect")
		)
		(pad "31" smd roundrect
			(at 3.937 2.249 90)
			(size 0.875 0.3)
			(layers "F.Cu" "F.Mask" "F.Paste")
			(roundrect_rratio 0.25)
			(net 2 "/Interfaces/1V8_FT")
			(pinfunction "V_{CORE}")
			(pintype "passive")
		)
		(pad "32" smd roundrect
			(at 3.937 1.749 90)
			(size 0.875 0.3)
			(layers "F.Cu" "F.Mask" "F.Paste")
			(roundrect_rratio 0.25)
			(net 251 "Net-(U4-CDBUS0)")
			(pinfunction "CDBUS0")
			(pintype "bidirectional")
		)
		(pad "33" smd roundrect
			(at 3.937 1.249 90)
			(size 0.875 0.3)
			(layers "F.Cu" "F.Mask" "F.Paste")
			(roundrect_rratio 0.25)
			(net 252 "Net-(U4-CDBUS1)")
			(pinfunction "CDBUS1")
			(pintype "bidirectional")
		)
		(pad "34" smd roundrect
			(at 3.937 0.749 90)
			(size 0.875 0.3)
			(layers "F.Cu" "F.Mask" "F.Paste")
			(roundrect_rratio 0.25)
			(net 564 "unconnected-(U4-CDBUS2-Pad34)")
			(pinfunction "CDBUS2")
			(pintype "bidirectional+no_connect")
		)
		(pad "35" smd roundrect
			(at 3.937 0.249 90)
			(size 0.875 0.3)
			(layers "F.Cu" "F.Mask" "F.Paste")
			(roundrect_rratio 0.25)
			(net 565 "unconnected-(U4-CDBUS3-Pad35)")
			(pinfunction "CDBUS3")
			(pintype "bidirectional+no_connect")
		)
		(pad "36" smd roundrect
			(at 3.937 -0.25 90)
			(size 0.875 0.3)
			(layers "F.Cu" "F.Mask" "F.Paste")
			(roundrect_rratio 0.25)
			(net 459 "3V3_SYS")
			(pinfunction "V_{CCIO}")
			(pintype "passive")
		)
		(pad "37" smd roundrect
			(at 3.937 -0.75 90)
			(size 0.875 0.3)
			(layers "F.Cu" "F.Mask" "F.Paste")
			(roundrect_rratio 0.25)
			(net 566 "unconnected-(U4-CDBUS4-Pad37)")
			(pinfunction "CDBUS4")
			(pintype "bidirectional+no_connect")
		)
		(pad "38" smd roundrect
			(at 3.937 -1.25 90)
			(size 0.875 0.3)
			(layers "F.Cu" "F.Mask" "F.Paste")
			(roundrect_rratio 0.25)
			(net 567 "unconnected-(U4-CDBUS5-Pad38)")
			(pinfunction "CDBUS5")
			(pintype "bidirectional+no_connect")
		)
		(pad "39" smd roundrect
			(at 3.937 -1.75 90)
			(size 0.875 0.3)
			(layers "F.Cu" "F.Mask" "F.Paste")
			(roundrect_rratio 0.25)
			(net 568 "unconnected-(U4-CDBUS6-Pad39)")
			(pinfunction "CDBUS6")
			(pintype "bidirectional+no_connect")
		)
		(pad "40" smd roundrect
			(at 3.937 -2.25 90)
			(size 0.875 0.3)
			(layers "F.Cu" "F.Mask" "F.Paste")
			(roundrect_rratio 0.25)
			(net 569 "unconnected-(U4-CDBUS7-Pad40)")
			(pinfunction "CDBUS7")
			(pintype "bidirectional+no_connect")
		)
		(pad "41" smd roundrect
			(at 3.937 -2.75 90)
			(size 0.875 0.3)
			(layers "F.Cu" "F.Mask" "F.Paste")
			(roundrect_rratio 0.25)
			(net 5 "GND")
			(pinfunction "GND")
			(pintype "passive")
		)
		(pad "42" smd roundrect
			(at 3.937 -3.25 90)
			(size 0.875 0.3)
			(layers "F.Cu" "F.Mask" "F.Paste")
			(roundrect_rratio 0.25)
			(net 253 "Net-(U4-DDBUS0)")
			(pinfunction "DDBUS0")
			(pintype "bidirectional")
		)
		(pad "43" smd roundrect
			(at 3.249 -3.938 180)
			(size 0.875 0.3)
			(layers "F.Cu" "F.Mask" "F.Paste")
			(roundrect_rratio 0.25)
			(net 2 "/Interfaces/1V8_FT")
			(pinfunction "V_{REGOUT}")
			(pintype "power_out")
		)
		(pad "44" smd roundrect
			(at 2.749 -3.938 180)
			(size 0.875 0.3)
			(layers "F.Cu" "F.Mask" "F.Paste")
			(roundrect_rratio 0.25)
			(net 459 "3V3_SYS")
			(pinfunction "V_{REGIN}")
			(pintype "power_in")
		)
		(pad "45" smd roundrect
			(at 2.249 -3.938 180)
			(size 0.875 0.3)
			(layers "F.Cu" "F.Mask" "F.Paste")
			(roundrect_rratio 0.25)
			(net 5 "GND")
			(pinfunction "GND")
			(pintype "passive")
		)
		(pad "46" smd roundrect
			(at 1.749 -3.938 180)
			(size 0.875 0.3)
			(layers "F.Cu" "F.Mask" "F.Paste")
			(roundrect_rratio 0.25)
			(net 254 "Net-(U4-DDBUS1)")
			(pinfunction "DDBUS1")
			(pintype "bidirectional")
		)
		(pad "47" smd roundrect
			(at 1.249 -3.938 180)
			(size 0.875 0.3)
			(layers "F.Cu" "F.Mask" "F.Paste")
			(roundrect_rratio 0.25)
			(net 570 "unconnected-(U4-DDBUS2-Pad47)")
			(pinfunction "DDBUS2")
			(pintype "bidirectional+no_connect")
		)
		(pad "48" smd roundrect
			(at 0.749 -3.938 180)
			(size 0.875 0.3)
			(layers "F.Cu" "F.Mask" "F.Paste")
			(roundrect_rratio 0.25)
			(net 571 "unconnected-(U4-DDBUS3-Pad48)")
			(pinfunction "DDBUS3")
			(pintype "bidirectional+no_connect")
		)
		(pad "49" smd roundrect
			(at 0.249 -3.938 180)
			(size 0.875 0.3)
			(layers "F.Cu" "F.Mask" "F.Paste")
			(roundrect_rratio 0.25)
			(net 572 "unconnected-(U4-DDBUS4-Pad49)")
			(pinfunction "DDBUS4")
			(pintype "bidirectional+no_connect")
		)
		(pad "50" smd roundrect
			(at -0.25 -3.938 180)
			(size 0.875 0.3)
			(layers "F.Cu" "F.Mask" "F.Paste")
			(roundrect_rratio 0.25)
			(net 459 "3V3_SYS")
			(pinfunction "V_{CCIO}")
			(pintype "passive")
		)
		(pad "51" smd roundrect
			(at -0.75 -3.938 180)
			(size 0.875 0.3)
			(layers "F.Cu" "F.Mask" "F.Paste")
			(roundrect_rratio 0.25)
			(net 573 "unconnected-(U4-DDBUS5-Pad51)")
			(pinfunction "DDBUS5")
			(pintype "bidirectional+no_connect")
		)
		(pad "52" smd roundrect
			(at -1.25 -3.938 180)
			(size 0.875 0.3)
			(layers "F.Cu" "F.Mask" "F.Paste")
			(roundrect_rratio 0.25)
			(net 604 "unconnected-(U4-DDBUS6-Pad52)")
			(pinfunction "DDBUS6")
			(pintype "bidirectional+no_connect")
		)
		(pad "53" smd roundrect
			(at -1.75 -3.938 180)
			(size 0.875 0.3)
			(layers "F.Cu" "F.Mask" "F.Paste")
			(roundrect_rratio 0.25)
			(net 606 "unconnected-(U4-DDBUS7-Pad53)")
			(pinfunction "DDBUS7")
			(pintype "bidirectional+no_connect")
		)
		(pad "54" smd roundrect
			(at -2.25 -3.938 180)
			(size 0.875 0.3)
			(layers "F.Cu" "F.Mask" "F.Paste")
			(roundrect_rratio 0.25)
			(net 607 "unconnected-(U4-~{PWR_{EN}}-Pad54)")
			(pinfunction "~{PWR_{EN}}")
			(pintype "output+no_connect")
		)
		(pad "55" smd roundrect
			(at -2.75 -3.938 180)
			(size 0.875 0.3)
			(layers "F.Cu" "F.Mask" "F.Paste")
			(roundrect_rratio 0.25)
			(net 608 "unconnected-(U4-EEDATA-Pad55)")
			(pinfunction "EEDATA")
			(pintype "bidirectional+no_connect")
		)
		(pad "56" smd roundrect
			(at -3.25 -3.938 180)
			(size 0.875 0.3)
			(layers "F.Cu" "F.Mask" "F.Paste")
			(roundrect_rratio 0.25)
			(net 634 "unconnected-(U4-EECLK-Pad56)")
			(pinfunction "EECLK")
			(pintype "output+no_connect")
		)
		(pad "57" smd rect
			(at 0 0 90)
			(size 5.9 5.9)
			(layers "F.Cu" "F.Mask")
			(net 5 "GND")
			(pinfunction "GND")
			(pintype "passive")
		)
	)
	(footprint "antmicro-footprints:R_0402_1005Metric"
		(layer "F.Cu")
		(at 128.672157 55.688672)
		(descr "Resistor SMD 0402")
		(tags "resistor SMD 0402")
		(property "Reference" "R115"
			(at -1.272157 -0.688672 0)
			(layer "F.SilkS")
			(effects
				(font
					(size 0.7 0.7)
					(thickness 0.15)
				)
				(justify left bottom)
			)
		)
		(property "Value" "R_5R1_0402"
			(at 0 1.4 0)
			(layer "F.Fab")
			(effects
				(font
					(size 0.7 0.7)
					(thickness 0.15)
				)
				(justify left bottom)
			)
		)
		(property "Description" "5R1 resistor in 0402 package with 1% tolerance"
			(at 0 0 0)
			(layer "F.Fab")
			(hide yes)
			(effects
				(font
					(size 1.27 1.27)
					(thickness 0.15)
				)
			)
		)
		(property "Author" "Antmicro"
			(at 0 0 0)
			(layer "F.Fab")
			(hide yes)
			(effects
				(font
					(size 1 1)
					(thickness 0.15)
				)
			)
		)
		(property "License" "Apache-2.0"
			(at 0 0 0)
			(layer "F.Fab")
			(hide yes)
			(effects
				(font
					(size 1 1)
					(thickness 0.15)
				)
			)
		)
		(property "MPN" "CR0402-FX-5R10GLF"
			(at 0 0 0)
			(layer "F.Fab")
			(hide yes)
			(effects
				(font
					(size 1 1)
					(thickness 0.15)
				)
			)
		)
		(property "Manufacturer" "Bourns"
			(at 0 0 0)
			(layer "F.Fab")
			(hide yes)
			(effects
				(font
					(size 1 1)
					(thickness 0.15)
				)
			)
		)
		(property "Tolerance" "1%"
			(at 0 0 0)
			(layer "F.Fab")
			(hide yes)
			(effects
				(font
					(size 1 1)
					(thickness 0.15)
				)
			)
		)
		(property "Val" "5R1"
			(at 0 0 0)
			(layer "F.Fab")
			(hide yes)
			(effects
				(font
					(size 1 1)
					(thickness 0.15)
				)
			)
		)
		(sheetname "Supply")
		(sheetfile "supply.kicad_sch")
		(attr exclude_from_pos_files exclude_from_bom dnp)
		(fp_rect
			(start -0.93 -0.47)
			(end 0.93 0.47)
			(stroke
				(width 0.05)
				(type solid)
			)
			(fill no)
			(layer "F.CrtYd")
		)
		(fp_rect
			(start -0.5 -0.25)
			(end 0.5 0.25)
			(stroke
				(width 0.15)
				(type solid)
			)
			(fill no)
			(layer "F.Fab")
		)
		(pad "1" smd roundrect
			(at -0.485 0)
			(size 0.59 0.64)
			(layers "F.Cu" "F.Mask" "F.Paste")
			(roundrect_rratio 0.25)
			(net 629 "/Supply/VDD2_BST")
			(pintype "passive")
		)
		(pad "2" smd roundrect
			(at 0.485 0)
			(size 0.59 0.64)
			(layers "F.Cu" "F.Mask" "F.Paste")
			(roundrect_rratio 0.25)
			(net 659 "Net-(C191-Pad1)")
			(pintype "passive")
		)
	)
	(footprint "antmicro-footprints:R_0402_1005Metric"
		(layer "F.Cu")
		(at 129.95 89.074 180)
		(descr "Resistor SMD 0402")
		(tags "resistor SMD 0402")
		(property "Reference" "R133"
			(at 1.285328 2.474 180)
			(layer "F.SilkS")
			(effects
				(font
					(size 0.7 0.7)
					(thickness 0.15)
				)
				(justify left bottom)
			)
		)
		(property "Value" "R_0R_0402"
			(at 0 1.4 180)
			(layer "F.Fab")
			(effects
				(font
					(size 0.7 0.7)
					(thickness 0.15)
				)
				(justify left bottom)
			)
		)
		(property "Description" "0R resistor in 0402 package with unspecified tolerance"
			(at 0 0 180)
			(layer "F.Fab")
			(hide yes)
			(effects
				(font
					(size 1.27 1.27)
					(thickness 0.15)
				)
			)
		)
		(property "Author" "Antmicro"
			(at 259.9 178.148 0)
			(layer "F.Fab")
			(hide yes)
			(effects
				(font
					(size 1 1)
					(thickness 0.15)
				)
			)
		)
		(property "Current" "1A"
			(at 259.9 178.148 0)
			(layer "F.Fab")
			(hide yes)
			(effects
				(font
					(size 1 1)
					(thickness 0.15)
				)
			)
		)
		(property "License" "Apache-2.0"
			(at 259.9 178.148 0)
			(layer "F.Fab")
			(hide yes)
			(effects
				(font
					(size 1 1)
					(thickness 0.15)
				)
			)
		)
		(property "MPN" "ERJ2GE0R00X"
			(at 259.9 178.148 0)
			(layer "F.Fab")
			(hide yes)
			(effects
				(font
					(size 1 1)
					(thickness 0.15)
				)
			)
		)
		(property "Manufacturer" "Panasonic"
			(at 259.9 178.148 0)
			(layer "F.Fab")
			(hide yes)
			(effects
				(font
					(size 1 1)
					(thickness 0.15)
				)
			)
		)
		(property "Tolerance" ""
			(at 259.9 178.148 0)
			(layer "F.Fab")
			(hide yes)
			(effects
				(font
					(size 1 1)
					(thickness 0.15)
				)
			)
		)
		(property "Val" "0R"
			(at 259.9 178.148 0)
			(layer "F.Fab")
			(hide yes)
			(effects
				(font
					(size 1 1)
					(thickness 0.15)
				)
			)
		)
		(sheetname "Supply")
		(sheetfile "supply.kicad_sch")
		(attr smd)
		(fp_rect
			(start -0.93 -0.47)
			(end 0.93 0.47)
			(stroke
				(width 0.05)
				(type solid)
			)
			(fill no)
			(layer "F.CrtYd")
		)
		(fp_rect
			(start -0.5 -0.25)
			(end 0.5 0.25)
			(stroke
				(width 0.15)
				(type solid)
			)
			(fill no)
			(layer "F.Fab")
		)
		(pad "1" smd roundrect
			(at -0.485 0 180)
			(size 0.59 0.64)
			(layers "F.Cu" "F.Mask" "F.Paste")
			(roundrect_rratio 0.25)
			(net 5 "GND")
			(pintype "passive")
		)
		(pad "2" smd roundrect
			(at 0.485 0 180)
			(size 0.59 0.64)
			(layers "F.Cu" "F.Mask" "F.Paste")
			(roundrect_rratio 0.25)
			(net 621 "/Supply/1V1_MODE")
			(pintype "passive")
		)
	)
	(footprint "antmicro-footprints:C_0805_2012Metric"
		(layer "F.Cu")
		(at 111.2992 127)
		(descr "Capacitor SMD 0805")
		(tags "capacitor SMD 0805")
		(property "Reference" "C124"
			(at -1.5992 0.1 135)
			(layer "F.SilkS")
			(effects
				(font
					(size 0.7 0.7)
					(thickness 0.15)
				)
				(justify left bottom)
			)
		)
		(property "Value" "C_22u_0805_16V"
			(at 0 1.947 0)
			(layer "F.Fab")
			(effects
				(font
					(size 0.7 0.7)
					(thickness 0.15)
				)
				(justify left bottom)
			)
		)
		(property "Description" " "
			(at 0 0 0)
			(layer "F.Fab")
			(hide yes)
			(effects
				(font
					(size 1.27 1.27)
					(thickness 0.15)
				)
			)
		)
		(property "Author" "Antmicro"
			(at 0 0 0)
			(layer "F.Fab")
			(hide yes)
			(effects
				(font
					(size 1 1)
					(thickness 0.15)
				)
			)
		)
		(property "Dielectric" ""
			(at 0 0 0)
			(layer "F.Fab")
			(hide yes)
			(effects
				(font
					(size 1 1)
					(thickness 0.15)
				)
			)
		)
		(property "License" "Apache-2.0"
			(at 0 0 0)
			(layer "F.Fab")
			(hide yes)
			(effects
				(font
					(size 1 1)
					(thickness 0.15)
				)
			)
		)
		(property "MPN" "GRT21BR61C226ME13L"
			(at 0 0 0)
			(layer "F.Fab")
			(hide yes)
			(effects
				(font
					(size 1 1)
					(thickness 0.15)
				)
			)
		)
		(property "Manufacturer" "Murata"
			(at 0 0 0)
			(layer "F.Fab")
			(hide yes)
			(effects
				(font
					(size 1 1)
					(thickness 0.15)
				)
			)
		)
		(property "Val" "22u/16V"
			(at 0 0 0)
			(layer "F.Fab")
			(hide yes)
			(effects
				(font
					(size 1 1)
					(thickness 0.15)
				)
			)
		)
		(property "Voltage" ""
			(at 0 0 0)
			(layer "F.Fab")
			(hide yes)
			(effects
				(font
					(size 1 1)
					(thickness 0.15)
				)
			)
		)
		(sheetname "Supply")
		(sheetfile "supply.kicad_sch")
		(attr smd)
		(fp_line
			(start -0.3 -0.8)
			(end 0.3 -0.8)
			(stroke
				(width 0.15)
				(type solid)
			)
			(layer "F.SilkS")
		)
		(fp_line
			(start -0.3 0.8)
			(end 0.3 0.8)
			(stroke
				(width 0.15)
				(type solid)
			)
			(layer "F.SilkS")
		)
		(fp_rect
			(start -1.9 -0.93)
			(end 1.9 0.93)
			(stroke
				(width 0.05)
				(type solid)
			)
			(fill no)
			(layer "F.CrtYd")
		)
		(fp_rect
			(start -0.95 -0.675)
			(end 0.95 0.675)
			(stroke
				(width 0.15)
				(type solid)
			)
			(fill no)
			(layer "F.Fab")
		)
		(pad "1" smd rect
			(at -1.05 0)
			(size 1.2 1.2)
			(layers "F.Cu" "F.Mask" "F.Paste")
			(net 224 "VIN")
			(pintype "passive")
		)
		(pad "2" smd rect
			(at 1.05 0)
			(size 1.2 1.2)
			(layers "F.Cu" "F.Mask" "F.Paste")
			(net 5 "GND")
			(pintype "passive")
		)
	)
	(footprint "antmicro-footprints:C_0402_1005Metric"
		(layer "F.Cu")
		(at 115.225 102.449 180)
		(descr "Capacitor SMD 0402")
		(tags "capacitor SMD 0402")
		(property "Reference" "C152"
			(at 1.925 -1.251 180)
			(layer "F.SilkS")
			(effects
				(font
					(size 0.7 0.7)
					(thickness 0.15)
				)
				(justify left bottom)
			)
		)
		(property "Value" "C_10u_0402"
			(at 0 1.4 180)
			(layer "F.Fab")
			(effects
				(font
					(size 0.7 0.7)
					(thickness 0.15)
				)
				(justify left bottom)
			)
		)
		(property "Description" " "
			(at 0 0 180)
			(layer "F.Fab")
			(hide yes)
			(effects
				(font
					(size 1.27 1.27)
					(thickness 0.15)
				)
			)
		)
		(property "Author" "Antmicro"
			(at 230.45 204.898 0)
			(layer "F.Fab")
			(hide yes)
			(effects
				(font
					(size 1 1)
					(thickness 0.15)
				)
			)
		)
		(property "Dielectric" ""
			(at 230.45 204.898 0)
			(layer "F.Fab")
			(hide yes)
			(effects
				(font
					(size 1 1)
					(thickness 0.15)
				)
			)
		)
		(property "License" "Apache-2.0"
			(at 230.45 204.898 0)
			(layer "F.Fab")
			(hide yes)
			(effects
				(font
					(size 1 1)
					(thickness 0.15)
				)
			)
		)
		(property "MPN" "CC0402MRX5R5BB106"
			(at 230.45 204.898 0)
			(layer "F.Fab")
			(hide yes)
			(effects
				(font
					(size 1 1)
					(thickness 0.15)
				)
			)
		)
		(property "Manufacturer" "Yaego"
			(at 230.45 204.898 0)
			(layer "F.Fab")
			(hide yes)
			(effects
				(font
					(size 1 1)
					(thickness 0.15)
				)
			)
		)
		(property "Val" "10u"
			(at 230.45 204.898 0)
			(layer "F.Fab")
			(hide yes)
			(effects
				(font
					(size 1 1)
					(thickness 0.15)
				)
			)
		)
		(property "Voltage" ""
			(at 230.45 204.898 0)
			(layer "F.Fab")
			(hide yes)
			(effects
				(font
					(size 1 1)
					(thickness 0.15)
				)
			)
		)
		(sheetname "Supply")
		(sheetfile "supply.kicad_sch")
		(attr smd)
		(fp_rect
			(start -0.94 -0.47)
			(end 0.94 0.47)
			(stroke
				(width 0.05)
				(type solid)
			)
			(fill no)
			(layer "F.CrtYd")
		)
		(fp_rect
			(start -0.499 -0.249)
			(end 0.499 0.249)
			(stroke
				(width 0.15)
				(type solid)
			)
			(fill no)
			(layer "F.Fab")
		)
		(pad "1" smd roundrect
			(at -0.484 0 180)
			(size 0.59 0.64)
			(layers "F.Cu" "F.Mask" "F.Paste")
			(roundrect_rratio 0.25)
			(net 463 "VCC5V0_INT")
			(pintype "passive")
		)
		(pad "2" smd roundrect
			(at 0.484 0 180)
			(size 0.59 0.64)
			(layers "F.Cu" "F.Mask" "F.Paste")
			(roundrect_rratio 0.25)
			(net 5 "GND")
			(pintype "passive")
		)
	)
	(footprint "antmicro-footprints:C_0805_2012Metric"
		(layer "F.Cu")
		(at 111.2992 125.125)
		(descr "Capacitor SMD 0805")
		(tags "capacitor SMD 0805")
		(property "Reference" "C123"
			(at -1.5992 0.1 135)
			(layer "F.SilkS")
			(effects
				(font
					(size 0.7 0.7)
					(thickness 0.15)
				)
				(justify left bottom)
			)
		)
		(property "Value" "C_22u_0805_16V"
			(at 0 1.947 0)
			(layer "F.Fab")
			(effects
				(font
					(size 0.7 0.7)
					(thickness 0.15)
				)
				(justify left bottom)
			)
		)
		(property "Description" " "
			(at 0 0 0)
			(layer "F.Fab")
			(hide yes)
			(effects
				(font
					(size 1.27 1.27)
					(thickness 0.15)
				)
			)
		)
		(property "Author" "Antmicro"
			(at 0 0 0)
			(layer "F.Fab")
			(hide yes)
			(effects
				(font
					(size 1 1)
					(thickness 0.15)
				)
			)
		)
		(property "Dielectric" ""
			(at 0 0 0)
			(layer "F.Fab")
			(hide yes)
			(effects
				(font
					(size 1 1)
					(thickness 0.15)
				)
			)
		)
		(property "License" "Apache-2.0"
			(at 0 0 0)
			(layer "F.Fab")
			(hide yes)
			(effects
				(font
					(size 1 1)
					(thickness 0.15)
				)
			)
		)
		(property "MPN" "GRT21BR61C226ME13L"
			(at 0 0 0)
			(layer "F.Fab")
			(hide yes)
			(effects
				(font
					(size 1 1)
					(thickness 0.15)
				)
			)
		)
		(property "Manufacturer" "Murata"
			(at 0 0 0)
			(layer "F.Fab")
			(hide yes)
			(effects
				(font
					(size 1 1)
					(thickness 0.15)
				)
			)
		)
		(property "Val" "22u/16V"
			(at 0 0 0)
			(layer "F.Fab")
			(hide yes)
			(effects
				(font
					(size 1 1)
					(thickness 0.15)
				)
			)
		)
		(property "Voltage" ""
			(at 0 0 0)
			(layer "F.Fab")
			(hide yes)
			(effects
				(font
					(size 1 1)
					(thickness 0.15)
				)
			)
		)
		(sheetname "Supply")
		(sheetfile "supply.kicad_sch")
		(attr smd)
		(fp_line
			(start -0.3 -0.8)
			(end 0.3 -0.8)
			(stroke
				(width 0.15)
				(type solid)
			)
			(layer "F.SilkS")
		)
		(fp_line
			(start -0.3 0.8)
			(end 0.3 0.8)
			(stroke
				(width 0.15)
				(type solid)
			)
			(layer "F.SilkS")
		)
		(fp_rect
			(start -1.9 -0.93)
			(end 1.9 0.93)
			(stroke
				(width 0.05)
				(type solid)
			)
			(fill no)
			(layer "F.CrtYd")
		)
		(fp_rect
			(start -0.95 -0.675)
			(end 0.95 0.675)
			(stroke
				(width 0.15)
				(type solid)
			)
			(fill no)
			(layer "F.Fab")
		)
		(pad "1" smd rect
			(at -1.05 0)
			(size 1.2 1.2)
			(layers "F.Cu" "F.Mask" "F.Paste")
			(net 224 "VIN")
			(pintype "passive")
		)
		(pad "2" smd rect
			(at 1.05 0)
			(size 1.2 1.2)
			(layers "F.Cu" "F.Mask" "F.Paste")
			(net 5 "GND")
			(pintype "passive")
		)
	)
	(footprint "antmicro-footprints:C_0402_1005Metric"
		(layer "F.Cu")
		(at 188.25 115.885 -90)
		(descr "Capacitor SMD 0402")
		(tags "capacitor SMD 0402")
		(property "Reference" "C160"
			(at -0.785 -0.45 90)
			(layer "F.SilkS")
			(effects
				(font
					(size 0.7 0.7)
					(thickness 0.15)
				)
				(justify left bottom)
			)
		)
		(property "Value" "C_100n_6V3_0402"
			(at 0 1.4 270)
			(layer "F.Fab")
			(effects
				(font
					(size 0.7 0.7)
					(thickness 0.15)
				)
				(justify left bottom)
			)
		)
		(property "Description" " "
			(at 0 0 270)
			(layer "F.Fab")
			(hide yes)
			(effects
				(font
					(size 1.27 1.27)
					(thickness 0.15)
				)
			)
		)
		(property "Author" "Antmicro"
			(at 72.365 304.135 0)
			(layer "F.Fab")
			(hide yes)
			(effects
				(font
					(size 1 1)
					(thickness 0.15)
				)
			)
		)
		(property "Dielectric" ""
			(at 72.365 304.135 0)
			(layer "F.Fab")
			(hide yes)
			(effects
				(font
					(size 1 1)
					(thickness 0.15)
				)
			)
		)
		(property "License" "Apache-2.0"
			(at 72.365 304.135 0)
			(layer "F.Fab")
			(hide yes)
			(effects
				(font
					(size 1 1)
					(thickness 0.15)
				)
			)
		)
		(property "MPN" "0402X104K6R3CT"
			(at 72.365 304.135 0)
			(layer "F.Fab")
			(hide yes)
			(effects
				(font
					(size 1 1)
					(thickness 0.15)
				)
			)
		)
		(property "Manufacturer" "Walsin"
			(at 72.365 304.135 0)
			(layer "F.Fab")
			(hide yes)
			(effects
				(font
					(size 1 1)
					(thickness 0.15)
				)
			)
		)
		(property "Val" "100n"
			(at 72.365 304.135 0)
			(layer "F.Fab")
			(hide yes)
			(effects
				(font
					(size 1 1)
					(thickness 0.15)
				)
			)
		)
		(property "Voltage" ""
			(at 72.365 304.135 0)
			(layer "F.Fab")
			(hide yes)
			(effects
				(font
					(size 1 1)
					(thickness 0.15)
				)
			)
		)
		(sheetname "Supply")
		(sheetfile "supply.kicad_sch")
		(attr smd)
		(fp_rect
			(start -0.94 -0.47)
			(end 0.94 0.47)
			(stroke
				(width 0.05)
				(type solid)
			)
			(fill no)
			(layer "F.CrtYd")
		)
		(fp_rect
			(start -0.499 -0.249)
			(end 0.499 0.249)
			(stroke
				(width 0.15)
				(type solid)
			)
			(fill no)
			(layer "F.Fab")
		)
		(pad "1" smd roundrect
			(at -0.484 0 270)
			(size 0.59 0.64)
			(layers "F.Cu" "F.Mask" "F.Paste")
			(roundrect_rratio 0.25)
			(net 586 "/Supply/1V2_SW")
			(pintype "passive")
		)
		(pad "2" smd roundrect
			(at 0.484 0 270)
			(size 0.59 0.64)
			(layers "F.Cu" "F.Mask" "F.Paste")
			(roundrect_rratio 0.25)
			(net 585 "/Supply/1V2_BST")
			(pintype "passive")
		)
	)
	(footprint "antmicro-footprints:TP_SMD_1mm"
		(layer "F.Cu")
		(at 144.725 85.1982 180)
		(property "Reference" "TP19"
			(at 1.4 4.3982 180)
			(layer "F.SilkS")
			(effects
				(font
					(size 0.7 0.7)
					(thickness 0.15)
				)
				(justify left bottom)
			)
		)
		(property "Value" "TP_1mm_SMD"
			(at 0 1.4 180)
			(layer "F.Fab")
			(effects
				(font
					(size 0.7 0.7)
					(thickness 0.15)
				)
				(justify left bottom)
			)
		)
		(property "Description" "Test Point 1mm"
			(at 0 0 180)
			(layer "F.Fab")
			(hide yes)
			(effects
				(font
					(size 1.27 1.27)
					(thickness 0.15)
				)
			)
		)
		(property "Author" "Antmicro"
			(at 289.45 170.3964 0)
			(layer "F.Fab")
			(hide yes)
			(effects
				(font
					(size 1 1)
					(thickness 0.15)
				)
			)
		)
		(property "License" "Apache-2.0"
			(at 289.45 170.3964 0)
			(layer "F.Fab")
			(hide yes)
			(effects
				(font
					(size 1 1)
					(thickness 0.15)
				)
			)
		)
		(property "MPN" ""
			(at 289.45 170.3964 0)
			(layer "F.Fab")
			(hide yes)
			(effects
				(font
					(size 1 1)
					(thickness 0.15)
				)
			)
		)
		(property "Manufacturer" ""
			(at 289.45 170.3964 0)
			(layer "F.Fab")
			(hide yes)
			(effects
				(font
					(size 1 1)
					(thickness 0.15)
				)
			)
		)
		(sheetname "Supply")
		(sheetfile "supply.kicad_sch")
		(attr exclude_from_pos_files)
		(pad "1" smd circle
			(at 0 0 180)
			(size 1 1)
			(layers "F.Cu" "F.Mask")
			(net 465 "1V0_SYS")
			(pinfunction "1")
			(pintype "passive")
		)
	)
	(footprint "antmicro-footprints:R_0402_1005Metric"
		(layer "F.Cu")
		(at 115.3492 112.6)
		(descr "Resistor SMD 0402")
		(tags "resistor SMD 0402")
		(property "Reference" "R100"
			(at -1.8492 -1.5 0)
			(layer "F.SilkS")
			(effects
				(font
					(size 0.7 0.7)
					(thickness 0.15)
				)
				(justify left bottom)
			)
		)
		(property "Value" "R_100k_0402"
			(at 0 1.4 0)
			(layer "F.Fab")
			(effects
				(font
					(size 0.7 0.7)
					(thickness 0.15)
				)
				(justify left bottom)
			)
		)
		(property "Description" "100k resistor in 0402 package with 1% tolerance"
			(at 0 0 0)
			(layer "F.Fab")
			(hide yes)
			(effects
				(font
					(size 1.27 1.27)
					(thickness 0.15)
				)
			)
		)
		(property "Author" "Antmicro"
			(at 0 0 0)
			(layer "F.Fab")
			(hide yes)
			(effects
				(font
					(size 1 1)
					(thickness 0.15)
				)
			)
		)
		(property "License" "Apache-2.0"
			(at 0 0 0)
			(layer "F.Fab")
			(hide yes)
			(effects
				(font
					(size 1 1)
					(thickness 0.15)
				)
			)
		)
		(property "MPN" "CR0402-FX-1003GLF"
			(at 0 0 0)
			(layer "F.Fab")
			(hide yes)
			(effects
				(font
					(size 1 1)
					(thickness 0.15)
				)
			)
		)
		(property "Manufacturer" "Bourns"
			(at 0 0 0)
			(layer "F.Fab")
			(hide yes)
			(effects
				(font
					(size 1 1)
					(thickness 0.15)
				)
			)
		)
		(property "Tolerance" "1%"
			(at 0 0 0)
			(layer "F.Fab")
			(hide yes)
			(effects
				(font
					(size 1 1)
					(thickness 0.15)
				)
			)
		)
		(property "Val" "100k"
			(at 0 0 0)
			(layer "F.Fab")
			(hide yes)
			(effects
				(font
					(size 1 1)
					(thickness 0.15)
				)
			)
		)
		(sheetname "Supply")
		(sheetfile "supply.kicad_sch")
		(attr smd)
		(fp_rect
			(start -0.93 -0.47)
			(end 0.93 0.47)
			(stroke
				(width 0.05)
				(type solid)
			)
			(fill no)
			(layer "F.CrtYd")
		)
		(fp_rect
			(start -0.5 -0.25)
			(end 0.5 0.25)
			(stroke
				(width 0.15)
				(type solid)
			)
			(fill no)
			(layer "F.Fab")
		)
		(pad "1" smd roundrect
			(at -0.485 0)
			(size 0.59 0.64)
			(layers "F.Cu" "F.Mask" "F.Paste")
			(roundrect_rratio 0.25)
			(net 463 "VCC5V0_INT")
			(pintype "passive")
		)
		(pad "2" smd roundrect
			(at 0.485 0)
			(size 0.59 0.64)
			(layers "F.Cu" "F.Mask" "F.Paste")
			(roundrect_rratio 0.25)
			(net 466 "SYS_ON")
			(pintype "passive")
		)
	)
	(footprint "antmicro-footprints:C_0603_1608Metric"
		(layer "F.Cu")
		(at 120.0492 110.475 180)
		(descr "Capacitor SMD 0603")
		(tags "capacitor 0603")
		(property "Reference" "C148"
			(at 3.7492 -0.425 180)
			(layer "F.SilkS")
			(effects
				(font
					(size 0.7 0.7)
					(thickness 0.15)
				)
				(justify left bottom)
			)
		)
		(property "Value" "C_47u_0603"
			(at 0 1.6 180)
			(layer "F.Fab")
			(effects
				(font
					(size 0.7 0.7)
					(thickness 0.15)
				)
				(justify left bottom)
			)
		)
		(property "Description" " "
			(at 0 0 180)
			(layer "F.Fab")
			(hide yes)
			(effects
				(font
					(size 1.27 1.27)
					(thickness 0.15)
				)
			)
		)
		(property "Author" "Antmicro"
			(at 240.0984 220.95 0)
			(layer "F.Fab")
			(hide yes)
			(effects
				(font
					(size 1 1)
					(thickness 0.15)
				)
			)
		)
		(property "Dielectric" ""
			(at 240.0984 220.95 0)
			(layer "F.Fab")
			(hide yes)
			(effects
				(font
					(size 1 1)
					(thickness 0.15)
				)
			)
		)
		(property "License" "Apache-2.0"
			(at 240.0984 220.95 0)
			(layer "F.Fab")
			(hide yes)
			(effects
				(font
					(size 1 1)
					(thickness 0.15)
				)
			)
		)
		(property "MPN" "GRM188R60J476ME15D"
			(at 240.0984 220.95 0)
			(layer "F.Fab")
			(hide yes)
			(effects
				(font
					(size 1 1)
					(thickness 0.15)
				)
			)
		)
		(property "Manufacturer" "Murata"
			(at 240.0984 220.95 0)
			(layer "F.Fab")
			(hide yes)
			(effects
				(font
					(size 1 1)
					(thickness 0.15)
				)
			)
		)
		(property "Val" "47u"
			(at 240.0984 220.95 0)
			(layer "F.Fab")
			(hide yes)
			(effects
				(font
					(size 1 1)
					(thickness 0.15)
				)
			)
		)
		(property "Voltage" ""
			(at 240.0984 220.95 0)
			(layer "F.Fab")
			(hide yes)
			(effects
				(font
					(size 1 1)
					(thickness 0.15)
				)
			)
		)
		(sheetname "Supply")
		(sheetfile "supply.kicad_sch")
		(attr smd)
		(fp_line
			(start -0.3 0.3)
			(end 0.3 0.3)
			(stroke
				(width 0.15)
				(type solid)
			)
			(layer "F.SilkS")
		)
		(fp_line
			(start -0.3 -0.3)
			(end 0.3 -0.3)
			(stroke
				(width 0.15)
				(type solid)
			)
			(layer "F.SilkS")
		)
		(fp_rect
			(start -1.24 -0.7)
			(end 1.24 0.7)
			(stroke
				(width 0.05)
				(type solid)
			)
			(fill no)
			(layer "F.CrtYd")
		)
		(fp_rect
			(start -0.8 -0.4)
			(end 0.8 0.4)
			(stroke
				(width 0.15)
				(type solid)
			)
			(fill no)
			(layer "F.Fab")
		)
		(pad "1" smd roundrect
			(at -0.7 0 180)
			(size 0.6 0.8)
			(layers "F.Cu" "F.Mask" "F.Paste")
			(roundrect_rratio 0.2)
			(net 55 "Net-(C141-Pad1)")
			(pintype "passive")
		)
		(pad "2" smd roundrect
			(at 0.7 0 180)
			(size 0.6 0.8)
			(layers "F.Cu" "F.Mask" "F.Paste")
			(roundrect_rratio 0.2)
			(net 5 "GND")
			(pintype "passive")
		)
	)
	(footprint "antmicro-footprints:C_0603_1608Metric"
		(layer "F.Cu")
		(at 120.0492 111.975 180)
		(descr "Capacitor SMD 0603")
		(tags "capacitor 0603")
		(property "Reference" "C145"
			(at 3.7492 -0.425 180)
			(layer "F.SilkS")
			(effects
				(font
					(size 0.7 0.7)
					(thickness 0.15)
				)
				(justify left bottom)
			)
		)
		(property "Value" "C_47u_0603"
			(at 0 1.6 180)
			(layer "F.Fab")
			(effects
				(font
					(size 0.7 0.7)
					(thickness 0.15)
				)
				(justify left bottom)
			)
		)
		(property "Description" " "
			(at 0 0 180)
			(layer "F.Fab")
			(hide yes)
			(effects
				(font
					(size 1.27 1.27)
					(thickness 0.15)
				)
			)
		)
		(property "Author" "Antmicro"
			(at 240.0984 223.95 0)
			(layer "F.Fab")
			(hide yes)
			(effects
				(font
					(size 1 1)
					(thickness 0.15)
				)
			)
		)
		(property "Dielectric" ""
			(at 240.0984 223.95 0)
			(layer "F.Fab")
			(hide yes)
			(effects
				(font
					(size 1 1)
					(thickness 0.15)
				)
			)
		)
		(property "License" "Apache-2.0"
			(at 240.0984 223.95 0)
			(layer "F.Fab")
			(hide yes)
			(effects
				(font
					(size 1 1)
					(thickness 0.15)
				)
			)
		)
		(property "MPN" "GRM188R60J476ME15D"
			(at 240.0984 223.95 0)
			(layer "F.Fab")
			(hide yes)
			(effects
				(font
					(size 1 1)
					(thickness 0.15)
				)
			)
		)
		(property "Manufacturer" "Murata"
			(at 240.0984 223.95 0)
			(layer "F.Fab")
			(hide yes)
			(effects
				(font
					(size 1 1)
					(thickness 0.15)
				)
			)
		)
		(property "Val" "47u"
			(at 240.0984 223.95 0)
			(layer "F.Fab")
			(hide yes)
			(effects
				(font
					(size 1 1)
					(thickness 0.15)
				)
			)
		)
		(property "Voltage" ""
			(at 240.0984 223.95 0)
			(layer "F.Fab")
			(hide yes)
			(effects
				(font
					(size 1 1)
					(thickness 0.15)
				)
			)
		)
		(sheetname "Supply")
		(sheetfile "supply.kicad_sch")
		(attr smd)
		(fp_line
			(start -0.3 0.3)
			(end 0.3 0.3)
			(stroke
				(width 0.15)
				(type solid)
			)
			(layer "F.SilkS")
		)
		(fp_line
			(start -0.3 -0.3)
			(end 0.3 -0.3)
			(stroke
				(width 0.15)
				(type solid)
			)
			(layer "F.SilkS")
		)
		(fp_rect
			(start -1.24 -0.7)
			(end 1.24 0.7)
			(stroke
				(width 0.05)
				(type solid)
			)
			(fill no)
			(layer "F.CrtYd")
		)
		(fp_rect
			(start -0.8 -0.4)
			(end 0.8 0.4)
			(stroke
				(width 0.15)
				(type solid)
			)
			(fill no)
			(layer "F.Fab")
		)
		(pad "1" smd roundrect
			(at -0.7 0 180)
			(size 0.6 0.8)
			(layers "F.Cu" "F.Mask" "F.Paste")
			(roundrect_rratio 0.2)
			(net 55 "Net-(C141-Pad1)")
			(pintype "passive")
		)
		(pad "2" smd roundrect
			(at 0.7 0 180)
			(size 0.6 0.8)
			(layers "F.Cu" "F.Mask" "F.Paste")
			(roundrect_rratio 0.2)
			(net 5 "GND")
			(pintype "passive")
		)
	)
	(footprint "antmicro-footprints:V-QFN2030-12"
		(layer "F.Cu")
		(at 115.188672 100.378992 180)
		(property "Reference" "U8"
			(at -1.011328 -2.521008 180)
			(layer "F.SilkS")
			(effects
				(font
					(size 0.7 0.7)
					(thickness 0.15)
				)
				(justify left bottom)
			)
		)
		(property "Value" "AP62600SJ-7"
			(at -4 2.2 180)
			(layer "F.Fab")
			(effects
				(font
					(size 0.7 0.7)
					(thickness 0.15)
				)
				(justify left bottom)
			)
		)
		(property "Description" "Buck Switching Regulator IC Positive Fixed 0.6V 1 Output 6A 12-VFQFN"
			(at 0 0 180)
			(layer "F.Fab")
			(hide yes)
			(effects
				(font
					(size 1.27 1.27)
					(thickness 0.15)
				)
			)
		)
		(property "Author" "Antmicro"
			(at 230.377344 200.757984 0)
			(layer "F.Fab")
			(hide yes)
			(effects
				(font
					(size 1 1)
					(thickness 0.15)
				)
			)
		)
		(property "License" "Apache-2.0"
			(at 230.377344 200.757984 0)
			(layer "F.Fab")
			(hide yes)
			(effects
				(font
					(size 1 1)
					(thickness 0.15)
				)
			)
		)
		(property "MPN" "AP62600SJ-7"
			(at 230.377344 200.757984 0)
			(layer "F.Fab")
			(hide yes)
			(effects
				(font
					(size 1 1)
					(thickness 0.15)
				)
			)
		)
		(property "Manufacturer" "Diodes Incorporated"
			(at 230.377344 200.757984 0)
			(layer "F.Fab")
			(hide yes)
			(effects
				(font
					(size 1 1)
					(thickness 0.15)
				)
			)
		)
		(sheetname "Supply")
		(sheetfile "supply.kicad_sch")
		(attr smd)
		(fp_line
			(start 1.8 1.199)
			(end 0.8 1.199)
			(stroke
				(width 0.15)
				(type solid)
			)
			(layer "F.SilkS")
		)
		(fp_line
			(start 1.8 0.998)
			(end 1.8 1.199)
			(stroke
				(width 0.15)
				(type solid)
			)
			(layer "F.SilkS")
		)
		(fp_line
			(start 1.8 -1.276)
			(end 1.8 -1.025)
			(stroke
				(width 0.15)
				(type solid)
			)
			(layer "F.SilkS")
		)
		(fp_line
			(start -0.802 1.199)
			(end -1.801 1.199)
			(stroke
				(width 0.15)
				(type solid)
			)
			(layer "F.SilkS")
		)
		(fp_line
			(start -1.801 1.199)
			(end -1.801 0.998)
			(stroke
				(width 0.15)
				(type solid)
			)
			(layer "F.SilkS")
		)
		(fp_line
			(start -1.801 -1)
			(end -1.801 -1.2)
			(stroke
				(width 0.15)
				(type solid)
			)
			(layer "F.SilkS")
		)
		(fp_line
			(start -1.801 -1.2)
			(end -0.802 -1.2)
			(stroke
				(width 0.15)
				(type solid)
			)
			(layer "F.SilkS")
		)
		(fp_circle
			(center 0.497 -1.7)
			(end 0.548 -1.7)
			(stroke
				(width 0.15)
				(type solid)
			)
			(fill yes)
			(layer "F.SilkS")
		)
		(fp_rect
			(start -2.026 -1.525)
			(end 2.023 1.524)
			(stroke
				(width 0.05)
				(type solid)
			)
			(fill no)
			(layer "F.CrtYd")
		)
		(fp_line
			(start 1.3 -1)
			(end 1.5 -0.8)
			(stroke
				(width 0.15)
				(type solid)
			)
			(layer "F.Fab")
		)
		(fp_rect
			(start -1.526 -1.025)
			(end 1.523 1.024)
			(stroke
				(width 0.15)
				(type solid)
			)
			(fill no)
			(layer "F.Fab")
		)
		(pad "1" smd rect
			(at 0.498 -0.552 90)
			(size 1.6 0.35)
			(layers "F.Cu" "F.Mask" "F.Paste")
			(net 5 "GND")
			(pinfunction "PGND")
			(pintype "passive")
		)
		(pad "2" smd rect
			(at -0.5 -0.552 90)
			(size 1.6 0.35)
			(layers "F.Cu" "F.Mask" "F.Paste")
			(net 463 "VCC5V0_INT")
			(pinfunction "VIN")
			(pintype "power_in")
		)
		(pad "3" smd rect
			(at -1.45 -0.75 90)
			(size 0.35 0.8)
			(layers "F.Cu" "F.Mask" "F.Paste")
			(net 577 "/Supply/3V3_EN")
			(pinfunction "EN")
			(pintype "input")
		)
		(pad "4" smd rect
			(at -1.45 -0.25 90)
			(size 0.35 0.8)
			(layers "F.Cu" "F.Mask" "F.Paste")
			(net 617 "/Supply/3V3_MODE")
			(pinfunction "MODE")
			(pintype "input")
		)
		(pad "5" smd rect
			(at -1.45 0.248 90)
			(size 0.35 0.8)
			(layers "F.Cu" "F.Mask" "F.Paste")
			(net 610 "/Supply/3V3_FSEL")
			(pinfunction "FSEL")
			(pintype "input")
		)
		(pad "6" smd rect
			(at -1.45 0.748 90)
			(size 0.35 0.8)
			(layers "F.Cu" "F.Mask" "F.Paste")
			(net 647 "unconnected-(U8-PG-Pad6)")
			(pinfunction "PG")
			(pintype "open_collector+no_connect")
		)
		(pad "7" smd rect
			(at -0.5 0.949 180)
			(size 0.35 0.8)
			(layers "F.Cu" "F.Mask" "F.Paste")
			(net 574 "/Supply/3V3_BST")
			(pinfunction "BST")
			(pintype "input")
		)
		(pad "8" smd rect
			(at 0 0.55 90)
			(size 1.6 0.35)
			(layers "F.Cu" "F.Mask" "F.Paste")
			(net 575 "/Supply/3V3_SW")
			(pinfunction "SW")
			(pintype "output")
		)
		(pad "9" smd rect
			(at 1.449 0.748 270)
			(size 0.35 0.8)
			(layers "F.Cu" "F.Mask" "F.Paste")
			(net 609 "/Supply/3V3_VCC_INT")
			(pinfunction "VCC")
			(pintype "input")
		)
		(pad "10" smd rect
			(at 1.449 0.248 270)
			(size 0.35 0.8)
			(layers "F.Cu" "F.Mask" "F.Paste")
			(net 618 "/Supply/3V3_SS{slash}TR")
			(pinfunction "SS/TR")
			(pintype "input")
		)
		(pad "11" smd rect
			(at 1.449 -0.25 270)
			(size 0.35 0.8)
			(layers "F.Cu" "F.Mask" "F.Paste")
			(net 5 "GND")
			(pinfunction "GND")
			(pintype "passive")
		)
		(pad "12" smd rect
			(at 1.449 -0.75 270)
			(size 0.35 0.8)
			(layers "F.Cu" "F.Mask" "F.Paste")
			(net 578 "/Supply/3V3_FB")
			(pinfunction "FB")
			(pintype "input")
		)
	)
	(footprint "antmicro-footprints:C_0402_1005Metric"
		(layer "F.Cu")
		(at 111.147806 83.774 180)
		(descr "Capacitor SMD 0402")
		(tags "capacitor SMD 0402")
		(property "Reference" "C178"
			(at 3.647806 -0.326 180)
			(layer "F.SilkS")
			(effects
				(font
					(size 0.7 0.7)
					(thickness 0.15)
				)
				(justify left bottom)
			)
		)
		(property "Value" "C_1u_0402"
			(at 0 1.4 180)
			(layer "F.Fab")
			(effects
				(font
					(size 0.7 0.7)
					(thickness 0.15)
				)
				(justify left bottom)
			)
		)
		(property "Description" " "
			(at 0 0 180)
			(layer "F.Fab")
			(hide yes)
			(effects
				(font
					(size 1.27 1.27)
					(thickness 0.15)
				)
			)
		)
		(property "Author" "Antmicro"
			(at 222.295612 167.548 0)
			(layer "F.Fab")
			(hide yes)
			(effects
				(font
					(size 1 1)
					(thickness 0.15)
				)
			)
		)
		(property "Dielectric" ""
			(at 222.295612 167.548 0)
			(layer "F.Fab")
			(hide yes)
			(effects
				(font
					(size 1 1)
					(thickness 0.15)
				)
			)
		)
		(property "License" "Apache-2.0"
			(at 222.295612 167.548 0)
			(layer "F.Fab")
			(hide yes)
			(effects
				(font
					(size 1 1)
					(thickness 0.15)
				)
			)
		)
		(property "MPN" "C1005X6S1A105K050BC"
			(at 222.295612 167.548 0)
			(layer "F.Fab")
			(hide yes)
			(effects
				(font
					(size 1 1)
					(thickness 0.15)
				)
			)
		)
		(property "Manufacturer" "TDK"
			(at 222.295612 167.548 0)
			(layer "F.Fab")
			(hide yes)
			(effects
				(font
					(size 1 1)
					(thickness 0.15)
				)
			)
		)
		(property "Val" "1u"
			(at 222.295612 167.548 0)
			(layer "F.Fab")
			(hide yes)
			(effects
				(font
					(size 1 1)
					(thickness 0.15)
				)
			)
		)
		(property "Voltage" ""
			(at 222.295612 167.548 0)
			(layer "F.Fab")
			(hide yes)
			(effects
				(font
					(size 1 1)
					(thickness 0.15)
				)
			)
		)
		(sheetname "Supply")
		(sheetfile "supply.kicad_sch")
		(attr smd)
		(fp_rect
			(start -0.94 -0.47)
			(end 0.94 0.47)
			(stroke
				(width 0.05)
				(type solid)
			)
			(fill no)
			(layer "F.CrtYd")
		)
		(fp_rect
			(start -0.499 -0.249)
			(end 0.499 0.249)
			(stroke
				(width 0.15)
				(type solid)
			)
			(fill no)
			(layer "F.Fab")
		)
		(pad "1" smd roundrect
			(at -0.484 0 180)
			(size 0.59 0.64)
			(layers "F.Cu" "F.Mask" "F.Paste")
			(roundrect_rratio 0.25)
			(net 583 "/Supply/1V8_REG")
			(pintype "passive")
		)
		(pad "2" smd roundrect
			(at 0.484 0 180)
			(size 0.59 0.64)
			(layers "F.Cu" "F.Mask" "F.Paste")
			(roundrect_rratio 0.25)
			(net 5 "GND")
			(pintype "passive")
		)
	)
	(footprint "antmicro-footprints:L_WE-MAIA-2512"
		(layer "F.Cu")
		(at 190.3 114.385 90)
		(property "Reference" "L5"
			(at -2.709 0.2 0)
			(layer "F.SilkS")
			(effects
				(font
					(size 0.7 0.7)
					(thickness 0.15)
				)
				(justify left bottom)
			)
		)
		(property "Value" "784383240047"
			(at 0 2.3 90)
			(layer "F.Fab")
			(effects
				(font
					(size 0.7 0.7)
					(thickness 0.15)
				)
				(justify left bottom)
			)
		)
		(property "Description" "Power Inductor (SMT), AEC-Q200, 470 nH, 3.4 A, Shielded, 6.25 A, WE-MAIA"
			(at 0 0 90)
			(layer "F.Fab")
			(hide yes)
			(effects
				(font
					(size 1.27 1.27)
					(thickness 0.15)
				)
			)
		)
		(property "Author" "Antmicro"
			(at 304.685 -75.915 0)
			(layer "F.Fab")
			(hide yes)
			(effects
				(font
					(size 1 1)
					(thickness 0.15)
				)
			)
		)
		(property "IMax" "3.4 A"
			(at 304.685 -75.915 0)
			(layer "F.Fab")
			(hide yes)
			(effects
				(font
					(size 1 1)
					(thickness 0.15)
				)
			)
		)
		(property "ISat" "6.25 A"
			(at 304.685 -75.915 0)
			(layer "F.Fab")
			(hide yes)
			(effects
				(font
					(size 1 1)
					(thickness 0.15)
				)
			)
		)
		(property "License" "Apache-2.0"
			(at 304.685 -75.915 0)
			(layer "F.Fab")
			(hide yes)
			(effects
				(font
					(size 1 1)
					(thickness 0.15)
				)
			)
		)
		(property "MPN" "784383240047"
			(at 304.685 -75.915 0)
			(layer "F.Fab")
			(hide yes)
			(effects
				(font
					(size 1 1)
					(thickness 0.15)
				)
			)
		)
		(property "Manufacturer" "Würth Elektronik"
			(at 304.685 -75.915 0)
			(layer "F.Fab")
			(hide yes)
			(effects
				(font
					(size 1 1)
					(thickness 0.15)
				)
			)
		)
		(property "Size" "2x2.5"
			(at 304.685 -75.915 0)
			(layer "F.Fab")
			(hide yes)
			(effects
				(font
					(size 1 1)
					(thickness 0.15)
				)
			)
		)
		(property "Val" "470n/3.4A"
			(at 304.685 -75.915 0)
			(layer "F.Fab")
			(hide yes)
			(effects
				(font
					(size 1 1)
					(thickness 0.15)
				)
			)
		)
		(sheetname "Supply")
		(sheetfile "supply.kicad_sch")
		(attr smd)
		(fp_line
			(start -0.325 -1.125)
			(end 0.325 -1.125)
			(stroke
				(width 0.15)
				(type solid)
			)
			(layer "F.SilkS")
		)
		(fp_line
			(start -0.325 1.125)
			(end 0.325 1.125)
			(stroke
				(width 0.15)
				(type solid)
			)
			(layer "F.SilkS")
		)
		(fp_rect
			(start -1.65 -1.4)
			(end 1.65 1.4)
			(stroke
				(width 0.05)
				(type solid)
			)
			(fill no)
			(layer "F.CrtYd")
		)
		(fp_rect
			(start -1.25 -1)
			(end 1.25 1)
			(stroke
				(width 0.15)
				(type solid)
			)
			(fill no)
			(layer "F.Fab")
		)
		(pad "1" smd roundrect
			(at -0.975 0 90)
			(size 0.85 2.3)
			(layers "F.Cu" "F.Mask" "F.Paste")
			(roundrect_rratio 0.1)
			(net 586 "/Supply/1V2_SW")
			(pintype "passive")
		)
		(pad "2" smd roundrect
			(at 0.975 0 90)
			(size 0.85 2.3)
			(layers "F.Cu" "F.Mask" "F.Paste")
			(roundrect_rratio 0.1)
			(net 589 "/Supply/1V2_REG")
			(pintype "passive")
		)
	)
	(footprint "antmicro-footprints:C_0402_1005Metric"
		(layer "F.Cu")
		(at 191.3 111.635 90)
		(descr "Capacitor SMD 0402")
		(tags "capacitor SMD 0402")
		(property "Reference" "C170"
			(at 0.735 0.4 90)
			(layer "F.SilkS")
			(effects
				(font
					(size 0.7 0.7)
					(thickness 0.15)
				)
				(justify left bottom)
			)
		)
		(property "Value" "C_22u_0402"
			(at 0 1.4 90)
			(layer "F.Fab")
			(effects
				(font
					(size 0.7 0.7)
					(thickness 0.15)
				)
				(justify left bottom)
			)
		)
		(property "Description" " "
			(at 0 0 90)
			(layer "F.Fab")
			(hide yes)
			(effects
				(font
					(size 1.27 1.27)
					(thickness 0.15)
				)
			)
		)
		(property "Author" "Antmicro"
			(at 302.935 -79.665 0)
			(layer "F.Fab")
			(hide yes)
			(effects
				(font
					(size 1 1)
					(thickness 0.15)
				)
			)
		)
		(property "Dielectric" ""
			(at 302.935 -79.665 0)
			(layer "F.Fab")
			(hide yes)
			(effects
				(font
					(size 1 1)
					(thickness 0.15)
				)
			)
		)
		(property "License" "Apache-2.0"
			(at 302.935 -79.665 0)
			(layer "F.Fab")
			(hide yes)
			(effects
				(font
					(size 1 1)
					(thickness 0.15)
				)
			)
		)
		(property "MPN" "04024W226MAT2A"
			(at 302.935 -79.665 0)
			(layer "F.Fab")
			(hide yes)
			(effects
				(font
					(size 1 1)
					(thickness 0.15)
				)
			)
		)
		(property "Manufacturer" "AVX"
			(at 302.935 -79.665 0)
			(layer "F.Fab")
			(hide yes)
			(effects
				(font
					(size 1 1)
					(thickness 0.15)
				)
			)
		)
		(property "Val" "22u"
			(at 302.935 -79.665 0)
			(layer "F.Fab")
			(hide yes)
			(effects
				(font
					(size 1 1)
					(thickness 0.15)
				)
			)
		)
		(property "Voltage" ""
			(at 302.935 -79.665 0)
			(layer "F.Fab")
			(hide yes)
			(effects
				(font
					(size 1 1)
					(thickness 0.15)
				)
			)
		)
		(sheetname "Supply")
		(sheetfile "supply.kicad_sch")
		(attr smd)
		(fp_rect
			(start -0.94 -0.47)
			(end 0.94 0.47)
			(stroke
				(width 0.05)
				(type solid)
			)
			(fill no)
			(layer "F.CrtYd")
		)
		(fp_rect
			(start -0.499 -0.249)
			(end 0.499 0.249)
			(stroke
				(width 0.15)
				(type solid)
			)
			(fill no)
			(layer "F.Fab")
		)
		(pad "1" smd roundrect
			(at -0.484 0 90)
			(size 0.59 0.64)
			(layers "F.Cu" "F.Mask" "F.Paste")
			(roundrect_rratio 0.25)
			(net 589 "/Supply/1V2_REG")
			(pintype "passive")
		)
		(pad "2" smd roundrect
			(at 0.484 0 90)
			(size 0.59 0.64)
			(layers "F.Cu" "F.Mask" "F.Paste")
			(roundrect_rratio 0.25)
			(net 5 "GND")
			(pintype "passive")
		)
	)
	(footprint "lpddr4-test-board-footprints:mounting-hole-3.2mm"
		(layer "F.Cu")
		(at 213.9 49.1)
		(property "Reference" "MH2"
			(at -0.178 4.025 0)
			(layer "F.SilkS")
			(hide yes)
			(effects
				(font
					(size 0.7 0.7)
					(thickness 0.15)
				)
				(justify left bottom)
			)
		)
		(property "Value" "M3.2"
			(at -0.153 -4.153 0)
			(layer "F.Fab")
			(hide yes)
			(effects
				(font
					(size 0.7 0.7)
					(thickness 0.15)
				)
				(justify left bottom)
			)
		)
		(attr through_hole board_only exclude_from_bom)
		(pad "1" thru_hole circle
			(at 0 0)
			(size 6 6)
			(drill 3.2)
			(layers "*.Cu" "*.Mask")
			(remove_unused_layers no)
		)
	)
	(footprint "antmicro-footprints:R_0805_2012Metric"
		(layer "F.Cu")
		(at 131.9 68.1)
		(property "Reference" "R99"
			(at -1.1 -1 0)
			(layer "F.SilkS")
			(effects
				(font
					(size 0.7 0.7)
					(thickness 0.15)
				)
				(justify left bottom)
			)
		)
		(property "Value" "R_0R_0805"
			(at 0 1.8 0)
			(layer "F.Fab")
			(effects
				(font
					(size 0.7 0.7)
					(thickness 0.15)
				)
				(justify left bottom)
			)
		)
		(property "Description" "0R resistor in 0805 package with unspecified tolerance"
			(at 0 0 0)
			(layer "F.Fab")
			(hide yes)
			(effects
				(font
					(size 1.27 1.27)
					(thickness 0.15)
				)
			)
		)
		(property "Author" "Antmicro"
			(at 0 0 0)
			(layer "F.Fab")
			(hide yes)
			(effects
				(font
					(size 1 1)
					(thickness 0.15)
				)
			)
		)
		(property "Current" "2.5A"
			(at 0 0 0)
			(layer "F.Fab")
			(hide yes)
			(effects
				(font
					(size 1 1)
					(thickness 0.15)
				)
			)
		)
		(property "License" "Apache-2.0"
			(at 0 0 0)
			(layer "F.Fab")
			(hide yes)
			(effects
				(font
					(size 1 1)
					(thickness 0.15)
				)
			)
		)
		(property "MPN" "CRCW08050000Z0EA"
			(at 0 0 0)
			(layer "F.Fab")
			(hide yes)
			(effects
				(font
					(size 1 1)
					(thickness 0.15)
				)
			)
		)
		(property "Manufacturer" "Vishay"
			(at 0 0 0)
			(layer "F.Fab")
			(hide yes)
			(effects
				(font
					(size 1 1)
					(thickness 0.15)
				)
			)
		)
		(property "Tolerance" ""
			(at 0 0 0)
			(layer "F.Fab")
			(hide yes)
			(effects
				(font
					(size 1 1)
					(thickness 0.15)
				)
			)
		)
		(property "Val" "0R"
			(at 0 0 0)
			(layer "F.Fab")
			(hide yes)
			(effects
				(font
					(size 1 1)
					(thickness 0.15)
				)
			)
		)
		(sheetname "Supply")
		(sheetfile "supply.kicad_sch")
		(attr exclude_from_pos_files exclude_from_bom dnp)
		(fp_line
			(start -0.32 0.699)
			(end 0.28 0.699)
			(stroke
				(width 0.15)
				(type solid)
			)
			(layer "F.SilkS")
		)
		(fp_line
			(start -0.3 -0.701)
			(end 0.298 -0.701)
			(stroke
				(width 0.15)
				(type solid)
			)
			(layer "F.SilkS")
		)
		(fp_rect
			(start -1.75 -0.85)
			(end 1.75 0.85)
			(stroke
				(width 0.05)
				(type solid)
			)
			(fill no)
			(layer "F.CrtYd")
		)
		(fp_line
			(start -0.951 -0.682)
			(end 0.949 -0.682)
			(stroke
				(width 0.15)
				(type solid)
			)
			(layer "F.Fab")
		)
		(fp_line
			(start -0.951 -0.677)
			(end -0.951 0.675)
			(stroke
				(width 0.15)
				(type solid)
			)
			(layer "F.Fab")
		)
		(fp_line
			(start -0.951 0.68)
			(end 0.949 0.68)
			(stroke
				(width 0.15)
				(type solid)
			)
			(layer "F.Fab")
		)
		(fp_line
			(start 0.949 -0.677)
			(end 0.949 0.675)
			(stroke
				(width 0.15)
				(type solid)
			)
			(layer "F.Fab")
		)
		(pad "1" smd roundrect
			(at -1.1 -0.001)
			(size 1 1.4)
			(layers "F.Cu" "F.Mask" "F.Paste")
			(roundrect_rratio 0.15)
			(net 551 "/Supply/VDD1V8")
			(pintype "passive")
		)
		(pad "2" smd roundrect
			(at 1.1 -0.001)
			(size 1 1.4)
			(layers "F.Cu" "F.Mask" "F.Paste")
			(roundrect_rratio 0.15)
			(net 460 "1V8_SYS")
			(pintype "passive")
		)
	)
	(footprint "antmicro-footprints:C_0402_1005Metric"
		(layer "F.Cu")
		(at 123.4325 97.249 180)
		(descr "Capacitor SMD 0402")
		(tags "capacitor SMD 0402")
		(property "Reference" "C171"
			(at 1.9325 2.449 180)
			(layer "F.SilkS")
			(effects
				(font
					(size 0.7 0.7)
					(thickness 0.15)
				)
				(justify left bottom)
			)
		)
		(property "Value" "C_22u_0402"
			(at 0 1.4 180)
			(layer "F.Fab")
			(effects
				(font
					(size 0.7 0.7)
					(thickness 0.15)
				)
				(justify left bottom)
			)
		)
		(property "Description" " "
			(at 0 0 180)
			(layer "F.Fab")
			(hide yes)
			(effects
				(font
					(size 1.27 1.27)
					(thickness 0.15)
				)
			)
		)
		(property "Author" "Antmicro"
			(at 246.865 194.498 0)
			(layer "F.Fab")
			(hide yes)
			(effects
				(font
					(size 1 1)
					(thickness 0.15)
				)
			)
		)
		(property "Dielectric" ""
			(at 246.865 194.498 0)
			(layer "F.Fab")
			(hide yes)
			(effects
				(font
					(size 1 1)
					(thickness 0.15)
				)
			)
		)
		(property "License" "Apache-2.0"
			(at 246.865 194.498 0)
			(layer "F.Fab")
			(hide yes)
			(effects
				(font
					(size 1 1)
					(thickness 0.15)
				)
			)
		)
		(property "MPN" "04024W226MAT2A"
			(at 246.865 194.498 0)
			(layer "F.Fab")
			(hide yes)
			(effects
				(font
					(size 1 1)
					(thickness 0.15)
				)
			)
		)
		(property "Manufacturer" "AVX"
			(at 246.865 194.498 0)
			(layer "F.Fab")
			(hide yes)
			(effects
				(font
					(size 1 1)
					(thickness 0.15)
				)
			)
		)
		(property "Val" "22u"
			(at 246.865 194.498 0)
			(layer "F.Fab")
			(hide yes)
			(effects
				(font
					(size 1 1)
					(thickness 0.15)
				)
			)
		)
		(property "Voltage" ""
			(at 246.865 194.498 0)
			(layer "F.Fab")
			(hide yes)
			(effects
				(font
					(size 1 1)
					(thickness 0.15)
				)
			)
		)
		(sheetname "Supply")
		(sheetfile "supply.kicad_sch")
		(attr smd)
		(fp_rect
			(start -0.94 -0.47)
			(end 0.94 0.47)
			(stroke
				(width 0.05)
				(type solid)
			)
			(fill no)
			(layer "F.CrtYd")
		)
		(fp_rect
			(start -0.499 -0.249)
			(end 0.499 0.249)
			(stroke
				(width 0.15)
				(type solid)
			)
			(fill no)
			(layer "F.Fab")
		)
		(pad "1" smd roundrect
			(at -0.484 0 180)
			(size 0.59 0.64)
			(layers "F.Cu" "F.Mask" "F.Paste")
			(roundrect_rratio 0.25)
			(net 588 "/Supply/1V0_REG")
			(pintype "passive")
		)
		(pad "2" smd roundrect
			(at 0.484 0 180)
			(size 0.59 0.64)
			(layers "F.Cu" "F.Mask" "F.Paste")
			(roundrect_rratio 0.25)
			(net 5 "GND")
			(pintype "passive")
		)
	)
	(footprint "antmicro-footprints:C_0402_1005Metric"
		(layer "F.Cu")
		(at 124.05 52.475 90)
		(descr "Capacitor SMD 0402")
		(tags "capacitor SMD 0402")
		(property "Reference" "C192"
			(at 0.775 0.35 90)
			(layer "F.SilkS")
			(effects
				(font
					(size 0.7 0.7)
					(thickness 0.15)
				)
				(justify left bottom)
			)
		)
		(property "Value" "C_470n_0402"
			(at 0 1.4 90)
			(layer "F.Fab")
			(effects
				(font
					(size 0.7 0.7)
					(thickness 0.15)
				)
				(justify left bottom)
			)
		)
		(property "Description" " "
			(at 0 0 90)
			(layer "F.Fab")
			(hide yes)
			(effects
				(font
					(size 1.27 1.27)
					(thickness 0.15)
				)
			)
		)
		(property "Author" "Antmicro"
			(at 176.525 -71.575 0)
			(layer "F.Fab")
			(hide yes)
			(effects
				(font
					(size 1 1)
					(thickness 0.15)
				)
			)
		)
		(property "Dielectric" ""
			(at 176.525 -71.575 0)
			(layer "F.Fab")
			(hide yes)
			(effects
				(font
					(size 1 1)
					(thickness 0.15)
				)
			)
		)
		(property "License" "Apache-2.0"
			(at 176.525 -71.575 0)
			(layer "F.Fab")
			(hide yes)
			(effects
				(font
					(size 1 1)
					(thickness 0.15)
				)
			)
		)
		(property "MPN" "C1005X5R1E474M050BB"
			(at 176.525 -71.575 0)
			(layer "F.Fab")
			(hide yes)
			(effects
				(font
					(size 1 1)
					(thickness 0.15)
				)
			)
		)
		(property "Manufacturer" "TDK"
			(at 176.525 -71.575 0)
			(layer "F.Fab")
			(hide yes)
			(effects
				(font
					(size 1 1)
					(thickness 0.15)
				)
			)
		)
		(property "Val" "470n"
			(at 176.525 -71.575 0)
			(layer "F.Fab")
			(hide yes)
			(effects
				(font
					(size 1 1)
					(thickness 0.15)
				)
			)
		)
		(property "Voltage" ""
			(at 176.525 -71.575 0)
			(layer "F.Fab")
			(hide yes)
			(effects
				(font
					(size 1 1)
					(thickness 0.15)
				)
			)
		)
		(sheetname "Supply")
		(sheetfile "supply.kicad_sch")
		(attr exclude_from_pos_files exclude_from_bom dnp)
		(fp_rect
			(start -0.94 -0.47)
			(end 0.94 0.47)
			(stroke
				(width 0.05)
				(type solid)
			)
			(fill no)
			(layer "F.CrtYd")
		)
		(fp_rect
			(start -0.499 -0.249)
			(end 0.499 0.249)
			(stroke
				(width 0.15)
				(type solid)
			)
			(fill no)
			(layer "F.Fab")
		)
		(pad "1" smd roundrect
			(at -0.484 0 90)
			(size 0.59 0.64)
			(layers "F.Cu" "F.Mask" "F.Paste")
			(roundrect_rratio 0.25)
			(net 626 "/Supply/VDDQ_REF")
			(pintype "passive")
		)
		(pad "2" smd roundrect
			(at 0.484 0 90)
			(size 0.59 0.64)
			(layers "F.Cu" "F.Mask" "F.Paste")
			(roundrect_rratio 0.25)
			(net 5 "GND")
			(pintype "passive")
		)
	)
	(footprint "antmicro-footprints:R_0805_2012Metric"
		(layer "F.Cu")
		(at 122.1492 108.7)
		(property "Reference" "R111"
			(at 1.6508 0.4 0)
			(layer "F.SilkS")
			(effects
				(font
					(size 0.7 0.7)
					(thickness 0.15)
				)
				(justify left bottom)
			)
		)
		(property "Value" "R_0R_0805"
			(at 0 1.8 0)
			(layer "F.Fab")
			(effects
				(font
					(size 0.7 0.7)
					(thickness 0.15)
				)
				(justify left bottom)
			)
		)
		(property "Description" "0R resistor in 0805 package with unspecified tolerance"
			(at 0 0 0)
			(layer "F.Fab")
			(hide yes)
			(effects
				(font
					(size 1.27 1.27)
					(thickness 0.15)
				)
			)
		)
		(property "Author" "Antmicro"
			(at 0 0 0)
			(layer "F.Fab")
			(hide yes)
			(effects
				(font
					(size 1 1)
					(thickness 0.15)
				)
			)
		)
		(property "Current" "2.5A"
			(at 0 0 0)
			(layer "F.Fab")
			(hide yes)
			(effects
				(font
					(size 1 1)
					(thickness 0.15)
				)
			)
		)
		(property "License" "Apache-2.0"
			(at 0 0 0)
			(layer "F.Fab")
			(hide yes)
			(effects
				(font
					(size 1 1)
					(thickness 0.15)
				)
			)
		)
		(property "MPN" "CRCW08050000Z0EA"
			(at 0 0 0)
			(layer "F.Fab")
			(hide yes)
			(effects
				(font
					(size 1 1)
					(thickness 0.15)
				)
			)
		)
		(property "Manufacturer" "Vishay"
			(at 0 0 0)
			(layer "F.Fab")
			(hide yes)
			(effects
				(font
					(size 1 1)
					(thickness 0.15)
				)
			)
		)
		(property "Tolerance" ""
			(at 0 0 0)
			(layer "F.Fab")
			(hide yes)
			(effects
				(font
					(size 1 1)
					(thickness 0.15)
				)
			)
		)
		(property "Val" "0R"
			(at 0 0 0)
			(layer "F.Fab")
			(hide yes)
			(effects
				(font
					(size 1 1)
					(thickness 0.15)
				)
			)
		)
		(sheetname "Supply")
		(sheetfile "supply.kicad_sch")
		(attr smd)
		(fp_line
			(start -0.32 0.699)
			(end 0.28 0.699)
			(stroke
				(width 0.15)
				(type solid)
			)
			(layer "F.SilkS")
		)
		(fp_line
			(start -0.3 -0.701)
			(end 0.298 -0.701)
			(stroke
				(width 0.15)
				(type solid)
			)
			(layer "F.SilkS")
		)
		(fp_rect
			(start -1.75 -0.85)
			(end 1.75 0.85)
			(stroke
				(width 0.05)
				(type solid)
			)
			(fill no)
			(layer "F.CrtYd")
		)
		(fp_line
			(start -0.951 -0.682)
			(end 0.949 -0.682)
			(stroke
				(width 0.15)
				(type solid)
			)
			(layer "F.Fab")
		)
		(fp_line
			(start -0.951 -0.677)
			(end -0.951 0.675)
			(stroke
				(width 0.15)
				(type solid)
			)
			(layer "F.Fab")
		)
		(fp_line
			(start -0.951 0.68)
			(end 0.949 0.68)
			(stroke
				(width 0.15)
				(type solid)
			)
			(layer "F.Fab")
		)
		(fp_line
			(start 0.949 -0.677)
			(end 0.949 0.675)
			(stroke
				(width 0.15)
				(type solid)
			)
			(layer "F.Fab")
		)
		(pad "1" smd roundrect
			(at -1.1 -0.001)
			(size 1 1.4)
			(layers "F.Cu" "F.Mask" "F.Paste")
			(roundrect_rratio 0.15)
			(net 55 "Net-(C141-Pad1)")
			(pintype "passive")
		)
		(pad "2" smd roundrect
			(at 1.1 -0.001)
			(size 1 1.4)
			(layers "F.Cu" "F.Mask" "F.Paste")
			(roundrect_rratio 0.15)
			(net 463 "VCC5V0_INT")
			(pintype "passive")
		)
	)
	(footprint "antmicro-footprints:R_0402_1005Metric"
		(layer "F.Cu")
		(at 140.1825 87.099)
		(descr "Resistor SMD 0402")
		(tags "resistor SMD 0402")
		(property "Reference" "R112"
			(at -3.6825 -0.799 0)
			(layer "F.SilkS")
			(effects
				(font
					(size 0.7 0.7)
					(thickness 0.15)
				)
				(justify left bottom)
			)
		)
		(property "Value" "R_330R_0402"
			(at 0 1.4 0)
			(layer "F.Fab")
			(effects
				(font
					(size 0.7 0.7)
					(thickness 0.15)
				)
				(justify left bottom)
			)
		)
		(property "Description" "330R resistor in 0402 package with 1% tolerance"
			(at 0 0 0)
			(layer "F.Fab")
			(hide yes)
			(effects
				(font
					(size 1.27 1.27)
					(thickness 0.15)
				)
			)
		)
		(property "Author" "Antmicro"
			(at 0 0 0)
			(layer "F.Fab")
			(hide yes)
			(effects
				(font
					(size 1 1)
					(thickness 0.15)
				)
			)
		)
		(property "License" "Apache-2.0"
			(at 0 0 0)
			(layer "F.Fab")
			(hide yes)
			(effects
				(font
					(size 1 1)
					(thickness 0.15)
				)
			)
		)
		(property "MPN" "CR0402-FX-3300GLF"
			(at 0 0 0)
			(layer "F.Fab")
			(hide yes)
			(effects
				(font
					(size 1 1)
					(thickness 0.15)
				)
			)
		)
		(property "Manufacturer" "Bourns"
			(at 0 0 0)
			(layer "F.Fab")
			(hide yes)
			(effects
				(font
					(size 1 1)
					(thickness 0.15)
				)
			)
		)
		(property "Tolerance" "1%"
			(at 0 0 0)
			(layer "F.Fab")
			(hide yes)
			(effects
				(font
					(size 1 1)
					(thickness 0.15)
				)
			)
		)
		(property "Val" "330R"
			(at 0 0 0)
			(layer "F.Fab")
			(hide yes)
			(effects
				(font
					(size 1 1)
					(thickness 0.15)
				)
			)
		)
		(sheetname "Supply")
		(sheetfile "supply.kicad_sch")
		(attr smd)
		(fp_rect
			(start -0.93 -0.47)
			(end 0.93 0.47)
			(stroke
				(width 0.05)
				(type solid)
			)
			(fill no)
			(layer "F.CrtYd")
		)
		(fp_rect
			(start -0.5 -0.25)
			(end 0.5 0.25)
			(stroke
				(width 0.15)
				(type solid)
			)
			(fill no)
			(layer "F.Fab")
		)
		(pad "1" smd roundrect
			(at -0.485 0)
			(size 0.59 0.64)
			(layers "F.Cu" "F.Mask" "F.Paste")
			(roundrect_rratio 0.25)
			(net 556 "Net-(PWR4-Pad2)")
			(pintype "passive")
		)
		(pad "2" smd roundrect
			(at 0.485 0)
			(size 0.59 0.64)
			(layers "F.Cu" "F.Mask" "F.Paste")
			(roundrect_rratio 0.25)
			(net 236 "Net-(Q10-D)")
			(pintype "passive")
		)
	)
	(footprint "antmicro-footprints:V-QFN2030-12"
		(layer "F.Cu")
		(at 186.170008 115.098672 90)
		(property "Reference" "U11"
			(at -2.801328 1.229992 180)
			(layer "F.SilkS")
			(effects
				(font
					(size 0.7 0.7)
					(thickness 0.15)
				)
				(justify left bottom)
			)
		)
		(property "Value" "AP62600SJ-7"
			(at -4 2.2 90)
			(layer "F.Fab")
			(effects
				(font
					(size 0.7 0.7)
					(thickness 0.15)
				)
				(justify left bottom)
			)
		)
		(property "Description" "Buck Switching Regulator IC Positive Fixed 0.6V 1 Output 6A 12-VFQFN"
			(at 0 0 90)
			(layer "F.Fab")
			(hide yes)
			(effects
				(font
					(size 1.27 1.27)
					(thickness 0.15)
				)
			)
		)
		(property "Author" "Antmicro"
			(at 301.26868 -71.071336 0)
			(layer "F.Fab")
			(hide yes)
			(effects
				(font
					(size 1 1)
					(thickness 0.15)
				)
			)
		)
		(property "License" "Apache-2.0"
			(at 301.26868 -71.071336 0)
			(layer "F.Fab")
			(hide yes)
			(effects
				(font
					(size 1 1)
					(thickness 0.15)
				)
			)
		)
		(property "MPN" "AP62600SJ-7"
			(at 301.26868 -71.071336 0)
			(layer "F.Fab")
			(hide yes)
			(effects
				(font
					(size 1 1)
					(thickness 0.15)
				)
			)
		)
		(property "Manufacturer" "Diodes Incorporated"
			(at 301.26868 -71.071336 0)
			(layer "F.Fab")
			(hide yes)
			(effects
				(font
					(size 1 1)
					(thickness 0.15)
				)
			)
		)
		(sheetname "Supply")
		(sheetfile "supply.kicad_sch")
		(attr smd)
		(fp_line
			(start 1.8 -1.276)
			(end 1.8 -1.025)
			(stroke
				(width 0.15)
				(type solid)
			)
			(layer "F.SilkS")
		)
		(fp_line
			(start -1.801 -1.2)
			(end -0.802 -1.2)
			(stroke
				(width 0.15)
				(type solid)
			)
			(layer "F.SilkS")
		)
		(fp_line
			(start -1.801 -1)
			(end -1.801 -1.2)
			(stroke
				(width 0.15)
				(type solid)
			)
			(layer "F.SilkS")
		)
		(fp_line
			(start 1.8 0.998)
			(end 1.8 1.199)
			(stroke
				(width 0.15)
				(type solid)
			)
			(layer "F.SilkS")
		)
		(fp_line
			(start 1.8 1.199)
			(end 0.8 1.199)
			(stroke
				(width 0.15)
				(type solid)
			)
			(layer "F.SilkS")
		)
		(fp_line
			(start -0.802 1.199)
			(end -1.801 1.199)
			(stroke
				(width 0.15)
				(type solid)
			)
			(layer "F.SilkS")
		)
		(fp_line
			(start -1.801 1.199)
			(end -1.801 0.998)
			(stroke
				(width 0.15)
				(type solid)
			)
			(layer "F.SilkS")
		)
		(fp_circle
			(center 0.497 -1.7)
			(end 0.548 -1.7)
			(stroke
				(width 0.15)
				(type solid)
			)
			(fill yes)
			(layer "F.SilkS")
		)
		(fp_rect
			(start -2.026 -1.525)
			(end 2.023 1.524)
			(stroke
				(width 0.05)
				(type solid)
			)
			(fill no)
			(layer "F.CrtYd")
		)
		(fp_line
			(start 1.3 -1)
			(end 1.5 -0.8)
			(stroke
				(width 0.15)
				(type solid)
			)
			(layer "F.Fab")
		)
		(fp_rect
			(start -1.526 -1.025)
			(end 1.523 1.024)
			(stroke
				(width 0.15)
				(type solid)
			)
			(fill no)
			(layer "F.Fab")
		)
		(pad "1" smd rect
			(at 0.498 -0.552)
			(size 1.6 0.35)
			(layers "F.Cu" "F.Mask" "F.Paste")
			(net 5 "GND")
			(pinfunction "PGND")
			(pintype "passive")
		)
		(pad "2" smd rect
			(at -0.5 -0.552)
			(size 1.6 0.35)
			(layers "F.Cu" "F.Mask" "F.Paste")
			(net 463 "VCC5V0_INT")
			(pinfunction "VIN")
			(pintype "power_in")
		)
		(pad "3" smd rect
			(at -1.45 -0.75)
			(size 0.35 0.8)
			(layers "F.Cu" "F.Mask" "F.Paste")
			(net 596 "/Supply/1V2_EN")
			(pinfunction "EN")
			(pintype "input")
		)
		(pad "4" smd rect
			(at -1.45 -0.25)
			(size 0.35 0.8)
			(layers "F.Cu" "F.Mask" "F.Paste")
			(net 623 "/Supply/1V2_MODE")
			(pinfunction "MODE")
			(pintype "input")
		)
		(pad "5" smd rect
			(at -1.45 0.248)
			(size 0.35 0.8)
			(layers "F.Cu" "F.Mask" "F.Paste")
			(net 616 "/Supply/1V2_FSEL")
			(pinfunction "FSEL")
			(pintype "input")
		)
		(pad "6" smd rect
			(at -1.45 0.748)
			(size 0.35 0.8)
			(layers "F.Cu" "F.Mask" "F.Paste")
			(net 655 "unconnected-(U11-PG-Pad6)")
			(pinfunction "PG")
			(pintype "open_collector+no_connect")
		)
		(pad "7" smd rect
			(at -0.5 0.949 90)
			(size 0.35 0.8)
			(layers "F.Cu" "F.Mask" "F.Paste")
			(net 585 "/Supply/1V2_BST")
			(pinfunction "BST")
			(pintype "input")
		)
		(pad "8" smd rect
			(at 0 0.55)
			(size 1.6 0.35)
			(layers "F.Cu" "F.Mask" "F.Paste")
			(net 586 "/Supply/1V2_SW")
			(pinfunction "SW")
			(pintype "output")
		)
		(pad "9" smd rect
			(at 1.449 0.748 180)
			(size 0.35 0.8)
			(layers "F.Cu" "F.Mask" "F.Paste")
			(net 597 "/Supply/1V2_VCC_INT")
			(pinfunction "VCC")
			(pintype "input")
		)
		(pad "10" smd rect
			(at 1.449 0.248 180)
			(size 0.35 0.8)
			(layers "F.Cu" "F.Mask" "F.Paste")
			(net 624 "/Supply/1V2_SS{slash}TR")
			(pinfunction "SS/TR")
			(pintype "input")
		)
		(pad "11" smd rect
			(at 1.449 -0.25 180)
			(size 0.35 0.8)
			(layers "F.Cu" "F.Mask" "F.Paste")
			(net 5 "GND")
			(pinfunction "GND")
			(pintype "passive")
		)
		(pad "12" smd rect
			(at 1.449 -0.75 180)
			(size 0.35 0.8)
			(layers "F.Cu" "F.Mask" "F.Paste")
			(net 601 "/Supply/1V2_FB")
			(pinfunction "FB")
			(pintype "input")
		)
	)
	(footprint "antmicro-footprints:C_0402_1005Metric"
		(layer "F.Cu")
		(at 114.647806 90.974 180)
		(descr "Capacitor SMD 0402")
		(tags "capacitor SMD 0402")
		(property "Reference" "C153"
			(at 1.447806 -1.226 180)
			(layer "F.SilkS")
			(effects
				(font
					(size 0.7 0.7)
					(thickness 0.15)
				)
				(justify left bottom)
			)
		)
		(property "Value" "C_10u_0402"
			(at 0 1.4 180)
			(layer "F.Fab")
			(effects
				(font
					(size 0.7 0.7)
					(thickness 0.15)
				)
				(justify left bottom)
			)
		)
		(property "Description" " "
			(at 0 0 180)
			(layer "F.Fab")
			(hide yes)
			(effects
				(font
					(size 1.27 1.27)
					(thickness 0.15)
				)
			)
		)
		(property "Author" "Antmicro"
			(at 229.295612 181.948 0)
			(layer "F.Fab")
			(hide yes)
			(effects
				(font
					(size 1 1)
					(thickness 0.15)
				)
			)
		)
		(property "Dielectric" ""
			(at 229.295612 181.948 0)
			(layer "F.Fab")
			(hide yes)
			(effects
				(font
					(size 1 1)
					(thickness 0.15)
				)
			)
		)
		(property "License" "Apache-2.0"
			(at 229.295612 181.948 0)
			(layer "F.Fab")
			(hide yes)
			(effects
				(font
					(size 1 1)
					(thickness 0.15)
				)
			)
		)
		(property "MPN" "CC0402MRX5R5BB106"
			(at 229.295612 181.948 0)
			(layer "F.Fab")
			(hide yes)
			(effects
				(font
					(size 1 1)
					(thickness 0.15)
				)
			)
		)
		(property "Manufacturer" "Yaego"
			(at 229.295612 181.948 0)
			(layer "F.Fab")
			(hide yes)
			(effects
				(font
					(size 1 1)
					(thickness 0.15)
				)
			)
		)
		(property "Val" "10u"
			(at 229.295612 181.948 0)
			(layer "F.Fab")
			(hide yes)
			(effects
				(font
					(size 1 1)
					(thickness 0.15)
				)
			)
		)
		(property "Voltage" ""
			(at 229.295612 181.948 0)
			(layer "F.Fab")
			(hide yes)
			(effects
				(font
					(size 1 1)
					(thickness 0.15)
				)
			)
		)
		(sheetname "Supply")
		(sheetfile "supply.kicad_sch")
		(attr smd)
		(fp_rect
			(start -0.94 -0.47)
			(end 0.94 0.47)
			(stroke
				(width 0.05)
				(type solid)
			)
			(fill no)
			(layer "F.CrtYd")
		)
		(fp_rect
			(start -0.499 -0.249)
			(end 0.499 0.249)
			(stroke
				(width 0.15)
				(type solid)
			)
			(fill no)
			(layer "F.Fab")
		)
		(pad "1" smd roundrect
			(at -0.484 0 180)
			(size 0.59 0.64)
			(layers "F.Cu" "F.Mask" "F.Paste")
			(roundrect_rratio 0.25)
			(net 463 "VCC5V0_INT")
			(pintype "passive")
		)
		(pad "2" smd roundrect
			(at 0.484 0 180)
			(size 0.59 0.64)
			(layers "F.Cu" "F.Mask" "F.Paste")
			(roundrect_rratio 0.25)
			(net 5 "GND")
			(pintype "passive")
		)
	)
	(footprint "antmicro-footprints:C_0402_1005Metric"
		(layer "F.Cu")
		(at 189.3 111.635 90)
		(descr "Capacitor SMD 0402")
		(tags "capacitor SMD 0402")
		(property "Reference" "C175"
			(at 0.735 0.4 90)
			(layer "F.SilkS")
			(effects
				(font
					(size 0.7 0.7)
					(thickness 0.15)
				)
				(justify left bottom)
			)
		)
		(property "Value" "C_22u_0402"
			(at 0 1.4 90)
			(layer "F.Fab")
			(effects
				(font
					(size 0.7 0.7)
					(thickness 0.15)
				)
				(justify left bottom)
			)
		)
		(property "Description" " "
			(at 0 0 90)
			(layer "F.Fab")
			(hide yes)
			(effects
				(font
					(size 1.27 1.27)
					(thickness 0.15)
				)
			)
		)
		(property "Author" "Antmicro"
			(at 300.935 -77.665 0)
			(layer "F.Fab")
			(hide yes)
			(effects
				(font
					(size 1 1)
					(thickness 0.15)
				)
			)
		)
		(property "Dielectric" ""
			(at 300.935 -77.665 0)
			(layer "F.Fab")
			(hide yes)
			(effects
				(font
					(size 1 1)
					(thickness 0.15)
				)
			)
		)
		(property "License" "Apache-2.0"
			(at 300.935 -77.665 0)
			(layer "F.Fab")
			(hide yes)
			(effects
				(font
					(size 1 1)
					(thickness 0.15)
				)
			)
		)
		(property "MPN" "04024W226MAT2A"
			(at 300.935 -77.665 0)
			(layer "F.Fab")
			(hide yes)
			(effects
				(font
					(size 1 1)
					(thickness 0.15)
				)
			)
		)
		(property "Manufacturer" "AVX"
			(at 300.935 -77.665 0)
			(layer "F.Fab")
			(hide yes)
			(effects
				(font
					(size 1 1)
					(thickness 0.15)
				)
			)
		)
		(property "Val" "22u"
			(at 300.935 -77.665 0)
			(layer "F.Fab")
			(hide yes)
			(effects
				(font
					(size 1 1)
					(thickness 0.15)
				)
			)
		)
		(property "Voltage" ""
			(at 300.935 -77.665 0)
			(layer "F.Fab")
			(hide yes)
			(effects
				(font
					(size 1 1)
					(thickness 0.15)
				)
			)
		)
		(sheetname "Supply")
		(sheetfile "supply.kicad_sch")
		(attr smd)
		(fp_rect
			(start -0.94 -0.47)
			(end 0.94 0.47)
			(stroke
				(width 0.05)
				(type solid)
			)
			(fill no)
			(layer "F.CrtYd")
		)
		(fp_rect
			(start -0.499 -0.249)
			(end 0.499 0.249)
			(stroke
				(width 0.15)
				(type solid)
			)
			(fill no)
			(layer "F.Fab")
		)
		(pad "1" smd roundrect
			(at -0.484 0 90)
			(size 0.59 0.64)
			(layers "F.Cu" "F.Mask" "F.Paste")
			(roundrect_rratio 0.25)
			(net 589 "/Supply/1V2_REG")
			(pintype "passive")
		)
		(pad "2" smd roundrect
			(at 0.484 0 90)
			(size 0.59 0.64)
			(layers "F.Cu" "F.Mask" "F.Paste")
			(roundrect_rratio 0.25)
			(net 5 "GND")
			(pintype "passive")
		)
	)
	(footprint "antmicro-footprints:R_0805_2012Metric"
		(layer "F.Cu")
		(at 143.3 63.9)
		(property "Reference" "R156"
			(at -1.4 1.8 0)
			(layer "F.SilkS")
			(effects
				(font
					(size 0.7 0.7)
					(thickness 0.15)
				)
				(justify left bottom)
			)
		)
		(property "Value" "R_0R_0805"
			(at 0 1.8 0)
			(layer "F.Fab")
			(effects
				(font
					(size 0.7 0.7)
					(thickness 0.15)
				)
				(justify left bottom)
			)
		)
		(property "Description" "0R resistor in 0805 package with unspecified tolerance"
			(at 0 0 0)
			(layer "F.Fab")
			(hide yes)
			(effects
				(font
					(size 1.27 1.27)
					(thickness 0.15)
				)
			)
		)
		(property "Author" "Antmicro"
			(at 0 0 0)
			(layer "F.Fab")
			(hide yes)
			(effects
				(font
					(size 1 1)
					(thickness 0.15)
				)
			)
		)
		(property "Current" "2.5A"
			(at 0 0 0)
			(layer "F.Fab")
			(hide yes)
			(effects
				(font
					(size 1 1)
					(thickness 0.15)
				)
			)
		)
		(property "License" "Apache-2.0"
			(at 0 0 0)
			(layer "F.Fab")
			(hide yes)
			(effects
				(font
					(size 1 1)
					(thickness 0.15)
				)
			)
		)
		(property "MPN" "CRCW08050000Z0EA"
			(at 0 0 0)
			(layer "F.Fab")
			(hide yes)
			(effects
				(font
					(size 1 1)
					(thickness 0.15)
				)
			)
		)
		(property "Manufacturer" "Vishay"
			(at 0 0 0)
			(layer "F.Fab")
			(hide yes)
			(effects
				(font
					(size 1 1)
					(thickness 0.15)
				)
			)
		)
		(property "Tolerance" ""
			(at 0 0 0)
			(layer "F.Fab")
			(hide yes)
			(effects
				(font
					(size 1 1)
					(thickness 0.15)
				)
			)
		)
		(property "Val" "0R"
			(at 0 0 0)
			(layer "F.Fab")
			(hide yes)
			(effects
				(font
					(size 1 1)
					(thickness 0.15)
				)
			)
		)
		(sheetname "Supply")
		(sheetfile "supply.kicad_sch")
		(attr smd)
		(fp_line
			(start -0.32 0.699)
			(end 0.28 0.699)
			(stroke
				(width 0.15)
				(type solid)
			)
			(layer "F.SilkS")
		)
		(fp_line
			(start -0.3 -0.701)
			(end 0.298 -0.701)
			(stroke
				(width 0.15)
				(type solid)
			)
			(layer "F.SilkS")
		)
		(fp_rect
			(start -1.75 -0.85)
			(end 1.75 0.85)
			(stroke
				(width 0.05)
				(type solid)
			)
			(fill no)
			(layer "F.CrtYd")
		)
		(fp_line
			(start -0.951 -0.682)
			(end 0.949 -0.682)
			(stroke
				(width 0.15)
				(type solid)
			)
			(layer "F.Fab")
		)
		(fp_line
			(start -0.951 -0.677)
			(end -0.951 0.675)
			(stroke
				(width 0.15)
				(type solid)
			)
			(layer "F.Fab")
		)
		(fp_line
			(start -0.951 0.68)
			(end 0.949 0.68)
			(stroke
				(width 0.15)
				(type solid)
			)
			(layer "F.Fab")
		)
		(fp_line
			(start 0.949 -0.677)
			(end 0.949 0.675)
			(stroke
				(width 0.15)
				(type solid)
			)
			(layer "F.Fab")
		)
		(pad "1" smd roundrect
			(at -1.1 -0.001)
			(size 1 1.4)
			(layers "F.Cu" "F.Mask" "F.Paste")
			(roundrect_rratio 0.15)
			(net 633 "/Supply/0V6_REG")
			(pintype "passive")
		)
		(pad "2" smd roundrect
			(at 1.1 -0.001)
			(size 1 1.4)
			(layers "F.Cu" "F.Mask" "F.Paste")
			(roundrect_rratio 0.15)
			(net 640 "0V6_DDR")
			(pintype "passive")
		)
	)
	(footprint "antmicro-footprints:C_0603_1608Metric"
		(layer "F.Cu")
		(at 140.6 63.5 90)
		(descr "Capacitor SMD 0603")
		(tags "capacitor 0603")
		(property "Reference" "C142"
			(at -3.9 0.4 90)
			(layer "F.SilkS")
			(effects
				(font
					(size 0.7 0.7)
					(thickness 0.15)
				)
				(justify left bottom)
			)
		)
		(property "Value" "C_47u_0603"
			(at 0 1.6 90)
			(layer "F.Fab")
			(effects
				(font
					(size 0.7 0.7)
					(thickness 0.15)
				)
				(justify left bottom)
			)
		)
		(property "Description" " "
			(at 0 0 90)
			(layer "F.Fab")
			(hide yes)
			(effects
				(font
					(size 1.27 1.27)
					(thickness 0.15)
				)
			)
		)
		(property "Author" "Antmicro"
			(at 204.1 -77.1 0)
			(layer "F.Fab")
			(hide yes)
			(effects
				(font
					(size 1 1)
					(thickness 0.15)
				)
			)
		)
		(property "Dielectric" ""
			(at 204.1 -77.1 0)
			(layer "F.Fab")
			(hide yes)
			(effects
				(font
					(size 1 1)
					(thickness 0.15)
				)
			)
		)
		(property "License" "Apache-2.0"
			(at 204.1 -77.1 0)
			(layer "F.Fab")
			(hide yes)
			(effects
				(font
					(size 1 1)
					(thickness 0.15)
				)
			)
		)
		(property "MPN" "GRM188R60J476ME15D"
			(at 204.1 -77.1 0)
			(layer "F.Fab")
			(hide yes)
			(effects
				(font
					(size 1 1)
					(thickness 0.15)
				)
			)
		)
		(property "Manufacturer" "Murata"
			(at 204.1 -77.1 0)
			(layer "F.Fab")
			(hide yes)
			(effects
				(font
					(size 1 1)
					(thickness 0.15)
				)
			)
		)
		(property "Val" "47u"
			(at 204.1 -77.1 0)
			(layer "F.Fab")
			(hide yes)
			(effects
				(font
					(size 1 1)
					(thickness 0.15)
				)
			)
		)
		(property "Voltage" ""
			(at 204.1 -77.1 0)
			(layer "F.Fab")
			(hide yes)
			(effects
				(font
					(size 1 1)
					(thickness 0.15)
				)
			)
		)
		(sheetname "Supply")
		(sheetfile "supply.kicad_sch")
		(attr smd)
		(fp_line
			(start -0.3 -0.3)
			(end 0.3 -0.3)
			(stroke
				(width 0.15)
				(type solid)
			)
			(layer "F.SilkS")
		)
		(fp_line
			(start -0.3 0.3)
			(end 0.3 0.3)
			(stroke
				(width 0.15)
				(type solid)
			)
			(layer "F.SilkS")
		)
		(fp_rect
			(start -1.24 -0.7)
			(end 1.24 0.7)
			(stroke
				(width 0.05)
				(type solid)
			)
			(fill no)
			(layer "F.CrtYd")
		)
		(fp_rect
			(start -0.8 -0.4)
			(end 0.8 0.4)
			(stroke
				(width 0.15)
				(type solid)
			)
			(fill no)
			(layer "F.Fab")
		)
		(pad "1" smd roundrect
			(at -0.7 0 90)
			(size 0.6 0.8)
			(layers "F.Cu" "F.Mask" "F.Paste")
			(roundrect_rratio 0.2)
			(net 633 "/Supply/0V6_REG")
			(pintype "passive")
		)
		(pad "2" smd roundrect
			(at 0.7 0 90)
			(size 0.6 0.8)
			(layers "F.Cu" "F.Mask" "F.Paste")
			(roundrect_rratio 0.2)
			(net 5 "GND")
			(pintype "passive")
		)
	)
	(footprint "antmicro-footprints:TP_SMD_1mm"
		(layer "F.Cu")
		(at 137.6 49.15 180)
		(property "Reference" "TP15"
			(at -0.4 -0.35 180)
			(layer "F.SilkS")
			(effects
				(font
					(size 0.7 0.7)
					(thickness 0.15)
				)
				(justify left bottom)
			)
		)
		(property "Value" "TP_1mm_SMD"
			(at 0 1.4 180)
			(layer "F.Fab")
			(effects
				(font
					(size 0.7 0.7)
					(thickness 0.15)
				)
				(justify left bottom)
			)
		)
		(property "Description" "Test Point 1mm"
			(at 0 0 180)
			(layer "F.Fab")
			(hide yes)
			(effects
				(font
					(size 1.27 1.27)
					(thickness 0.15)
				)
			)
		)
		(property "Author" "Antmicro"
			(at 275.2 98.3 0)
			(layer "F.Fab")
			(hide yes)
			(effects
				(font
					(size 1 1)
					(thickness 0.15)
				)
			)
		)
		(property "License" "Apache-2.0"
			(at 275.2 98.3 0)
			(layer "F.Fab")
			(hide yes)
			(effects
				(font
					(size 1 1)
					(thickness 0.15)
				)
			)
		)
		(property "MPN" ""
			(at 275.2 98.3 0)
			(layer "F.Fab")
			(hide yes)
			(effects
				(font
					(size 1 1)
					(thickness 0.15)
				)
			)
		)
		(property "Manufacturer" ""
			(at 275.2 98.3 0)
			(layer "F.Fab")
			(hide yes)
			(effects
				(font
					(size 1 1)
					(thickness 0.15)
				)
			)
		)
		(sheetname "Supply")
		(sheetfile "supply.kicad_sch")
		(attr exclude_from_pos_files)
		(pad "1" smd circle
			(at 0 0 180)
			(size 1 1)
			(layers "F.Cu" "F.Mask")
			(net 640 "0V6_DDR")
			(pinfunction "1")
			(pintype "passive")
		)
	)
	(footprint "antmicro-footprints:V-QFN2030-12"
		(layer "F.Cu")
		(at 114.611478 88.903992 180)
		(property "Reference" "U9"
			(at -0.888522 -2.296008 180)
			(layer "F.SilkS")
			(effects
				(font
					(size 0.7 0.7)
					(thickness 0.15)
				)
				(justify left bottom)
			)
		)
		(property "Value" "AP62600SJ-7"
			(at -4 2.2 180)
			(layer "F.Fab")
			(effects
				(font
					(size 0.7 0.7)
					(thickness 0.15)
				)
				(justify left bottom)
			)
		)
		(property "Description" "Buck Switching Regulator IC Positive Fixed 0.6V 1 Output 6A 12-VFQFN"
			(at 0 0 180)
			(layer "F.Fab")
			(hide yes)
			(effects
				(font
					(size 1.27 1.27)
					(thickness 0.15)
				)
			)
		)
		(property "Author" "Antmicro"
			(at 229.222956 177.807984 0)
			(layer "F.Fab")
			(hide yes)
			(effects
				(font
					(size 1 1)
					(thickness 0.15)
				)
			)
		)
		(property "License" "Apache-2.0"
			(at 229.222956 177.807984 0)
			(layer "F.Fab")
			(hide yes)
			(effects
				(font
					(size 1 1)
					(thickness 0.15)
				)
			)
		)
		(property "MPN" "AP62600SJ-7"
			(at 229.222956 177.807984 0)
			(layer "F.Fab")
			(hide yes)
			(effects
				(font
					(size 1 1)
					(thickness 0.15)
				)
			)
		)
		(property "Manufacturer" "Diodes Incorporated"
			(at 229.222956 177.807984 0)
			(layer "F.Fab")
			(hide yes)
			(effects
				(font
					(size 1 1)
					(thickness 0.15)
				)
			)
		)
		(sheetname "Supply")
		(sheetfile "supply.kicad_sch")
		(attr smd)
		(fp_line
			(start 1.8 1.199)
			(end 0.8 1.199)
			(stroke
				(width 0.15)
				(type solid)
			)
			(layer "F.SilkS")
		)
		(fp_line
			(start 1.8 0.998)
			(end 1.8 1.199)
			(stroke
				(width 0.15)
				(type solid)
			)
			(layer "F.SilkS")
		)
		(fp_line
			(start 1.8 -1.276)
			(end 1.8 -1.025)
			(stroke
				(width 0.15)
				(type solid)
			)
			(layer "F.SilkS")
		)
		(fp_line
			(start -0.802 1.199)
			(end -1.801 1.199)
			(stroke
				(width 0.15)
				(type solid)
			)
			(layer "F.SilkS")
		)
		(fp_line
			(start -1.801 1.199)
			(end -1.801 0.998)
			(stroke
				(width 0.15)
				(type solid)
			)
			(layer "F.SilkS")
		)
		(fp_line
			(start -1.801 -1)
			(end -1.801 -1.2)
			(stroke
				(width 0.15)
				(type solid)
			)
			(layer "F.SilkS")
		)
		(fp_line
			(start -1.801 -1.2)
			(end -0.802 -1.2)
			(stroke
				(width 0.15)
				(type solid)
			)
			(layer "F.SilkS")
		)
		(fp_circle
			(center 0.497 -1.7)
			(end 0.548 -1.7)
			(stroke
				(width 0.15)
				(type solid)
			)
			(fill yes)
			(layer "F.SilkS")
		)
		(fp_rect
			(start -2.026 -1.525)
			(end 2.023 1.524)
			(stroke
				(width 0.05)
				(type solid)
			)
			(fill no)
			(layer "F.CrtYd")
		)
		(fp_line
			(start 1.3 -1)
			(end 1.5 -0.8)
			(stroke
				(width 0.15)
				(type solid)
			)
			(layer "F.Fab")
		)
		(fp_rect
			(start -1.526 -1.025)
			(end 1.523 1.024)
			(stroke
				(width 0.15)
				(type solid)
			)
			(fill no)
			(layer "F.Fab")
		)
		(pad "1" smd rect
			(at 0.498 -0.552 90)
			(size 1.6 0.35)
			(layers "F.Cu" "F.Mask" "F.Paste")
			(net 5 "GND")
			(pinfunction "PGND")
			(pintype "passive")
		)
		(pad "2" smd rect
			(at -0.5 -0.552 90)
			(size 1.6 0.35)
			(layers "F.Cu" "F.Mask" "F.Paste")
			(net 463 "VCC5V0_INT")
			(pinfunction "VIN")
			(pintype "power_in")
		)
		(pad "3" smd rect
			(at -1.45 -0.75 90)
			(size 0.35 0.8)
			(layers "F.Cu" "F.Mask" "F.Paste")
			(net 594 "/Supply/1V8_EN")
			(pinfunction "EN")
			(pintype "input")
		)
		(pad "4" smd rect
			(at -1.45 -0.25 90)
			(size 0.35 0.8)
			(layers "F.Cu" "F.Mask" "F.Paste")
			(net 619 "/Supply/1V8_MODE")
			(pinfunction "MODE")
			(pintype "input")
		)
		(pad "5" smd rect
			(at -1.45 0.248 90)
			(size 0.35 0.8)
			(layers "F.Cu" "F.Mask" "F.Paste")
			(net 614 "/Supply/1V8_FSEL")
			(pinfunction "FSEL")
			(pintype "input")
		)
		(pad "6" smd rect
			(at -1.45 0.748 90)
			(size 0.35 0.8)
			(layers "F.Cu" "F.Mask" "F.Paste")
			(net 605 "/Supply/1V8_PG")
			(pinfunction "PG")
			(pintype "open_collector")
		)
		(pad "7" smd rect
			(at -0.5 0.949 180)
			(size 0.35 0.8)
			(layers "F.Cu" "F.Mask" "F.Paste")
			(net 552 "/Supply/1V8_BST")
			(pinfunction "BST")
			(pintype "input")
		)
		(pad "8" smd rect
			(at 0 0.55 90)
			(size 1.6 0.35)
			(layers "F.Cu" "F.Mask" "F.Paste")
			(net 584 "/Supply/1V8_SW")
			(pinfunction "SW")
			(pintype "output")
		)
		(pad "9" smd rect
			(at 1.449 0.748 270)
			(size 0.35 0.8)
			(layers "F.Cu" "F.Mask" "F.Paste")
			(net 595 "/Supply/1V8_VCC_INT")
			(pinfunction "VCC")
			(pintype "input")
		)
		(pad "10" smd rect
			(at 1.449 0.248 270)
			(size 0.35 0.8)
			(layers "F.Cu" "F.Mask" "F.Paste")
			(net 620 "/Supply/1V8_SS{slash}TR")
			(pinfunction "SS/TR")
			(pintype "input")
		)
		(pad "11" smd rect
			(at 1.449 -0.25 270)
			(size 0.35 0.8)
			(layers "F.Cu" "F.Mask" "F.Paste")
			(net 5 "GND")
			(pinfunction "GND")
			(pintype "passive")
		)
		(pad "12" smd rect
			(at 1.449 -0.75 270)
			(size 0.35 0.8)
			(layers "F.Cu" "F.Mask" "F.Paste")
			(net 600 "/Supply/1V8_FB")
			(pinfunction "FB")
			(pintype "input")
		)
	)
	(footprint "antmicro-footprints:DFN-10-1EP_3x3mm"
		(layer "F.Cu")
		(at 136.5 62.2 -90)
		(property "Reference" "U14"
			(at 1.808 1.88 270)
			(layer "F.SilkS")
			(effects
				(font
					(size 0.7 0.7)
					(thickness 0.15)
				)
				(justify left bottom)
			)
		)
		(property "Value" "MIC61300YML"
			(at 0 2.8 270)
			(layer "F.Fab")
			(effects
				(font
					(size 0.7 0.7)
					(thickness 0.15)
				)
				(justify left bottom)
			)
		)
		(property "Description" "Linear voltage regulator"
			(at 0 0 270)
			(layer "F.Fab")
			(hide yes)
			(effects
				(font
					(size 1.27 1.27)
					(thickness 0.15)
				)
			)
		)
		(property "Author" "Antmicro"
			(at 74.3 198.7 0)
			(layer "F.Fab")
			(hide yes)
			(effects
				(font
					(size 1 1)
					(thickness 0.15)
				)
			)
		)
		(property "License" "Apache-2.0"
			(at 74.3 198.7 0)
			(layer "F.Fab")
			(hide yes)
			(effects
				(font
					(size 1 1)
					(thickness 0.15)
				)
			)
		)
		(property "MPN" "MIC61300YML-TR"
			(at 74.3 198.7 0)
			(layer "F.Fab")
			(hide yes)
			(effects
				(font
					(size 1 1)
					(thickness 0.15)
				)
			)
		)
		(property "Manufacturer" "Microchip Technology"
			(at 74.3 198.7 0)
			(layer "F.Fab")
			(hide yes)
			(effects
				(font
					(size 1 1)
					(thickness 0.15)
				)
			)
		)
		(sheetname "Supply")
		(sheetfile "supply.kicad_sch")
		(attr smd)
		(fp_line
			(start -1.6 1.6)
			(end -1.35 1.6)
			(stroke
				(width 0.15)
				(type solid)
			)
			(layer "F.SilkS")
		)
		(fp_line
			(start -1.6 1.6)
			(end -1.6 1.35)
			(stroke
				(width 0.15)
				(type solid)
			)
			(layer "F.SilkS")
		)
		(fp_line
			(start 1.601 1.6)
			(end 1.401 1.6)
			(stroke
				(width 0.15)
				(type solid)
			)
			(layer "F.SilkS")
		)
		(fp_line
			(start 1.601 1.6)
			(end 1.601 1.35)
			(stroke
				(width 0.15)
				(type solid)
			)
			(layer "F.SilkS")
		)
		(fp_line
			(start -1.624 -1.226)
			(end -1.773 -1.226)
			(stroke
				(width 0.15)
				(type solid)
			)
			(layer "F.SilkS")
		)
		(fp_line
			(start -1.249 -1.601)
			(end -1.624 -1.226)
			(stroke
				(width 0.15)
				(type solid)
			)
			(layer "F.SilkS")
		)
		(fp_line
			(start -1.249 -1.601)
			(end -0.824 -1.601)
			(stroke
				(width 0.15)
				(type solid)
			)
			(layer "F.SilkS")
		)
		(fp_line
			(start 1.601 -1.601)
			(end 1.601 -1.401)
			(stroke
				(width 0.15)
				(type solid)
			)
			(layer "F.SilkS")
		)
		(fp_line
			(start 1.601 -1.601)
			(end 1.351 -1.601)
			(stroke
				(width 0.15)
				(type solid)
			)
			(layer "F.SilkS")
		)
		(fp_circle
			(center -1.8 -1.6)
			(end -1.8 -1.551)
			(stroke
				(width 0.15)
				(type solid)
			)
			(fill yes)
			(layer "F.SilkS")
		)
		(fp_line
			(start -1.91 1.75)
			(end -1.91 -1.73)
			(stroke
				(width 0.05)
				(type solid)
			)
			(layer "F.CrtYd")
		)
		(fp_line
			(start 1.89 1.75)
			(end -1.91 1.75)
			(stroke
				(width 0.05)
				(type solid)
			)
			(layer "F.CrtYd")
		)
		(fp_line
			(start 1.89 1.75)
			(end 1.89 -1.73)
			(stroke
				(width 0.05)
				(type solid)
			)
			(layer "F.CrtYd")
		)
		(fp_line
			(start -1.91 -1.73)
			(end 1.89 -1.73)
			(stroke
				(width 0.05)
				(type solid)
			)
			(layer "F.CrtYd")
		)
		(fp_line
			(start -1.499 1.499)
			(end -1.499 -1.176)
			(stroke
				(width 0.15)
				(type solid)
			)
			(layer "F.Fab")
		)
		(fp_line
			(start 1.5 1.499)
			(end -1.499 1.499)
			(stroke
				(width 0.15)
				(type solid)
			)
			(layer "F.Fab")
		)
		(fp_line
			(start -1.499 -1.18)
			(end -1.179 -1.5)
			(stroke
				(width 0.15)
				(type solid)
			)
			(layer "F.Fab")
		)
		(fp_line
			(start 1.5 -1.5)
			(end 1.5 1.499)
			(stroke
				(width 0.15)
				(type solid)
			)
			(layer "F.Fab")
		)
		(fp_line
			(start 1.5 -1.5)
			(end -1.175 -1.5)
			(stroke
				(width 0.15)
				(type solid)
			)
			(layer "F.Fab")
		)
		(pad "1" smd roundrect
			(at -1.425 -1 180)
			(size 0.25 0.7)
			(layers "F.Cu" "F.Mask" "F.Paste")
			(roundrect_rratio 0.25)
			(net 461 "1V1_SYS")
			(pinfunction "IN")
			(pintype "power_in")
		)
		(pad "2" smd roundrect
			(at -1.425 -0.5 180)
			(size 0.25 0.7)
			(layers "F.Cu" "F.Mask" "F.Paste")
			(roundrect_rratio 0.25)
			(net 461 "1V1_SYS")
			(pinfunction "IN")
			(pintype "passive")
		)
		(pad "3" smd roundrect
			(at -1.425 0 180)
			(size 0.25 0.7)
			(layers "F.Cu" "F.Mask" "F.Paste")
			(roundrect_rratio 0.25)
			(net 5 "GND")
			(pinfunction "GND")
			(pintype "passive")
		)
		(pad "4" smd roundrect
			(at -1.425 0.498 180)
			(size 0.25 0.7)
			(layers "F.Cu" "F.Mask" "F.Paste")
			(roundrect_rratio 0.25)
			(net 636 "/Supply/0V6_EN")
			(pinfunction "EN")
			(pintype "input")
		)
		(pad "5" smd roundrect
			(at -1.425 0.998 180)
			(size 0.25 0.7)
			(layers "F.Cu" "F.Mask" "F.Paste")
			(roundrect_rratio 0.25)
			(net 661 "unconnected-(U14-NC-Pad5)")
			(pinfunction "NC")
			(pintype "no_connect")
		)
		(pad "6" smd roundrect
			(at 1.426 0.998 180)
			(size 0.25 0.7)
			(layers "F.Cu" "F.Mask" "F.Paste")
			(roundrect_rratio 0.25)
			(net 662 "unconnected-(U14-NC-Pad6)")
			(pinfunction "NC")
			(pintype "no_connect")
		)
		(pad "7" smd roundrect
			(at 1.426 0.498 180)
			(size 0.25 0.7)
			(layers "F.Cu" "F.Mask" "F.Paste")
			(roundrect_rratio 0.25)
			(net 639 "/Supply/0V6_CP")
			(pinfunction "CP")
			(pintype "passive")
		)
		(pad "8" smd roundrect
			(at 1.426 0 180)
			(size 0.25 0.7)
			(layers "F.Cu" "F.Mask" "F.Paste")
			(roundrect_rratio 0.25)
			(net 635 "/Supply/0V6_FB")
			(pinfunction "FB")
			(pintype "input")
		)
		(pad "9" smd roundrect
			(at 1.426 -0.5 180)
			(size 0.25 0.7)
			(layers "F.Cu" "F.Mask" "F.Paste")
			(roundrect_rratio 0.25)
			(net 633 "/Supply/0V6_REG")
			(pinfunction "OUT")
			(pintype "passive")
		)
		(pad "10" smd roundrect
			(at 1.426 -1 180)
			(size 0.25 0.7)
			(layers "F.Cu" "F.Mask" "F.Paste")
			(roundrect_rratio 0.25)
			(net 633 "/Supply/0V6_REG")
			(pinfunction "OUT")
			(pintype "power_out")
		)
		(pad "11" smd roundrect
			(at 0 0 180)
			(size 2.38 1.65)
			(layers "F.Cu" "F.Mask" "F.Paste")
			(roundrect_rratio 0.05)
			(net 5 "GND")
			(pinfunction "GND")
			(pintype "passive")
		)
	)
	(footprint "antmicro-footprints:R_0402_1005Metric"
		(layer "F.Cu")
		(at 111.94 102.449)
		(descr "Resistor SMD 0402")
		(tags "resistor SMD 0402")
		(property "Reference" "R134"
			(at -3.64 0.351 0)
			(layer "F.SilkS")
			(effects
				(font
					(size 0.7 0.7)
					(thickness 0.15)
				)
				(justify left bottom)
			)
		)
		(property "Value" "R_31k6_0402"
			(at 0 1.4 0)
			(layer "F.Fab")
			(effects
				(font
					(size 0.7 0.7)
					(thickness 0.15)
				)
				(justify left bottom)
			)
		)
		(property "Description" "31k6 resistor in 0402 package with 1% tolerance"
			(at 0 0 0)
			(layer "F.Fab")
			(hide yes)
			(effects
				(font
					(size 1.27 1.27)
					(thickness 0.15)
				)
			)
		)
		(property "Author" "Antmicro"
			(at 0 0 0)
			(layer "F.Fab")
			(hide yes)
			(effects
				(font
					(size 1 1)
					(thickness 0.15)
				)
			)
		)
		(property "License" "Apache-2.0"
			(at 0 0 0)
			(layer "F.Fab")
			(hide yes)
			(effects
				(font
					(size 1 1)
					(thickness 0.15)
				)
			)
		)
		(property "MPN" "CR0402-FX-3162GLF"
			(at 0 0 0)
			(layer "F.Fab")
			(hide yes)
			(effects
				(font
					(size 1 1)
					(thickness 0.15)
				)
			)
		)
		(property "Manufacturer" "Bourns"
			(at 0 0 0)
			(layer "F.Fab")
			(hide yes)
			(effects
				(font
					(size 1 1)
					(thickness 0.15)
				)
			)
		)
		(property "Tolerance" "1%"
			(at 0 0 0)
			(layer "F.Fab")
			(hide yes)
			(effects
				(font
					(size 1 1)
					(thickness 0.15)
				)
			)
		)
		(property "Val" "31k6"
			(at 0 0 0)
			(layer "F.Fab")
			(hide yes)
			(effects
				(font
					(size 1 1)
					(thickness 0.15)
				)
			)
		)
		(sheetname "Supply")
		(sheetfile "supply.kicad_sch")
		(attr smd)
		(fp_rect
			(start -0.93 -0.47)
			(end 0.93 0.47)
			(stroke
				(width 0.05)
				(type solid)
			)
			(fill no)
			(layer "F.CrtYd")
		)
		(fp_rect
			(start -0.5 -0.25)
			(end 0.5 0.25)
			(stroke
				(width 0.15)
				(type solid)
			)
			(fill no)
			(layer "F.Fab")
		)
		(pad "1" smd roundrect
			(at -0.485 0)
			(size 0.59 0.64)
			(layers "F.Cu" "F.Mask" "F.Paste")
			(roundrect_rratio 0.25)
			(net 576 "/Supply/3V3_REG")
			(pintype "passive")
		)
		(pad "2" smd roundrect
			(at 0.485 0)
			(size 0.59 0.64)
			(layers "F.Cu" "F.Mask" "F.Paste")
			(roundrect_rratio 0.25)
			(net 578 "/Supply/3V3_FB")
			(pintype "passive")
		)
	)
	(footprint "antmicro-footprints:R_0402_1005Metric"
		(layer "F.Cu")
		(at 123.65 89.974 180)
		(descr "Resistor SMD 0402")
		(tags "resistor SMD 0402")
		(property "Reference" "R139"
			(at 3.65 -0.326 180)
			(layer "F.SilkS")
			(effects
				(font
					(size 0.7 0.7)
					(thickness 0.15)
				)
				(justify left bottom)
			)
		)
		(property "Value" "R_10k_0402"
			(at 0 1.4 180)
			(layer "F.Fab")
			(effects
				(font
					(size 0.7 0.7)
					(thickness 0.15)
				)
				(justify left bottom)
			)
		)
		(property "Description" "10k resistor in 0402 package with 1% tolerance"
			(at 0 0 180)
			(layer "F.Fab")
			(hide yes)
			(effects
				(font
					(size 1.27 1.27)
					(thickness 0.15)
				)
			)
		)
		(property "Author" "Antmicro"
			(at 247.3 179.948 0)
			(layer "F.Fab")
			(hide yes)
			(effects
				(font
					(size 1 1)
					(thickness 0.15)
				)
			)
		)
		(property "License" "Apache-2.0"
			(at 247.3 179.948 0)
			(layer "F.Fab")
			(hide yes)
			(effects
				(font
					(size 1 1)
					(thickness 0.15)
				)
			)
		)
		(property "MPN" "CR0402-FX-1002GLF"
			(at 247.3 179.948 0)
			(layer "F.Fab")
			(hide yes)
			(effects
				(font
					(size 1 1)
					(thickness 0.15)
				)
			)
		)
		(property "Manufacturer" "Bourns"
			(at 247.3 179.948 0)
			(layer "F.Fab")
			(hide yes)
			(effects
				(font
					(size 1 1)
					(thickness 0.15)
				)
			)
		)
		(property "Tolerance" "1%"
			(at 247.3 179.948 0)
			(layer "F.Fab")
			(hide yes)
			(effects
				(font
					(size 1 1)
					(thickness 0.15)
				)
			)
		)
		(property "Val" "10k"
			(at 247.3 179.948 0)
			(layer "F.Fab")
			(hide yes)
			(effects
				(font
					(size 1 1)
					(thickness 0.15)
				)
			)
		)
		(sheetname "Supply")
		(sheetfile "supply.kicad_sch")
		(attr smd)
		(fp_rect
			(start -0.93 -0.47)
			(end 0.93 0.47)
			(stroke
				(width 0.05)
				(type solid)
			)
			(fill no)
			(layer "F.CrtYd")
		)
		(fp_rect
			(start -0.5 -0.25)
			(end 0.5 0.25)
			(stroke
				(width 0.15)
				(type solid)
			)
			(fill no)
			(layer "F.Fab")
		)
		(pad "1" smd roundrect
			(at -0.485 0 180)
			(size 0.59 0.64)
			(layers "F.Cu" "F.Mask" "F.Paste")
			(roundrect_rratio 0.25)
			(net 598 "/Supply/1V1_FB")
			(pintype "passive")
		)
		(pad "2" smd roundrect
			(at 0.485 0 180)
			(size 0.59 0.64)
			(layers "F.Cu" "F.Mask" "F.Paste")
			(roundrect_rratio 0.25)
			(net 5 "GND")
			(pintype "passive")
		)
	)
	(footprint "antmicro-footprints:R_0402_1005Metric"
		(layer "F.Cu")
		(at 185 118.185 90)
		(descr "Resistor SMD 0402")
		(tags "resistor SMD 0402")
		(property "Reference" "R126"
			(at -3.615 0.436828 90)
			(layer "F.SilkS")
			(effects
				(font
					(size 0.7 0.7)
					(thickness 0.15)
				)
				(justify left bottom)
			)
		)
		(property "Value" "R_100k_0402"
			(at 0 1.4 90)
			(layer "F.Fab")
			(effects
				(font
					(size 0.7 0.7)
					(thickness 0.15)
				)
				(justify left bottom)
			)
		)
		(property "Description" "100k resistor in 0402 package with 1% tolerance"
			(at 0 0 90)
			(layer "F.Fab")
			(hide yes)
			(effects
				(font
					(size 1.27 1.27)
					(thickness 0.15)
				)
			)
		)
		(property "Author" "Antmicro"
			(at 303.185 -66.815 0)
			(layer "F.Fab")
			(hide yes)
			(effects
				(font
					(size 1 1)
					(thickness 0.15)
				)
			)
		)
		(property "License" "Apache-2.0"
			(at 303.185 -66.815 0)
			(layer "F.Fab")
			(hide yes)
			(effects
				(font
					(size 1 1)
					(thickness 0.15)
				)
			)
		)
		(property "MPN" "CR0402-FX-1003GLF"
			(at 303.185 -66.815 0)
			(layer "F.Fab")
			(hide yes)
			(effects
				(font
					(size 1 1)
					(thickness 0.15)
				)
			)
		)
		(property "Manufacturer" "Bourns"
			(at 303.185 -66.815 0)
			(layer "F.Fab")
			(hide yes)
			(effects
				(font
					(size 1 1)
					(thickness 0.15)
				)
			)
		)
		(property "Tolerance" "1%"
			(at 303.185 -66.815 0)
			(layer "F.Fab")
			(hide yes)
			(effects
				(font
					(size 1 1)
					(thickness 0.15)
				)
			)
		)
		(property "Val" "100k"
			(at 303.185 -66.815 0)
			(layer "F.Fab")
			(hide yes)
			(effects
				(font
					(size 1 1)
					(thickness 0.15)
				)
			)
		)
		(sheetname "Supply")
		(sheetfile "supply.kicad_sch")
		(attr smd)
		(fp_rect
			(start -0.93 -0.47)
			(end 0.93 0.47)
			(stroke
				(width 0.05)
				(type solid)
			)
			(fill no)
			(layer "F.CrtYd")
		)
		(fp_rect
			(start -0.5 -0.25)
			(end 0.5 0.25)
			(stroke
				(width 0.15)
				(type solid)
			)
			(fill no)
			(layer "F.Fab")
		)
		(pad "1" smd roundrect
			(at -0.485 0 90)
			(size 0.59 0.64)
			(layers "F.Cu" "F.Mask" "F.Paste")
			(roundrect_rratio 0.25)
			(net 470 "/Supply/VCC_IO_EN")
			(pintype "passive")
		)
		(pad "2" smd roundrect
			(at 0.485 0 90)
			(size 0.59 0.64)
			(layers "F.Cu" "F.Mask" "F.Paste")
			(roundrect_rratio 0.25)
			(net 596 "/Supply/1V2_EN")
			(pintype "passive")
		)
	)
	(footprint "antmicro-footprints:L_WE-MAIA-3015"
		(layer "F.Cu")
		(at 126.29 84.374 180)
		(property "Reference" "L4"
			(at -1.98 0.554 0)
			(unlocked yes)
			(layer "F.SilkS")
			(effects
				(font
					(size 0.7 0.7)
					(thickness 0.15)
				)
				(justify left bottom)
			)
		)
		(property "Value" "784383350047"
			(at -1.9 2.7 180)
			(unlocked yes)
			(layer "F.Fab")
			(effects
				(font
					(size 0.7 0.7)
					(thickness 0.15)
				)
				(justify left bottom)
			)
		)
		(property "Description" "Power Inductor (SMT), AEC-Q200, 470 nH, 4.6 A, Shielded, 5.8 A, WE-MAIA"
			(at 0 0 180)
			(layer "F.Fab")
			(hide yes)
			(effects
				(font
					(size 1.27 1.27)
					(thickness 0.15)
				)
			)
		)
		(property "Author" "Antmicro"
			(at 252.58 168.748 0)
			(layer "F.Fab")
			(hide yes)
			(effects
				(font
					(size 1 1)
					(thickness 0.15)
				)
			)
		)
		(property "IMax" "4.6 A"
			(at 252.58 168.748 0)
			(layer "F.Fab")
			(hide yes)
			(effects
				(font
					(size 1 1)
					(thickness 0.15)
				)
			)
		)
		(property "ISat" "5.8 A"
			(at 252.58 168.748 0)
			(layer "F.Fab")
			(hide yes)
			(effects
				(font
					(size 1 1)
					(thickness 0.15)
				)
			)
		)
		(property "License" "Apache-2.0"
			(at 252.58 168.748 0)
			(layer "F.Fab")
			(hide yes)
			(effects
				(font
					(size 1 1)
					(thickness 0.15)
				)
			)
		)
		(property "MPN" "784383350047"
			(at 252.58 168.748 0)
			(layer "F.Fab")
			(hide yes)
			(effects
				(font
					(size 1 1)
					(thickness 0.15)
				)
			)
		)
		(property "Manufacturer" "Würth Elektronik"
			(at 252.58 168.748 0)
			(layer "F.Fab")
			(hide yes)
			(effects
				(font
					(size 1 1)
					(thickness 0.15)
				)
			)
		)
		(property "Size" "3.0x3.0"
			(at 252.58 168.748 0)
			(layer "F.Fab")
			(hide yes)
			(effects
				(font
					(size 1 1)
					(thickness 0.15)
				)
			)
		)
		(property "Val" "470n/4.6A"
			(at 252.58 168.748 0)
			(layer "F.Fab")
			(hide yes)
			(effects
				(font
					(size 1 1)
					(thickness 0.15)
				)
			)
		)
		(sheetname "Supply")
		(sheetfile "supply.kicad_sch")
		(attr smd)
		(fp_line
			(start -0.175 1.625)
			(end 0.175 1.625)
			(stroke
				(width 0.15)
				(type solid)
			)
			(layer "F.SilkS")
		)
		(fp_line
			(start -0.175 -1.625)
			(end 0.175 -1.625)
			(stroke
				(width 0.15)
				(type solid)
			)
			(layer "F.SilkS")
		)
		(fp_rect
			(start -1.95 -1.95)
			(end 1.95 1.95)
			(stroke
				(width 0.05)
				(type solid)
			)
			(fill no)
			(layer "F.CrtYd")
		)
		(fp_rect
			(start -1.5 -1.5)
			(end 1.5 1.5)
			(stroke
				(width 0.15)
				(type solid)
			)
			(fill no)
			(layer "F.Fab")
		)
		(pad "1" smd roundrect
			(at -1.05 0 180)
			(size 1.3 3.4)
			(layers "F.Cu" "F.Mask" "F.Paste")
			(roundrect_rratio 0.1)
			(net 579 "/Supply/1V1_SW")
			(pintype "passive")
		)
		(pad "2" smd roundrect
			(at 1.05 0 180)
			(size 1.3 3.4)
			(layers "F.Cu" "F.Mask" "F.Paste")
			(roundrect_rratio 0.1)
			(net 587 "/Supply/1V1_REG")
			(pintype "passive")
		)
	)
	(footprint "antmicro-footprints:C_0402_1005Metric"
		(layer "F.Cu")
		(at 127.6825 98.299)
		(descr "Capacitor SMD 0402")
		(tags "capacitor SMD 0402")
		(property "Reference" "C161"
			(at -3.5825 0.401 0)
			(layer "F.SilkS")
			(effects
				(font
					(size 0.7 0.7)
					(thickness 0.15)
				)
				(justify left bottom)
			)
		)
		(property "Value" "C_100n_6V3_0402"
			(at 0 1.4 0)
			(layer "F.Fab")
			(effects
				(font
					(size 0.7 0.7)
					(thickness 0.15)
				)
				(justify left bottom)
			)
		)
		(property "Description" " "
			(at 0 0 0)
			(layer "F.Fab")
			(hide yes)
			(effects
				(font
					(size 1.27 1.27)
					(thickness 0.15)
				)
			)
		)
		(property "Author" "Antmicro"
			(at 0 0 0)
			(layer "F.Fab")
			(hide yes)
			(effects
				(font
					(size 1 1)
					(thickness 0.15)
				)
			)
		)
		(property "Dielectric" ""
			(at 0 0 0)
			(layer "F.Fab")
			(hide yes)
			(effects
				(font
					(size 1 1)
					(thickness 0.15)
				)
			)
		)
		(property "License" "Apache-2.0"
			(at 0 0 0)
			(layer "F.Fab")
			(hide yes)
			(effects
				(font
					(size 1 1)
					(thickness 0.15)
				)
			)
		)
		(property "MPN" "0402X104K6R3CT"
			(at 0 0 0)
			(layer "F.Fab")
			(hide yes)
			(effects
				(font
					(size 1 1)
					(thickness 0.15)
				)
			)
		)
		(property "Manufacturer" "Walsin"
			(at 0 0 0)
			(layer "F.Fab")
			(hide yes)
			(effects
				(font
					(size 1 1)
					(thickness 0.15)
				)
			)
		)
		(property "Val" "100n"
			(at 0 0 0)
			(layer "F.Fab")
			(hide yes)
			(effects
				(font
					(size 1 1)
					(thickness 0.15)
				)
			)
		)
		(property "Voltage" ""
			(at 0 0 0)
			(layer "F.Fab")
			(hide yes)
			(effects
				(font
					(size 1 1)
					(thickness 0.15)
				)
			)
		)
		(sheetname "Supply")
		(sheetfile "supply.kicad_sch")
		(attr smd)
		(fp_rect
			(start -0.94 -0.47)
			(end 0.94 0.47)
			(stroke
				(width 0.05)
				(type solid)
			)
			(fill no)
			(layer "F.CrtYd")
		)
		(fp_rect
			(start -0.499 -0.249)
			(end 0.499 0.249)
			(stroke
				(width 0.15)
				(type solid)
			)
			(fill no)
			(layer "F.Fab")
		)
		(pad "1" smd roundrect
			(at -0.484 0)
			(size 0.59 0.64)
			(layers "F.Cu" "F.Mask" "F.Paste")
			(roundrect_rratio 0.25)
			(net 582 "/Supply/1V0_SW")
			(pintype "passive")
		)
		(pad "2" smd roundrect
			(at 0.484 0)
			(size 0.59 0.64)
			(layers "F.Cu" "F.Mask" "F.Paste")
			(roundrect_rratio 0.25)
			(net 581 "/Supply/1V0_BST")
			(pintype "passive")
		)
	)
	(footprint "lpddr4-test-board-footprints:mounting-hole-3.2mm"
		(layer "F.Cu")
		(at 110.0492 132.9)
		(property "Reference" "MH4"
			(at -0.178 4.025 0)
			(layer "F.SilkS")
			(hide yes)
			(effects
				(font
					(size 0.7 0.7)
					(thickness 0.15)
				)
				(justify left bottom)
			)
		)
		(property "Value" "M3.2"
			(at -0.153 -4.153 0)
			(layer "F.Fab")
			(effects
				(font
					(size 0.7 0.7)
					(thickness 0.15)
				)
				(justify left bottom)
			)
		)
		(attr through_hole board_only exclude_from_bom)
		(pad "1" thru_hole circle
			(at 0 0)
			(size 6 6)
			(drill 3.2)
			(layers "*.Cu" "*.Mask")
			(remove_unused_layers no)
		)
	)
	(footprint "antmicro-footprints:C_0402_1005Metric"
		(layer "F.Cu")
		(at 123.14 85.724 180)
		(descr "Capacitor SMD 0402")
		(tags "capacitor SMD 0402")
		(property "Reference" "C174"
			(at 1.94 2.524 180)
			(layer "F.SilkS")
			(effects
				(font
					(size 0.7 0.7)
					(thickness 0.15)
				)
				(justify left bottom)
			)
		)
		(property "Value" "C_22u_0402"
			(at 0 1.4 180)
			(layer "F.Fab")
			(effects
				(font
					(size 0.7 0.7)
					(thickness 0.15)
				)
				(justify left bottom)
			)
		)
		(property "Description" " "
			(at 0 0 180)
			(layer "F.Fab")
			(hide yes)
			(effects
				(font
					(size 1.27 1.27)
					(thickness 0.15)
				)
			)
		)
		(property "Author" "Antmicro"
			(at 246.28 171.448 0)
			(layer "F.Fab")
			(hide yes)
			(effects
				(font
					(size 1 1)
					(thickness 0.15)
				)
			)
		)
		(property "Dielectric" ""
			(at 246.28 171.448 0)
			(layer "F.Fab")
			(hide yes)
			(effects
				(font
					(size 1 1)
					(thickness 0.15)
				)
			)
		)
		(property "License" "Apache-2.0"
			(at 246.28 171.448 0)
			(layer "F.Fab")
			(hide yes)
			(effects
				(font
					(size 1 1)
					(thickness 0.15)
				)
			)
		)
		(property "MPN" "04024W226MAT2A"
			(at 246.28 171.448 0)
			(layer "F.Fab")
			(hide yes)
			(effects
				(font
					(size 1 1)
					(thickness 0.15)
				)
			)
		)
		(property "Manufacturer" "AVX"
			(at 246.28 171.448 0)
			(layer "F.Fab")
			(hide yes)
			(effects
				(font
					(size 1 1)
					(thickness 0.15)
				)
			)
		)
		(property "Val" "22u"
			(at 246.28 171.448 0)
			(layer "F.Fab")
			(hide yes)
			(effects
				(font
					(size 1 1)
					(thickness 0.15)
				)
			)
		)
		(property "Voltage" ""
			(at 246.28 171.448 0)
			(layer "F.Fab")
			(hide yes)
			(effects
				(font
					(size 1 1)
					(thickness 0.15)
				)
			)
		)
		(sheetname "Supply")
		(sheetfile "supply.kicad_sch")
		(attr smd)
		(fp_rect
			(start -0.94 -0.47)
			(end 0.94 0.47)
			(stroke
				(width 0.05)
				(type solid)
			)
			(fill no)
			(layer "F.CrtYd")
		)
		(fp_rect
			(start -0.499 -0.249)
			(end 0.499 0.249)
			(stroke
				(width 0.15)
				(type solid)
			)
			(fill no)
			(layer "F.Fab")
		)
		(pad "1" smd roundrect
			(at -0.484 0 180)
			(size 0.59 0.64)
			(layers "F.Cu" "F.Mask" "F.Paste")
			(roundrect_rratio 0.25)
			(net 587 "/Supply/1V1_REG")
			(pintype "passive")
		)
		(pad "2" smd roundrect
			(at 0.484 0 180)
			(size 0.59 0.64)
			(layers "F.Cu" "F.Mask" "F.Paste")
			(roundrect_rratio 0.25)
			(net 5 "GND")
			(pintype "passive")
		)
	)
	(footprint "antmicro-footprints:SOT-523"
		(layer "F.Cu")
		(at 142.3825 92.099 90)
		(property "Reference" "Q9"
			(at 0.599 -1.9825 0)
			(layer "F.SilkS")
			(effects
				(font
					(size 0.7 0.7)
					(thickness 0.15)
				)
				(justify left bottom)
			)
		)
		(property "Value" "DMG1012T-7"
			(at 0.1 1.824 90)
			(layer "F.Fab")
			(effects
				(font
					(size 0.7 0.7)
					(thickness 0.15)
				)
				(justify left bottom)
			)
		)
		(property "Author" "Antmicro"
			(at 234.4815 -50.2835 0)
			(layer "F.Fab")
			(hide yes)
			(effects
				(font
					(size 1 1)
					(thickness 0.15)
				)
			)
		)
		(property "License" "Apache-2.0"
			(at 234.4815 -50.2835 0)
			(layer "F.Fab")
			(hide yes)
			(effects
				(font
					(size 1 1)
					(thickness 0.15)
				)
			)
		)
		(property "MPN" "DMG1012T-7"
			(at 234.4815 -50.2835 0)
			(layer "F.Fab")
			(hide yes)
			(effects
				(font
					(size 1 1)
					(thickness 0.15)
				)
			)
		)
		(property "Manufacturer" "Diodes Incorporated"
			(at 234.4815 -50.2835 0)
			(layer "F.Fab")
			(hide yes)
			(effects
				(font
					(size 1 1)
					(thickness 0.15)
				)
			)
		)
		(sheetname "Supply")
		(sheetfile "supply.kicad_sch")
		(attr smd)
		(fp_line
			(start -0.277 -0.551)
			(end -0.277 -0.75)
			(stroke
				(width 0.15)
				(type solid)
			)
			(layer "F.SilkS")
		)
		(fp_line
			(start -0.725 -0.551)
			(end -0.277 -0.551)
			(stroke
				(width 0.15)
				(type solid)
			)
			(layer "F.SilkS")
		)
		(fp_line
			(start -0.927 -0.351)
			(end -0.725 -0.551)
			(stroke
				(width 0.15)
				(type solid)
			)
			(layer "F.SilkS")
		)
		(fp_line
			(start -0.927 -0.051)
			(end -0.927 -0.351)
			(stroke
				(width 0.15)
				(type solid)
			)
			(layer "F.SilkS")
		)
		(fp_circle
			(center -0.9652 0.9652)
			(end -0.9152 0.9652)
			(stroke
				(width 0.15)
				(type solid)
			)
			(fill yes)
			(layer "F.SilkS")
		)
		(fp_line
			(start 1.1 -1.16)
			(end 1.1 1.15)
			(stroke
				(width 0.05)
				(type solid)
			)
			(layer "F.CrtYd")
		)
		(fp_line
			(start -1.12 -1.16)
			(end 1.1 -1.16)
			(stroke
				(width 0.05)
				(type solid)
			)
			(layer "F.CrtYd")
		)
		(fp_line
			(start -1.12 -1.16)
			(end -1.12 1.15)
			(stroke
				(width 0.05)
				(type solid)
			)
			(layer "F.CrtYd")
		)
		(fp_line
			(start -1.12 1.15)
			(end 1.1 1.15)
			(stroke
				(width 0.05)
				(type solid)
			)
			(layer "F.CrtYd")
		)
		(fp_line
			(start 0.8 -0.425)
			(end -0.652 -0.425)
			(stroke
				(width 0.15)
				(type solid)
			)
			(layer "F.Fab")
		)
		(fp_line
			(start 0.8 -0.425)
			(end 0.8 0.424)
			(stroke
				(width 0.15)
				(type solid)
			)
			(layer "F.Fab")
		)
		(fp_line
			(start -0.652 -0.425)
			(end -0.802 -0.276)
			(stroke
				(width 0.15)
				(type solid)
			)
			(layer "F.Fab")
		)
		(fp_line
			(start -0.802 -0.276)
			(end -0.802 0.424)
			(stroke
				(width 0.15)
				(type solid)
			)
			(layer "F.Fab")
		)
		(fp_line
			(start 0.8 0.424)
			(end -0.802 0.424)
			(stroke
				(width 0.15)
				(type solid)
			)
			(layer "F.Fab")
		)
		(fp_circle
			(center -0.9652 0.9652)
			(end -0.9144 0.9652)
			(stroke
				(width 0.15)
				(type solid)
			)
			(fill no)
			(layer "F.Fab")
		)
		(pad "1" smd rect
			(at -0.5 0.65 90)
			(size 0.4 0.51)
			(layers "F.Cu" "F.Mask" "F.Paste")
			(net 460 "1V8_SYS")
			(pinfunction "G")
			(pintype "bidirectional")
		)
		(pad "2" smd rect
			(at 0.498 0.65 90)
			(size 0.4 0.51)
			(layers "F.Cu" "F.Mask" "F.Paste")
			(net 5 "GND")
			(pinfunction "S")
			(pintype "bidirectional")
		)
		(pad "3" smd rect
			(at 0 -0.652 90)
			(size 0.4 0.51)
			(layers "F.Cu" "F.Mask" "F.Paste")
			(net 235 "Net-(Q9-D)")
			(pinfunction "D")
			(pintype "bidirectional")
		)
	)
	(footprint "antmicro-footprints:C_0805_2012Metric"
		(layer "F.Cu")
		(at 108.9492 112.05 90)
		(descr "Capacitor SMD 0805")
		(tags "capacitor SMD 0805")
		(property "Reference" "C128"
			(at 1.65 0.3508 90)
			(layer "F.SilkS")
			(effects
				(font
					(size 0.7 0.7)
					(thickness 0.15)
				)
				(justify left bottom)
			)
		)
		(property "Value" "C_22u_0805_16V"
			(at 0 1.947 90)
			(layer "F.Fab")
			(effects
				(font
					(size 0.7 0.7)
					(thickness 0.15)
				)
				(justify left bottom)
			)
		)
		(property "Description" " "
			(at 0 0 90)
			(layer "F.Fab")
			(hide yes)
			(effects
				(font
					(size 1.27 1.27)
					(thickness 0.15)
				)
			)
		)
		(property "Author" "Antmicro"
			(at 220.9992 3.1008 0)
			(layer "F.Fab")
			(hide yes)
			(effects
				(font
					(size 1 1)
					(thickness 0.15)
				)
			)
		)
		(property "Dielectric" ""
			(at 220.9992 3.1008 0)
			(layer "F.Fab")
			(hide yes)
			(effects
				(font
					(size 1 1)
					(thickness 0.15)
				)
			)
		)
		(property "License" "Apache-2.0"
			(at 220.9992 3.1008 0)
			(layer "F.Fab")
			(hide yes)
			(effects
				(font
					(size 1 1)
					(thickness 0.15)
				)
			)
		)
		(property "MPN" "GRT21BR61C226ME13L"
			(at 220.9992 3.1008 0)
			(layer "F.Fab")
			(hide yes)
			(effects
				(font
					(size 1 1)
					(thickness 0.15)
				)
			)
		)
		(property "Manufacturer" "Murata"
			(at 220.9992 3.1008 0)
			(layer "F.Fab")
			(hide yes)
			(effects
				(font
					(size 1 1)
					(thickness 0.15)
				)
			)
		)
		(property "Val" "22u/16V"
			(at 220.9992 3.1008 0)
			(layer "F.Fab")
			(hide yes)
			(effects
				(font
					(size 1 1)
					(thickness 0.15)
				)
			)
		)
		(property "Voltage" ""
			(at 220.9992 3.1008 0)
			(layer "F.Fab")
			(hide yes)
			(effects
				(font
					(size 1 1)
					(thickness 0.15)
				)
			)
		)
		(sheetname "Supply")
		(sheetfile "supply.kicad_sch")
		(attr smd)
		(fp_line
			(start -0.3 -0.8)
			(end 0.3 -0.8)
			(stroke
				(width 0.15)
				(type solid)
			)
			(layer "F.SilkS")
		)
		(fp_line
			(start -0.3 0.8)
			(end 0.3 0.8)
			(stroke
				(width 0.15)
				(type solid)
			)
			(layer "F.SilkS")
		)
		(fp_rect
			(start -1.9 -0.93)
			(end 1.9 0.93)
			(stroke
				(width 0.05)
				(type solid)
			)
			(fill no)
			(layer "F.CrtYd")
		)
		(fp_rect
			(start -0.95 -0.675)
			(end 0.95 0.675)
			(stroke
				(width 0.15)
				(type solid)
			)
			(fill no)
			(layer "F.Fab")
		)
		(pad "1" smd rect
			(at -1.05 0 90)
			(size 1.2 1.2)
			(layers "F.Cu" "F.Mask" "F.Paste")
			(net 224 "VIN")
			(pintype "passive")
		)
		(pad "2" smd rect
			(at 1.05 0 90)
			(size 1.2 1.2)
			(layers "F.Cu" "F.Mask" "F.Paste")
			(net 5 "GND")
			(pintype "passive")
		)
	)
	(footprint "antmicro-footprints:C_0603_1608Metric"
		(layer "F.Cu")
		(at 120.0492 113.475 180)
		(descr "Capacitor SMD 0603")
		(tags "capacitor 0603")
		(property "Reference" "C141"
			(at 3.7492 -0.425 180)
			(layer "F.SilkS")
			(effects
				(font
					(size 0.7 0.7)
					(thickness 0.15)
				)
				(justify left bottom)
			)
		)
		(property "Value" "C_47u_0603"
			(at 0 1.6 180)
			(layer "F.Fab")
			(effects
				(font
					(size 0.7 0.7)
					(thickness 0.15)
				)
				(justify left bottom)
			)
		)
		(property "Description" " "
			(at 0 0 180)
			(layer "F.Fab")
			(hide yes)
			(effects
				(font
					(size 1.27 1.27)
					(thickness 0.15)
				)
			)
		)
		(property "Author" "Antmicro"
			(at 240.0984 226.95 0)
			(layer "F.Fab")
			(hide yes)
			(effects
				(font
					(size 1 1)
					(thickness 0.15)
				)
			)
		)
		(property "Dielectric" ""
			(at 240.0984 226.95 0)
			(layer "F.Fab")
			(hide yes)
			(effects
				(font
					(size 1 1)
					(thickness 0.15)
				)
			)
		)
		(property "License" "Apache-2.0"
			(at 240.0984 226.95 0)
			(layer "F.Fab")
			(hide yes)
			(effects
				(font
					(size 1 1)
					(thickness 0.15)
				)
			)
		)
		(property "MPN" "GRM188R60J476ME15D"
			(at 240.0984 226.95 0)
			(layer "F.Fab")
			(hide yes)
			(effects
				(font
					(size 1 1)
					(thickness 0.15)
				)
			)
		)
		(property "Manufacturer" "Murata"
			(at 240.0984 226.95 0)
			(layer "F.Fab")
			(hide yes)
			(effects
				(font
					(size 1 1)
					(thickness 0.15)
				)
			)
		)
		(property "Val" "47u"
			(at 240.0984 226.95 0)
			(layer "F.Fab")
			(hide yes)
			(effects
				(font
					(size 1 1)
					(thickness 0.15)
				)
			)
		)
		(property "Voltage" ""
			(at 240.0984 226.95 0)
			(layer "F.Fab")
			(hide yes)
			(effects
				(font
					(size 1 1)
					(thickness 0.15)
				)
			)
		)
		(sheetname "Supply")
		(sheetfile "supply.kicad_sch")
		(attr smd)
		(fp_line
			(start -0.3 0.3)
			(end 0.3 0.3)
			(stroke
				(width 0.15)
				(type solid)
			)
			(layer "F.SilkS")
		)
		(fp_line
			(start -0.3 -0.3)
			(end 0.3 -0.3)
			(stroke
				(width 0.15)
				(type solid)
			)
			(layer "F.SilkS")
		)
		(fp_rect
			(start -1.24 -0.7)
			(end 1.24 0.7)
			(stroke
				(width 0.05)
				(type solid)
			)
			(fill no)
			(layer "F.CrtYd")
		)
		(fp_rect
			(start -0.8 -0.4)
			(end 0.8 0.4)
			(stroke
				(width 0.15)
				(type solid)
			)
			(fill no)
			(layer "F.Fab")
		)
		(pad "1" smd roundrect
			(at -0.7 0 180)
			(size 0.6 0.8)
			(layers "F.Cu" "F.Mask" "F.Paste")
			(roundrect_rratio 0.2)
			(net 55 "Net-(C141-Pad1)")
			(pintype "passive")
		)
		(pad "2" smd roundrect
			(at 0.7 0 180)
			(size 0.6 0.8)
			(layers "F.Cu" "F.Mask" "F.Paste")
			(roundrect_rratio 0.2)
			(net 5 "GND")
			(pintype "passive")
		)
	)
	(footprint "antmicro-footprints:TP_SMD_1mm"
		(layer "F.Cu")
		(at 124.3492 106.6)
		(property "Reference" "TP13"
			(at 0.5508 0.3 0)
			(layer "F.SilkS")
			(effects
				(font
					(size 0.7 0.7)
					(thickness 0.15)
				)
				(justify left bottom)
			)
		)
		(property "Value" "TP_1mm_SMD"
			(at 0 1.4 0)
			(layer "F.Fab")
			(effects
				(font
					(size 0.7 0.7)
					(thickness 0.15)
				)
				(justify left bottom)
			)
		)
		(property "Description" "Test Point 1mm"
			(at 0 0 0)
			(layer "F.Fab")
			(hide yes)
			(effects
				(font
					(size 1.27 1.27)
					(thickness 0.15)
				)
			)
		)
		(property "Author" "Antmicro"
			(at 0 0 0)
			(layer "F.Fab")
			(hide yes)
			(effects
				(font
					(size 1 1)
					(thickness 0.15)
				)
			)
		)
		(property "License" "Apache-2.0"
			(at 0 0 0)
			(layer "F.Fab")
			(hide yes)
			(effects
				(font
					(size 1 1)
					(thickness 0.15)
				)
			)
		)
		(property "MPN" ""
			(at 0 0 0)
			(layer "F.Fab")
			(hide yes)
			(effects
				(font
					(size 1 1)
					(thickness 0.15)
				)
			)
		)
		(property "Manufacturer" ""
			(at 0 0 0)
			(layer "F.Fab")
			(hide yes)
			(effects
				(font
					(size 1 1)
					(thickness 0.15)
				)
			)
		)
		(sheetname "Supply")
		(sheetfile "supply.kicad_sch")
		(attr exclude_from_pos_files)
		(pad "1" smd circle
			(at 0 0)
			(size 1 1)
			(layers "F.Cu" "F.Mask")
			(net 463 "VCC5V0_INT")
			(pinfunction "1")
			(pintype "passive")
		)
	)
	(footprint "antmicro-footprints:C_0402_1005Metric"
		(layer "F.Cu")
		(at 111.725 96.249 180)
		(descr "Capacitor SMD 0402")
		(tags "capacitor SMD 0402")
		(property "Reference" "C167"
			(at 3.625 -0.351 180)
			(layer "F.SilkS")
			(effects
				(font
					(size 0.7 0.7)
					(thickness 0.15)
				)
				(justify left bottom)
			)
		)
		(property "Value" "C_22u_0402"
			(at 0 1.4 180)
			(layer "F.Fab")
			(effects
				(font
					(size 0.7 0.7)
					(thickness 0.15)
				)
				(justify left bottom)
			)
		)
		(property "Description" " "
			(at 0 0 180)
			(layer "F.Fab")
			(hide yes)
			(effects
				(font
					(size 1.27 1.27)
					(thickness 0.15)
				)
			)
		)
		(property "Author" "Antmicro"
			(at 223.45 192.498 0)
			(layer "F.Fab")
			(hide yes)
			(effects
				(font
					(size 1 1)
					(thickness 0.15)
				)
			)
		)
		(property "Dielectric" ""
			(at 223.45 192.498 0)
			(layer "F.Fab")
			(hide yes)
			(effects
				(font
					(size 1 1)
					(thickness 0.15)
				)
			)
		)
		(property "License" "Apache-2.0"
			(at 223.45 192.498 0)
			(layer "F.Fab")
			(hide yes)
			(effects
				(font
					(size 1 1)
					(thickness 0.15)
				)
			)
		)
		(property "MPN" "04024W226MAT2A"
			(at 223.45 192.498 0)
			(layer "F.Fab")
			(hide yes)
			(effects
				(font
					(size 1 1)
					(thickness 0.15)
				)
			)
		)
		(property "Manufacturer" "AVX"
			(at 223.45 192.498 0)
			(layer "F.Fab")
			(hide yes)
			(effects
				(font
					(size 1 1)
					(thickness 0.15)
				)
			)
		)
		(property "Val" "22u"
			(at 223.45 192.498 0)
			(layer "F.Fab")
			(hide yes)
			(effects
				(font
					(size 1 1)
					(thickness 0.15)
				)
			)
		)
		(property "Voltage" ""
			(at 223.45 192.498 0)
			(layer "F.Fab")
			(hide yes)
			(effects
				(font
					(size 1 1)
					(thickness 0.15)
				)
			)
		)
		(sheetname "Supply")
		(sheetfile "supply.kicad_sch")
		(attr smd)
		(fp_rect
			(start -0.94 -0.47)
			(end 0.94 0.47)
			(stroke
				(width 0.05)
				(type solid)
			)
			(fill no)
			(layer "F.CrtYd")
		)
		(fp_rect
			(start -0.499 -0.249)
			(end 0.499 0.249)
			(stroke
				(width 0.15)
				(type solid)
			)
			(fill no)
			(layer "F.Fab")
		)
		(pad "1" smd roundrect
			(at -0.484 0 180)
			(size 0.59 0.64)
			(layers "F.Cu" "F.Mask" "F.Paste")
			(roundrect_rratio 0.25)
			(net 576 "/Supply/3V3_REG")
			(pintype "passive")
		)
		(pad "2" smd roundrect
			(at 0.484 0 180)
			(size 0.59 0.64)
			(layers "F.Cu" "F.Mask" "F.Paste")
			(roundrect_rratio 0.25)
			(net 5 "GND")
			(pintype "passive")
		)
	)
	(footprint "antmicro-footprints:C_0402_1005Metric"
		(layer "F.Cu")
		(at 127.95 86.874)
		(descr "Capacitor SMD 0402")
		(tags "capacitor SMD 0402")
		(property "Reference" "C159"
			(at -3.65 0.426 0)
			(layer "F.SilkS")
			(effects
				(font
					(size 0.7 0.7)
					(thickness 0.15)
				)
				(justify left bottom)
			)
		)
		(property "Value" "C_100n_6V3_0402"
			(at 0 1.4 0)
			(layer "F.Fab")
			(effects
				(font
					(size 0.7 0.7)
					(thickness 0.15)
				)
				(justify left bottom)
			)
		)
		(property "Description" " "
			(at 0 0 0)
			(layer "F.Fab")
			(hide yes)
			(effects
				(font
					(size 1.27 1.27)
					(thickness 0.15)
				)
			)
		)
		(property "Author" "Antmicro"
			(at 0 0 0)
			(layer "F.Fab")
			(hide yes)
			(effects
				(font
					(size 1 1)
					(thickness 0.15)
				)
			)
		)
		(property "Dielectric" ""
			(at 0 0 0)
			(layer "F.Fab")
			(hide yes)
			(effects
				(font
					(size 1 1)
					(thickness 0.15)
				)
			)
		)
		(property "License" "Apache-2.0"
			(at 0 0 0)
			(layer "F.Fab")
			(hide yes)
			(effects
				(font
					(size 1 1)
					(thickness 0.15)
				)
			)
		)
		(property "MPN" "0402X104K6R3CT"
			(at 0 0 0)
			(layer "F.Fab")
			(hide yes)
			(effects
				(font
					(size 1 1)
					(thickness 0.15)
				)
			)
		)
		(property "Manufacturer" "Walsin"
			(at 0 0 0)
			(layer "F.Fab")
			(hide yes)
			(effects
				(font
					(size 1 1)
					(thickness 0.15)
				)
			)
		)
		(property "Val" "100n"
			(at 0 0 0)
			(layer "F.Fab")
			(hide yes)
			(effects
				(font
					(size 1 1)
					(thickness 0.15)
				)
			)
		)
		(property "Voltage" ""
			(at 0 0 0)
			(layer "F.Fab")
			(hide yes)
			(effects
				(font
					(size 1 1)
					(thickness 0.15)
				)
			)
		)
		(sheetname "Supply")
		(sheetfile "supply.kicad_sch")
		(attr smd)
		(fp_rect
			(start -0.94 -0.47)
			(end 0.94 0.47)
			(stroke
				(width 0.05)
				(type solid)
			)
			(fill no)
			(layer "F.CrtYd")
		)
		(fp_rect
			(start -0.499 -0.249)
			(end 0.499 0.249)
			(stroke
				(width 0.15)
				(type solid)
			)
			(fill no)
			(layer "F.Fab")
		)
		(pad "1" smd roundrect
			(at -0.484 0)
			(size 0.59 0.64)
			(layers "F.Cu" "F.Mask" "F.Paste")
			(roundrect_rratio 0.25)
			(net 579 "/Supply/1V1_SW")
			(pintype "passive")
		)
		(pad "2" smd roundrect
			(at 0.484 0)
			(size 0.59 0.64)
			(layers "F.Cu" "F.Mask" "F.Paste")
			(roundrect_rratio 0.25)
			(net 580 "/Supply/1V1_BST")
			(pintype "passive")
		)
	)
	(footprint "antmicro-footprints:TP_SMD_1mm"
		(layer "F.Cu")
		(at 109.0992 104.4)
		(property "Reference" "TP20"
			(at -0.5992 1.2 270)
			(layer "F.SilkS")
			(effects
				(font
					(size 0.7 0.7)
					(thickness 0.15)
				)
				(justify left bottom)
			)
		)
		(property "Value" "TP_1mm_SMD"
			(at 0 1.4 0)
			(layer "F.Fab")
			(effects
				(font
					(size 0.7 0.7)
					(thickness 0.15)
				)
				(justify left bottom)
			)
		)
		(property "Description" "Test Point 1mm"
			(at 0 0 0)
			(layer "F.Fab")
			(hide yes)
			(effects
				(font
					(size 1.27 1.27)
					(thickness 0.15)
				)
			)
		)
		(property "Author" "Antmicro"
			(at 0 0 0)
			(layer "F.Fab")
			(hide yes)
			(effects
				(font
					(size 1 1)
					(thickness 0.15)
				)
			)
		)
		(property "License" "Apache-2.0"
			(at 0 0 0)
			(layer "F.Fab")
			(hide yes)
			(effects
				(font
					(size 1 1)
					(thickness 0.15)
				)
			)
		)
		(property "MPN" ""
			(at 0 0 0)
			(layer "F.Fab")
			(hide yes)
			(effects
				(font
					(size 1 1)
					(thickness 0.15)
				)
			)
		)
		(property "Manufacturer" ""
			(at 0 0 0)
			(layer "F.Fab")
			(hide yes)
			(effects
				(font
					(size 1 1)
					(thickness 0.15)
				)
			)
		)
		(sheetname "Supply")
		(sheetfile "supply.kicad_sch")
		(attr exclude_from_pos_files)
		(pad "1" smd circle
			(at 0 0)
			(size 1 1)
			(layers "F.Cu" "F.Mask")
			(net 5 "GND")
			(pinfunction "1")
			(pintype "passive")
		)
	)
	(footprint "antmicro-footprints:R_0402_1005Metric"
		(layer "F.Cu")
		(at 123.6475 100.449)
		(descr "Resistor SMD 0402")
		(tags "resistor SMD 0402")
		(property "Reference" "R127"
			(at -3.5475 0.351 0)
			(layer "F.SilkS")
			(effects
				(font
					(size 0.7 0.7)
					(thickness 0.15)
				)
				(justify left bottom)
			)
		)
		(property "Value" "R_0R_0402"
			(at 0 1.4 0)
			(layer "F.Fab")
			(effects
				(font
					(size 0.7 0.7)
					(thickness 0.15)
				)
				(justify left bottom)
			)
		)
		(property "Description" "0R resistor in 0402 package with unspecified tolerance"
			(at 0 0 0)
			(layer "F.Fab")
			(hide yes)
			(effects
				(font
					(size 1.27 1.27)
					(thickness 0.15)
				)
			)
		)
		(property "Author" "Antmicro"
			(at 0 0 0)
			(layer "F.Fab")
			(hide yes)
			(effects
				(font
					(size 1 1)
					(thickness 0.15)
				)
			)
		)
		(property "Current" "1A"
			(at 0 0 0)
			(layer "F.Fab")
			(hide yes)
			(effects
				(font
					(size 1 1)
					(thickness 0.15)
				)
			)
		)
		(property "License" "Apache-2.0"
			(at 0 0 0)
			(layer "F.Fab")
			(hide yes)
			(effects
				(font
					(size 1 1)
					(thickness 0.15)
				)
			)
		)
		(property "MPN" "ERJ2GE0R00X"
			(at 0 0 0)
			(layer "F.Fab")
			(hide yes)
			(effects
				(font
					(size 1 1)
					(thickness 0.15)
				)
			)
		)
		(property "Manufacturer" "Panasonic"
			(at 0 0 0)
			(layer "F.Fab")
			(hide yes)
			(effects
				(font
					(size 1 1)
					(thickness 0.15)
				)
			)
		)
		(property "Tolerance" ""
			(at 0 0 0)
			(layer "F.Fab")
			(hide yes)
			(effects
				(font
					(size 1 1)
					(thickness 0.15)
				)
			)
		)
		(property "Val" "0R"
			(at 0 0 0)
			(layer "F.Fab")
			(hide yes)
			(effects
				(font
					(size 1 1)
					(thickness 0.15)
				)
			)
		)
		(sheetname "Supply")
		(sheetfile "supply.kicad_sch")
		(attr smd)
		(fp_rect
			(start -0.93 -0.47)
			(end 0.93 0.47)
			(stroke
				(width 0.05)
				(type solid)
			)
			(fill no)
			(layer "F.CrtYd")
		)
		(fp_rect
			(start -0.5 -0.25)
			(end 0.5 0.25)
			(stroke
				(width 0.15)
				(type solid)
			)
			(fill no)
			(layer "F.Fab")
		)
		(pad "1" smd roundrect
			(at -0.485 0)
			(size 0.59 0.64)
			(layers "F.Cu" "F.Mask" "F.Paste")
			(roundrect_rratio 0.25)
			(net 5 "GND")
			(pintype "passive")
		)
		(pad "2" smd roundrect
			(at 0.485 0)
			(size 0.59 0.64)
			(layers "F.Cu" "F.Mask" "F.Paste")
			(roundrect_rratio 0.25)
			(net 613 "/Supply/1V0_SS{slash}TR")
			(pintype "passive")
		)
	)
	(footprint "antmicro-footprints:C_0402_1005Metric"
		(layer "F.Cu")
		(at 123.65 87.974 180)
		(descr "Capacitor SMD 0402")
		(tags "capacitor SMD 0402")
		(property "Reference" "C164"
			(at 3.65 -0.326 180)
			(layer "F.SilkS")
			(effects
				(font
					(size 0.7 0.7)
					(thickness 0.15)
				)
				(justify left bottom)
			)
		)
		(property "Value" "C_1u_0402"
			(at 0 1.4 180)
			(layer "F.Fab")
			(effects
				(font
					(size 0.7 0.7)
					(thickness 0.15)
				)
				(justify left bottom)
			)
		)
		(property "Description" " "
			(at 0 0 180)
			(layer "F.Fab")
			(hide yes)
			(effects
				(font
					(size 1.27 1.27)
					(thickness 0.15)
				)
			)
		)
		(property "Author" "Antmicro"
			(at 247.3 175.948 0)
			(layer "F.Fab")
			(hide yes)
			(effects
				(font
					(size 1 1)
					(thickness 0.15)
				)
			)
		)
		(property "Dielectric" ""
			(at 247.3 175.948 0)
			(layer "F.Fab")
			(hide yes)
			(effects
				(font
					(size 1 1)
					(thickness 0.15)
				)
			)
		)
		(property "License" "Apache-2.0"
			(at 247.3 175.948 0)
			(layer "F.Fab")
			(hide yes)
			(effects
				(font
					(size 1 1)
					(thickness 0.15)
				)
			)
		)
		(property "MPN" "C1005X6S1A105K050BC"
			(at 247.3 175.948 0)
			(layer "F.Fab")
			(hide yes)
			(effects
				(font
					(size 1 1)
					(thickness 0.15)
				)
			)
		)
		(property "Manufacturer" "TDK"
			(at 247.3 175.948 0)
			(layer "F.Fab")
			(hide yes)
			(effects
				(font
					(size 1 1)
					(thickness 0.15)
				)
			)
		)
		(property "Val" "1u"
			(at 247.3 175.948 0)
			(layer "F.Fab")
			(hide yes)
			(effects
				(font
					(size 1 1)
					(thickness 0.15)
				)
			)
		)
		(property "Voltage" ""
			(at 247.3 175.948 0)
			(layer "F.Fab")
			(hide yes)
			(effects
				(font
					(size 1 1)
					(thickness 0.15)
				)
			)
		)
		(sheetname "Supply")
		(sheetfile "supply.kicad_sch")
		(attr smd)
		(fp_rect
			(start -0.94 -0.47)
			(end 0.94 0.47)
			(stroke
				(width 0.05)
				(type solid)
			)
			(fill no)
			(layer "F.CrtYd")
		)
		(fp_rect
			(start -0.499 -0.249)
			(end 0.499 0.249)
			(stroke
				(width 0.15)
				(type solid)
			)
			(fill no)
			(layer "F.Fab")
		)
		(pad "1" smd roundrect
			(at -0.484 0 180)
			(size 0.59 0.64)
			(layers "F.Cu" "F.Mask" "F.Paste")
			(roundrect_rratio 0.25)
			(net 591 "/Supply/1V1_VCC_INT")
			(pintype "passive")
		)
		(pad "2" smd roundrect
			(at 0.484 0 180)
			(size 0.59 0.64)
			(layers "F.Cu" "F.Mask" "F.Paste")
			(roundrect_rratio 0.25)
			(net 5 "GND")
			(pintype "passive")
		)
	)
	(footprint "antmicro-footprints:C_0402_1005Metric"
		(layer "F.Cu")
		(at 126.9325 102.449 180)
		(descr "Capacitor SMD 0402")
		(tags "capacitor SMD 0402")
		(property "Reference" "C156"
			(at 1.9325 -1.251 180)
			(layer "F.SilkS")
			(effects
				(font
					(size 0.7 0.7)
					(thickness 0.15)
				)
				(justify left bottom)
			)
		)
		(property "Value" "C_10u_0402"
			(at 0 1.4 180)
			(layer "F.Fab")
			(effects
				(font
					(size 0.7 0.7)
					(thickness 0.15)
				)
				(justify left bottom)
			)
		)
		(property "Description" " "
			(at 0 0 180)
			(layer "F.Fab")
			(hide yes)
			(effects
				(font
					(size 1.27 1.27)
					(thickness 0.15)
				)
			)
		)
		(property "Author" "Antmicro"
			(at 253.865 204.898 0)
			(layer "F.Fab")
			(hide yes)
			(effects
				(font
					(size 1 1)
					(thickness 0.15)
				)
			)
		)
		(property "Dielectric" ""
			(at 253.865 204.898 0)
			(layer "F.Fab")
			(hide yes)
			(effects
				(font
					(size 1 1)
					(thickness 0.15)
				)
			)
		)
		(property "License" "Apache-2.0"
			(at 253.865 204.898 0)
			(layer "F.Fab")
			(hide yes)
			(effects
				(font
					(size 1 1)
					(thickness 0.15)
				)
			)
		)
		(property "MPN" "CC0402MRX5R5BB106"
			(at 253.865 204.898 0)
			(layer "F.Fab")
			(hide yes)
			(effects
				(font
					(size 1 1)
					(thickness 0.15)
				)
			)
		)
		(property "Manufacturer" "Yaego"
			(at 253.865 204.898 0)
			(layer "F.Fab")
			(hide yes)
			(effects
				(font
					(size 1 1)
					(thickness 0.15)
				)
			)
		)
		(property "Val" "10u"
			(at 253.865 204.898 0)
			(layer "F.Fab")
			(hide yes)
			(effects
				(font
					(size 1 1)
					(thickness 0.15)
				)
			)
		)
		(property "Voltage" ""
			(at 253.865 204.898 0)
			(layer "F.Fab")
			(hide yes)
			(effects
				(font
					(size 1 1)
					(thickness 0.15)
				)
			)
		)
		(sheetname "Supply")
		(sheetfile "supply.kicad_sch")
		(attr smd)
		(fp_rect
			(start -0.94 -0.47)
			(end 0.94 0.47)
			(stroke
				(width 0.05)
				(type solid)
			)
			(fill no)
			(layer "F.CrtYd")
		)
		(fp_rect
			(start -0.499 -0.249)
			(end 0.499 0.249)
			(stroke
				(width 0.15)
				(type solid)
			)
			(fill no)
			(layer "F.Fab")
		)
		(pad "1" smd roundrect
			(at -0.484 0 180)
			(size 0.59 0.64)
			(layers "F.Cu" "F.Mask" "F.Paste")
			(roundrect_rratio 0.25)
			(net 463 "VCC5V0_INT")
			(pintype "passive")
		)
		(pad "2" smd roundrect
			(at 0.484 0 180)
			(size 0.59 0.64)
			(layers "F.Cu" "F.Mask" "F.Paste")
			(roundrect_rratio 0.25)
			(net 5 "GND")
			(pintype "passive")
		)
	)
	(footprint "antmicro-footprints:V-QFN2030-12"
		(layer "F.Cu")
		(at 126.863672 88.903992 180)
		(property "Reference" "U10"
			(at -0.836328 -2.496008 180)
			(layer "F.SilkS")
			(effects
				(font
					(size 0.7 0.7)
					(thickness 0.15)
				)
				(justify left bottom)
			)
		)
		(property "Value" "AP62600SJ-7"
			(at -4 2.2 180)
			(layer "F.Fab")
			(effects
				(font
					(size 0.7 0.7)
					(thickness 0.15)
				)
				(justify left bottom)
			)
		)
		(property "Description" "Buck Switching Regulator IC Positive Fixed 0.6V 1 Output 6A 12-VFQFN"
			(at 0 0 180)
			(layer "F.Fab")
			(hide yes)
			(effects
				(font
					(size 1.27 1.27)
					(thickness 0.15)
				)
			)
		)
		(property "Author" "Antmicro"
			(at 253.727344 177.807984 0)
			(layer "F.Fab")
			(hide yes)
			(effects
				(font
					(size 1 1)
					(thickness 0.15)
				)
			)
		)
		(property "License" "Apache-2.0"
			(at 253.727344 177.807984 0)
			(layer "F.Fab")
			(hide yes)
			(effects
				(font
					(size 1 1)
					(thickness 0.15)
				)
			)
		)
		(property "MPN" "AP62600SJ-7"
			(at 253.727344 177.807984 0)
			(layer "F.Fab")
			(hide yes)
			(effects
				(font
					(size 1 1)
					(thickness 0.15)
				)
			)
		)
		(property "Manufacturer" "Diodes Incorporated"
			(at 253.727344 177.807984 0)
			(layer "F.Fab")
			(hide yes)
			(effects
				(font
					(size 1 1)
					(thickness 0.15)
				)
			)
		)
		(sheetname "Supply")
		(sheetfile "supply.kicad_sch")
		(attr smd)
		(fp_line
			(start 1.8 1.199)
			(end 0.8 1.199)
			(stroke
				(width 0.15)
				(type solid)
			)
			(layer "F.SilkS")
		)
		(fp_line
			(start 1.8 0.998)
			(end 1.8 1.199)
			(stroke
				(width 0.15)
				(type solid)
			)
			(layer "F.SilkS")
		)
		(fp_line
			(start 1.8 -1.276)
			(end 1.8 -1.025)
			(stroke
				(width 0.15)
				(type solid)
			)
			(layer "F.SilkS")
		)
		(fp_line
			(start -0.802 1.199)
			(end -1.801 1.199)
			(stroke
				(width 0.15)
				(type solid)
			)
			(layer "F.SilkS")
		)
		(fp_line
			(start -1.801 1.199)
			(end -1.801 0.998)
			(stroke
				(width 0.15)
				(type solid)
			)
			(layer "F.SilkS")
		)
		(fp_line
			(start -1.801 -1)
			(end -1.801 -1.2)
			(stroke
				(width 0.15)
				(type solid)
			)
			(layer "F.SilkS")
		)
		(fp_line
			(start -1.801 -1.2)
			(end -0.802 -1.2)
			(stroke
				(width 0.15)
				(type solid)
			)
			(layer "F.SilkS")
		)
		(fp_circle
			(center 0.497 -1.7)
			(end 0.548 -1.7)
			(stroke
				(width 0.15)
				(type solid)
			)
			(fill yes)
			(layer "F.SilkS")
		)
		(fp_rect
			(start -2.026 -1.525)
			(end 2.023 1.524)
			(stroke
				(width 0.05)
				(type solid)
			)
			(fill no)
			(layer "F.CrtYd")
		)
		(fp_line
			(start 1.3 -1)
			(end 1.5 -0.8)
			(stroke
				(width 0.15)
				(type solid)
			)
			(layer "F.Fab")
		)
		(fp_rect
			(start -1.526 -1.025)
			(end 1.523 1.024)
			(stroke
				(width 0.15)
				(type solid)
			)
			(fill no)
			(layer "F.Fab")
		)
		(pad "1" smd rect
			(at 0.498 -0.552 90)
			(size 1.6 0.35)
			(layers "F.Cu" "F.Mask" "F.Paste")
			(net 5 "GND")
			(pinfunction "PGND")
			(pintype "passive")
		)
		(pad "2" smd rect
			(at -0.5 -0.552 90)
			(size 1.6 0.35)
			(layers "F.Cu" "F.Mask" "F.Paste")
			(net 463 "VCC5V0_INT")
			(pinfunction "VIN")
			(pintype "power_in")
		)
		(pad "3" smd rect
			(at -1.45 -0.75 90)
			(size 0.35 0.8)
			(layers "F.Cu" "F.Mask" "F.Paste")
			(net 590 "/Supply/1V1_EN")
			(pinfunction "EN")
			(pintype "input")
		)
		(pad "4" smd rect
			(at -1.45 -0.25 90)
			(size 0.35 0.8)
			(layers "F.Cu" "F.Mask" "F.Paste")
			(net 621 "/Supply/1V1_MODE")
			(pinfunction "MODE")
			(pintype "input")
		)
		(pad "5" smd rect
			(at -1.45 0.248 90)
			(size 0.35 0.8)
			(layers "F.Cu" "F.Mask" "F.Paste")
			(net 615 "/Supply/1V1_FSEL")
			(pinfunction "FSEL")
			(pintype "input")
		)
		(pad "6" smd rect
			(at -1.45 0.748 90)
			(size 0.35 0.8)
			(layers "F.Cu" "F.Mask" "F.Paste")
			(net 654 "unconnected-(U10-PG-Pad6)")
			(pinfunction "PG")
			(pintype "open_collector+no_connect")
		)
		(pad "7" smd rect
			(at -0.5 0.949 180)
			(size 0.35 0.8)
			(layers "F.Cu" "F.Mask" "F.Paste")
			(net 580 "/Supply/1V1_BST")
			(pinfunction "BST")
			(pintype "input")
		)
		(pad "8" smd rect
			(at 0 0.55 90)
			(size 1.6 0.35)
			(layers "F.Cu" "F.Mask" "F.Paste")
			(net 579 "/Supply/1V1_SW")
			(pinfunction "SW")
			(pintype "output")
		)
		(pad "9" smd rect
			(at 1.449 0.748 270)
			(size 0.35 0.8)
			(layers "F.Cu" "F.Mask" "F.Paste")
			(net 591 "/Supply/1V1_VCC_INT")
			(pinfunction "VCC")
			(pintype "input")
		)
		(pad "10" smd rect
			(at 1.449 0.248 270)
			(size 0.35 0.8)
			(layers "F.Cu" "F.Mask" "F.Paste")
			(net 622 "/Supply/1V1_SS{slash}TR")
			(pinfunction "SS/TR")
			(pintype "input")
		)
		(pad "11" smd rect
			(at 1.449 -0.25 270)
			(size 0.35 0.8)
			(layers "F.Cu" "F.Mask" "F.Paste")
			(net 5 "GND")
			(pinfunction "GND")
			(pintype "passive")
		)
		(pad "12" smd rect
			(at 1.449 -0.75 270)
			(size 0.35 0.8)
			(layers "F.Cu" "F.Mask" "F.Paste")
			(net 598 "/Supply/1V1_FB")
			(pinfunction "FB")
			(pintype "input")
		)
	)
	(footprint "antmicro-footprints:R_0402_1005Metric"
		(layer "F.Cu")
		(at 129.95 88.074 180)
		(descr "Resistor SMD 0402")
		(tags "resistor SMD 0402")
		(property "Reference" "R121"
			(at 1.285328 2.474 180)
			(layer "F.SilkS")
			(effects
				(font
					(size 0.7 0.7)
					(thickness 0.15)
				)
				(justify left bottom)
			)
		)
		(property "Value" "R_0R_0402"
			(at 0 1.4 180)
			(layer "F.Fab")
			(effects
				(font
					(size 0.7 0.7)
					(thickness 0.15)
				)
				(justify left bottom)
			)
		)
		(property "Description" "0R resistor in 0402 package with unspecified tolerance"
			(at 0 0 180)
			(layer "F.Fab")
			(hide yes)
			(effects
				(font
					(size 1.27 1.27)
					(thickness 0.15)
				)
			)
		)
		(property "Author" "Antmicro"
			(at 259.9 176.148 0)
			(layer "F.Fab")
			(hide yes)
			(effects
				(font
					(size 1 1)
					(thickness 0.15)
				)
			)
		)
		(property "Current" "1A"
			(at 259.9 176.148 0)
			(layer "F.Fab")
			(hide yes)
			(effects
				(font
					(size 1 1)
					(thickness 0.15)
				)
			)
		)
		(property "License" "Apache-2.0"
			(at 259.9 176.148 0)
			(layer "F.Fab")
			(hide yes)
			(effects
				(font
					(size 1 1)
					(thickness 0.15)
				)
			)
		)
		(property "MPN" "ERJ2GE0R00X"
			(at 259.9 176.148 0)
			(layer "F.Fab")
			(hide yes)
			(effects
				(font
					(size 1 1)
					(thickness 0.15)
				)
			)
		)
		(property "Manufacturer" "Panasonic"
			(at 259.9 176.148 0)
			(layer "F.Fab")
			(hide yes)
			(effects
				(font
					(size 1 1)
					(thickness 0.15)
				)
			)
		)
		(property "Tolerance" ""
			(at 259.9 176.148 0)
			(layer "F.Fab")
			(hide yes)
			(effects
				(font
					(size 1 1)
					(thickness 0.15)
				)
			)
		)
		(property "Val" "0R"
			(at 259.9 176.148 0)
			(layer "F.Fab")
			(hide yes)
			(effects
				(font
					(size 1 1)
					(thickness 0.15)
				)
			)
		)
		(sheetname "Supply")
		(sheetfile "supply.kicad_sch")
		(attr smd)
		(fp_rect
			(start -0.93 -0.47)
			(end 0.93 0.47)
			(stroke
				(width 0.05)
				(type solid)
			)
			(fill no)
			(layer "F.CrtYd")
		)
		(fp_rect
			(start -0.5 -0.25)
			(end 0.5 0.25)
			(stroke
				(width 0.15)
				(type solid)
			)
			(fill no)
			(layer "F.Fab")
		)
		(pad "1" smd roundrect
			(at -0.485 0 180)
			(size 0.59 0.64)
			(layers "F.Cu" "F.Mask" "F.Paste")
			(roundrect_rratio 0.25)
			(net 591 "/Supply/1V1_VCC_INT")
			(pintype "passive")
		)
		(pad "2" smd roundrect
			(at 0.485 0 180)
			(size 0.59 0.64)
			(layers "F.Cu" "F.Mask" "F.Paste")
			(roundrect_rratio 0.25)
			(net 615 "/Supply/1V1_FSEL")
			(pintype "passive")
		)
	)
	(footprint "antmicro-footprints:C_0402_1005Metric"
		(layer "F.Cu")
		(at 111.725 97.249 180)
		(descr "Capacitor SMD 0402")
		(tags "capacitor SMD 0402")
		(property "Reference" "C172"
			(at 3.625 -0.351 180)
			(layer "F.SilkS")
			(effects
				(font
					(size 0.7 0.7)
					(thickness 0.15)
				)
				(justify left bottom)
			)
		)
		(property "Value" "C_22u_0402"
			(at 0 1.4 180)
			(layer "F.Fab")
			(effects
				(font
					(size 0.7 0.7)
					(thickness 0.15)
				)
				(justify left bottom)
			)
		)
		(property "Description" " "
			(at 0 0 180)
			(layer "F.Fab")
			(hide yes)
			(effects
				(font
					(size 1.27 1.27)
					(thickness 0.15)
				)
			)
		)
		(property "Author" "Antmicro"
			(at 223.45 194.498 0)
			(layer "F.Fab")
			(hide yes)
			(effects
				(font
					(size 1 1)
					(thickness 0.15)
				)
			)
		)
		(property "Dielectric" ""
			(at 223.45 194.498 0)
			(layer "F.Fab")
			(hide yes)
			(effects
				(font
					(size 1 1)
					(thickness 0.15)
				)
			)
		)
		(property "License" "Apache-2.0"
			(at 223.45 194.498 0)
			(layer "F.Fab")
			(hide yes)
			(effects
				(font
					(size 1 1)
					(thickness 0.15)
				)
			)
		)
		(property "MPN" "04024W226MAT2A"
			(at 223.45 194.498 0)
			(layer "F.Fab")
			(hide yes)
			(effects
				(font
					(size 1 1)
					(thickness 0.15)
				)
			)
		)
		(property "Manufacturer" "AVX"
			(at 223.45 194.498 0)
			(layer "F.Fab")
			(hide yes)
			(effects
				(font
					(size 1 1)
					(thickness 0.15)
				)
			)
		)
		(property "Val" "22u"
			(at 223.45 194.498 0)
			(layer "F.Fab")
			(hide yes)
			(effects
				(font
					(size 1 1)
					(thickness 0.15)
				)
			)
		)
		(property "Voltage" ""
			(at 223.45 194.498 0)
			(layer "F.Fab")
			(hide yes)
			(effects
				(font
					(size 1 1)
					(thickness 0.15)
				)
			)
		)
		(sheetname "Supply")
		(sheetfile "supply.kicad_sch")
		(attr smd)
		(fp_rect
			(start -0.94 -0.47)
			(end 0.94 0.47)
			(stroke
				(width 0.05)
				(type solid)
			)
			(fill no)
			(layer "F.CrtYd")
		)
		(fp_rect
			(start -0.499 -0.249)
			(end 0.499 0.249)
			(stroke
				(width 0.15)
				(type solid)
			)
			(fill no)
			(layer "F.Fab")
		)
		(pad "1" smd roundrect
			(at -0.484 0 180)
			(size 0.59 0.64)
			(layers "F.Cu" "F.Mask" "F.Paste")
			(roundrect_rratio 0.25)
			(net 576 "/Supply/3V3_REG")
			(pintype "passive")
		)
		(pad "2" smd roundrect
			(at 0.484 0 180)
			(size 0.59 0.64)
			(layers "F.Cu" "F.Mask" "F.Paste")
			(roundrect_rratio 0.25)
			(net 5 "GND")
			(pintype "passive")
		)
	)
	(footprint "antmicro-footprints:Vishay_PowerPAK_1212-8_Single"
		(layer "F.Cu")
		(at 110.9992 122.4 180)
		(descr "PowerPAK 1212-8 Single (https://www.vishay.com/docs/71656/ppak12128.pdf, https://www.vishay.com/docs/72597/72597.pdf)")
		(tags "Vishay PowerPAK 1212-8 Single")
		(property "Reference" "Q12"
			(at 0.0992 1.9 0)
			(layer "F.SilkS")
			(effects
				(font
					(size 0.7 0.7)
					(thickness 0.15)
				)
				(justify left bottom)
			)
		)
		(property "Value" "SQS401EN-T1_BE3"
			(at -8 2.7 180)
			(layer "F.Fab")
			(effects
				(font
					(size 0.7 0.7)
					(thickness 0.15)
				)
				(justify left bottom)
			)
		)
		(property "Description" "MOSFET P-CHANNEL 40V (D-S), 16 A, PowerPAK 1212-8 Single"
			(at 0 0 180)
			(layer "F.Fab")
			(hide yes)
			(effects
				(font
					(size 1.27 1.27)
					(thickness 0.15)
				)
			)
		)
		(property "Author" "Antmicro"
			(at 221.9984 244.8 0)
			(layer "F.Fab")
			(hide yes)
			(effects
				(font
					(size 1 1)
					(thickness 0.15)
				)
			)
		)
		(property "License" "Apache-2.0"
			(at 221.9984 244.8 0)
			(layer "F.Fab")
			(hide yes)
			(effects
				(font
					(size 1 1)
					(thickness 0.15)
				)
			)
		)
		(property "MPN" "SQS401EN-T1_BE3"
			(at 221.9984 244.8 0)
			(layer "F.Fab")
			(hide yes)
			(effects
				(font
					(size 1 1)
					(thickness 0.15)
				)
			)
		)
		(property "Manufacturer" "Vishay"
			(at 221.9984 244.8 0)
			(layer "F.Fab")
			(hide yes)
			(effects
				(font
					(size 1 1)
					(thickness 0.15)
				)
			)
		)
		(sheetname "Supply")
		(sheetfile "supply.kicad_sch")
		(attr smd)
		(fp_line
			(start 1.634 1.3)
			(end 1.634 1.634)
			(stroke
				(width 0.15)
				(type solid)
			)
			(layer "F.SilkS")
		)
		(fp_line
			(start 1.634 -1.635)
			(end 1.634 -1.301)
			(stroke
				(width 0.15)
				(type solid)
			)
			(layer "F.SilkS")
		)
		(fp_line
			(start -1.635 1.634)
			(end 1.634 1.634)
			(stroke
				(width 0.15)
				(type solid)
			)
			(layer "F.SilkS")
		)
		(fp_line
			(start -1.635 1.3)
			(end -1.635 1.634)
			(stroke
				(width 0.15)
				(type solid)
			)
			(layer "F.SilkS")
		)
		(fp_line
			(start -1.871 -1.635)
			(end 1.634 -1.635)
			(stroke
				(width 0.15)
				(type solid)
			)
			(layer "F.SilkS")
		)
		(fp_circle
			(center -2.451 -0.99)
			(end -2.401 -0.99)
			(stroke
				(width 0.15)
				(type solid)
			)
			(fill yes)
			(layer "F.SilkS")
		)
		(fp_rect
			(start -2.151 -2.151)
			(end 2.148 2.148)
			(stroke
				(width 0.05)
				(type solid)
			)
			(fill no)
			(layer "F.CrtYd")
		)
		(fp_line
			(start -1.6425 -1.4175)
			(end -1.4175 -1.6425)
			(stroke
				(width 0.15)
				(type solid)
			)
			(layer "F.Fab")
		)
		(fp_rect
			(start -1.651 -1.651)
			(end 1.648 1.648)
			(stroke
				(width 0.15)
				(type solid)
			)
			(fill no)
			(layer "F.Fab")
		)
		(pad "1" smd rect
			(at -1.436 -0.99 180)
			(size 0.99 0.405)
			(layers "F.Cu" "F.Mask" "F.Paste")
			(net 76 "Net-(J6-Pad1)")
			(pinfunction "S")
			(pintype "bidirectional")
		)
		(pad "2" smd rect
			(at -1.436 -0.332 180)
			(size 0.99 0.405)
			(layers "F.Cu" "F.Mask" "F.Paste")
			(net 76 "Net-(J6-Pad1)")
			(pinfunction "S")
			(pintype "bidirectional")
		)
		(pad "3" smd rect
			(at -1.436 0.33 180)
			(size 0.99 0.405)
			(layers "F.Cu" "F.Mask" "F.Paste")
			(net 76 "Net-(J6-Pad1)")
			(pinfunction "S")
			(pintype "bidirectional")
		)
		(pad "4" smd rect
			(at -1.436 0.988 180)
			(size 0.99 0.405)
			(layers "F.Cu" "F.Mask" "F.Paste")
			(net 5 "GND")
			(pinfunction "G")
			(pintype "bidirectional")
		)
		(pad "5" smd custom
			(at 0.557 0 180)
			(size 1.725 2.235)
			(layers "F.Cu" "F.Mask" "F.Paste")
			(net 224 "VIN")
			(pinfunction "D")
			(pintype "bidirectional")
			(zone_connect 2)
			(options
				(clearance outline)
				(anchor rect)
			)
			(primitives
				(gr_poly
					(pts
						(xy 0.8625 0.1275) (xy 0.8625 -0.1275) (xy 1.3725 -0.1275) (xy 1.3725 -0.5325) (xy 0.8625 -0.5325)
						(xy 0.8625 -0.7875) (xy 1.3725 -0.7875) (xy 1.3725 -1.195) (xy 0.6125 -1.195) (xy 0.6125 1.195)
						(xy 1.3725 1.195) (xy 1.3725 0.7875) (xy 0.8625 0.7875) (xy 0.8625 0.5325) (xy 1.3725 0.5325)
						(xy 1.3725 0.1275)
					)
					(width 0)
					(fill yes)
				)
			)
		)
	)
	(footprint "antmicro-footprints:C_0402_1005Metric"
		(layer "F.Cu")
		(at 125.675 52.1 180)
		(descr "Capacitor SMD 0402")
		(tags "capacitor SMD 0402")
		(property "Reference" "C194"
			(at 1.175 1.5 180)
			(layer "F.SilkS")
			(effects
				(font
					(size 0.7 0.7)
					(thickness 0.15)
				)
				(justify left bottom)
			)
		)
		(property "Value" "C_10u_0402"
			(at 0 1.4 180)
			(layer "F.Fab")
			(effects
				(font
					(size 0.7 0.7)
					(thickness 0.15)
				)
				(justify left bottom)
			)
		)
		(property "Description" " "
			(at 0 0 180)
			(layer "F.Fab")
			(hide yes)
			(effects
				(font
					(size 1.27 1.27)
					(thickness 0.15)
				)
			)
		)
		(property "Author" "Antmicro"
			(at 251.35 104.2 0)
			(layer "F.Fab")
			(hide yes)
			(effects
				(font
					(size 1 1)
					(thickness 0.15)
				)
			)
		)
		(property "Dielectric" ""
			(at 251.35 104.2 0)
			(layer "F.Fab")
			(hide yes)
			(effects
				(font
					(size 1 1)
					(thickness 0.15)
				)
			)
		)
		(property "License" "Apache-2.0"
			(at 251.35 104.2 0)
			(layer "F.Fab")
			(hide yes)
			(effects
				(font
					(size 1 1)
					(thickness 0.15)
				)
			)
		)
		(property "MPN" "CC0402MRX5R5BB106"
			(at 251.35 104.2 0)
			(layer "F.Fab")
			(hide yes)
			(effects
				(font
					(size 1 1)
					(thickness 0.15)
				)
			)
		)
		(property "Manufacturer" "Yaego"
			(at 251.35 104.2 0)
			(layer "F.Fab")
			(hide yes)
			(effects
				(font
					(size 1 1)
					(thickness 0.15)
				)
			)
		)
		(property "Val" "10u"
			(at 251.35 104.2 0)
			(layer "F.Fab")
			(hide yes)
			(effects
				(font
					(size 1 1)
					(thickness 0.15)
				)
			)
		)
		(property "Voltage" ""
			(at 251.35 104.2 0)
			(layer "F.Fab")
			(hide yes)
			(effects
				(font
					(size 1 1)
					(thickness 0.15)
				)
			)
		)
		(sheetname "Supply")
		(sheetfile "supply.kicad_sch")
		(attr exclude_from_pos_files exclude_from_bom dnp)
		(fp_rect
			(start -0.94 -0.47)
			(end 0.94 0.47)
			(stroke
				(width 0.05)
				(type solid)
			)
			(fill no)
			(layer "F.CrtYd")
		)
		(fp_rect
			(start -0.499 -0.249)
			(end 0.499 0.249)
			(stroke
				(width 0.15)
				(type solid)
			)
			(fill no)
			(layer "F.Fab")
		)
		(pad "1" smd roundrect
			(at -0.484 0 180)
			(size 0.59 0.64)
			(layers "F.Cu" "F.Mask" "F.Paste")
			(roundrect_rratio 0.25)
			(net 627 "/Supply/VDDQ_0V6")
			(pintype "passive")
		)
		(pad "2" smd roundrect
			(at 0.484 0 180)
			(size 0.59 0.64)
			(layers "F.Cu" "F.Mask" "F.Paste")
			(roundrect_rratio 0.25)
			(net 5 "GND")
			(pintype "passive")
		)
	)
	(footprint "antmicro-footprints:C_0805_2012Metric"
		(layer "F.Cu")
		(at 111.2992 128.9)
		(descr "Capacitor SMD 0805")
		(tags "capacitor SMD 0805")
		(property "Reference" "C125"
			(at -1.5992 0.1 135)
			(layer "F.SilkS")
			(effects
				(font
					(size 0.7 0.7)
					(thickness 0.15)
				)
				(justify left bottom)
			)
		)
		(property "Value" "C_22u_0805_16V"
			(at 0 1.947 0)
			(layer "F.Fab")
			(effects
				(font
					(size 0.7 0.7)
					(thickness 0.15)
				)
				(justify left bottom)
			)
		)
		(property "Description" " "
			(at 0 0 0)
			(layer "F.Fab")
			(hide yes)
			(effects
				(font
					(size 1.27 1.27)
					(thickness 0.15)
				)
			)
		)
		(property "Author" "Antmicro"
			(at 0 0 0)
			(layer "F.Fab")
			(hide yes)
			(effects
				(font
					(size 1 1)
					(thickness 0.15)
				)
			)
		)
		(property "Dielectric" ""
			(at 0 0 0)
			(layer "F.Fab")
			(hide yes)
			(effects
				(font
					(size 1 1)
					(thickness 0.15)
				)
			)
		)
		(property "License" "Apache-2.0"
			(at 0 0 0)
			(layer "F.Fab")
			(hide yes)
			(effects
				(font
					(size 1 1)
					(thickness 0.15)
				)
			)
		)
		(property "MPN" "GRT21BR61C226ME13L"
			(at 0 0 0)
			(layer "F.Fab")
			(hide yes)
			(effects
				(font
					(size 1 1)
					(thickness 0.15)
				)
			)
		)
		(property "Manufacturer" "Murata"
			(at 0 0 0)
			(layer "F.Fab")
			(hide yes)
			(effects
				(font
					(size 1 1)
					(thickness 0.15)
				)
			)
		)
		(property "Val" "22u/16V"
			(at 0 0 0)
			(layer "F.Fab")
			(hide yes)
			(effects
				(font
					(size 1 1)
					(thickness 0.15)
				)
			)
		)
		(property "Voltage" ""
			(at 0 0 0)
			(layer "F.Fab")
			(hide yes)
			(effects
				(font
					(size 1 1)
					(thickness 0.15)
				)
			)
		)
		(sheetname "Supply")
		(sheetfile "supply.kicad_sch")
		(attr smd)
		(fp_line
			(start -0.3 -0.8)
			(end 0.3 -0.8)
			(stroke
				(width 0.15)
				(type solid)
			)
			(layer "F.SilkS")
		)
		(fp_line
			(start -0.3 0.8)
			(end 0.3 0.8)
			(stroke
				(width 0.15)
				(type solid)
			)
			(layer "F.SilkS")
		)
		(fp_rect
			(start -1.9 -0.93)
			(end 1.9 0.93)
			(stroke
				(width 0.05)
				(type solid)
			)
			(fill no)
			(layer "F.CrtYd")
		)
		(fp_rect
			(start -0.95 -0.675)
			(end 0.95 0.675)
			(stroke
				(width 0.15)
				(type solid)
			)
			(fill no)
			(layer "F.Fab")
		)
		(pad "1" smd rect
			(at -1.05 0)
			(size 1.2 1.2)
			(layers "F.Cu" "F.Mask" "F.Paste")
			(net 224 "VIN")
			(pintype "passive")
		)
		(pad "2" smd rect
			(at 1.05 0)
			(size 1.2 1.2)
			(layers "F.Cu" "F.Mask" "F.Paste")
			(net 5 "GND")
			(pintype "passive")
		)
	)
	(footprint "antmicro-footprints:R_0402_1005Metric"
		(layer "F.Cu")
		(at 111.94 101.449 180)
		(descr "Resistor SMD 0402")
		(tags "resistor SMD 0402")
		(property "Reference" "R135"
			(at 3.64 -0.351 180)
			(layer "F.SilkS")
			(effects
				(font
					(size 0.7 0.7)
					(thickness 0.15)
				)
				(justify left bottom)
			)
		)
		(property "Value" "R_10k_0402"
			(at 0 1.4 180)
			(layer "F.Fab")
			(effects
				(font
					(size 0.7 0.7)
					(thickness 0.15)
				)
				(justify left bottom)
			)
		)
		(property "Description" "10k resistor in 0402 package with 1% tolerance"
			(at 0 0 180)
			(layer "F.Fab")
			(hide yes)
			(effects
				(font
					(size 1.27 1.27)
					(thickness 0.15)
				)
			)
		)
		(property "Author" "Antmicro"
			(at 223.88 202.898 0)
			(layer "F.Fab")
			(hide yes)
			(effects
				(font
					(size 1 1)
					(thickness 0.15)
				)
			)
		)
		(property "License" "Apache-2.0"
			(at 223.88 202.898 0)
			(layer "F.Fab")
			(hide yes)
			(effects
				(font
					(size 1 1)
					(thickness 0.15)
				)
			)
		)
		(property "MPN" "CR0402-FX-1002GLF"
			(at 223.88 202.898 0)
			(layer "F.Fab")
			(hide yes)
			(effects
				(font
					(size 1 1)
					(thickness 0.15)
				)
			)
		)
		(property "Manufacturer" "Bourns"
			(at 223.88 202.898 0)
			(layer "F.Fab")
			(hide yes)
			(effects
				(font
					(size 1 1)
					(thickness 0.15)
				)
			)
		)
		(property "Tolerance" "1%"
			(at 223.88 202.898 0)
			(layer "F.Fab")
			(hide yes)
			(effects
				(font
					(size 1 1)
					(thickness 0.15)
				)
			)
		)
		(property "Val" "10k"
			(at 223.88 202.898 0)
			(layer "F.Fab")
			(hide yes)
			(effects
				(font
					(size 1 1)
					(thickness 0.15)
				)
			)
		)
		(sheetname "Supply")
		(sheetfile "supply.kicad_sch")
		(attr smd)
		(fp_rect
			(start -0.93 -0.47)
			(end 0.93 0.47)
			(stroke
				(width 0.05)
				(type solid)
			)
			(fill no)
			(layer "F.CrtYd")
		)
		(fp_rect
			(start -0.5 -0.25)
			(end 0.5 0.25)
			(stroke
				(width 0.15)
				(type solid)
			)
			(fill no)
			(layer "F.Fab")
		)
		(pad "1" smd roundrect
			(at -0.485 0 180)
			(size 0.59 0.64)
			(layers "F.Cu" "F.Mask" "F.Paste")
			(roundrect_rratio 0.25)
			(net 578 "/Supply/3V3_FB")
			(pintype "passive")
		)
		(pad "2" smd roundrect
			(at 0.485 0 180)
			(size 0.59 0.64)
			(layers "F.Cu" "F.Mask" "F.Paste")
			(roundrect_rratio 0.25)
			(net 5 "GND")
			(pintype "passive")
		)
	)
	(footprint "antmicro-footprints:R_0402_1005Metric"
		(layer "F.Cu")
		(at 117.7 87.049 180)
		(descr "Resistor SMD 0402")
		(tags "resistor SMD 0402")
		(property "Reference" "R157"
			(at 0.897806 3.574 180)
			(layer "F.SilkS")
			(effects
				(font
					(size 0.7 0.7)
					(thickness 0.15)
				)
				(justify left bottom)
			)
		)
		(property "Value" "R_100k_0402"
			(at 0 1.4 180)
			(layer "F.Fab")
			(effects
				(font
					(size 0.7 0.7)
					(thickness 0.15)
				)
				(justify left bottom)
			)
		)
		(property "Description" "100k resistor in 0402 package with 1% tolerance"
			(at 0 0 180)
			(layer "F.Fab")
			(hide yes)
			(effects
				(font
					(size 1.27 1.27)
					(thickness 0.15)
				)
			)
		)
		(property "Author" "Antmicro"
			(at 235.4 174.098 0)
			(layer "F.Fab")
			(hide yes)
			(effects
				(font
					(size 1 1)
					(thickness 0.15)
				)
			)
		)
		(property "License" "Apache-2.0"
			(at 235.4 174.098 0)
			(layer "F.Fab")
			(hide yes)
			(effects
				(font
					(size 1 1)
					(thickness 0.15)
				)
			)
		)
		(property "MPN" "CR0402-FX-1003GLF"
			(at 235.4 174.098 0)
			(layer "F.Fab")
			(hide yes)
			(effects
				(font
					(size 1 1)
					(thickness 0.15)
				)
			)
		)
		(property "Manufacturer" "Bourns"
			(at 235.4 174.098 0)
			(layer "F.Fab")
			(hide yes)
			(effects
				(font
					(size 1 1)
					(thickness 0.15)
				)
			)
		)
		(property "Tolerance" "1%"
			(at 235.4 174.098 0)
			(layer "F.Fab")
			(hide yes)
			(effects
				(font
					(size 1 1)
					(thickness 0.15)
				)
			)
		)
		(property "Val" "100k"
			(at 235.4 174.098 0)
			(layer "F.Fab")
			(hide yes)
			(effects
				(font
					(size 1 1)
					(thickness 0.15)
				)
			)
		)
		(sheetname "Supply")
		(sheetfile "supply.kicad_sch")
		(attr smd)
		(fp_rect
			(start -0.93 -0.47)
			(end 0.93 0.47)
			(stroke
				(width 0.05)
				(type solid)
			)
			(fill no)
			(layer "F.CrtYd")
		)
		(fp_rect
			(start -0.5 -0.25)
			(end 0.5 0.25)
			(stroke
				(width 0.15)
				(type solid)
			)
			(fill no)
			(layer "F.Fab")
		)
		(pad "1" smd roundrect
			(at -0.485 0 180)
			(size 0.59 0.64)
			(layers "F.Cu" "F.Mask" "F.Paste")
			(roundrect_rratio 0.25)
			(net 595 "/Supply/1V8_VCC_INT")
			(pintype "passive")
		)
		(pad "2" smd roundrect
			(at 0.485 0 180)
			(size 0.59 0.64)
			(layers "F.Cu" "F.Mask" "F.Paste")
			(roundrect_rratio 0.25)
			(net 605 "/Supply/1V8_PG")
			(pintype "passive")
		)
	)
	(footprint "antmicro-footprints:PinHeader_1x3_P2.54mm_Horizontal"
		(layer "F.Cu")
		(at 142.97 56.38 90)
		(descr "Through hole angled pin header, 1x03, 2.54mm pitch, 6mm pin length, single row")
		(tags "Through hole angled pin header THT 1x03 2.54mm single row")
		(property "Reference" "J7"
			(at 2.38 6.83 180)
			(layer "F.SilkS")
			(effects
				(font
					(size 0.7 0.7)
					(thickness 0.15)
				)
				(justify left bottom)
			)
		)
		(property "Value" "PinHeader_1x3_P2.54mm_Drill1.1mm_Horizontal"
			(at -5.5 7.6 90)
			(layer "F.Fab")
			(effects
				(font
					(size 0.7 0.7)
					(thickness 0.15)
				)
				(justify left bottom)
			)
		)
		(property "Description" "Connector Header Through Hole, Right Angle 3 position 0.100\" (2.54mm)"
			(at 0 0 90)
			(layer "F.Fab")
			(hide yes)
			(effects
				(font
					(size 1.27 1.27)
					(thickness 0.15)
				)
			)
		)
		(property "Author" "Antmicro"
			(at 199.35 -86.59 0)
			(layer "F.Fab")
			(hide yes)
			(effects
				(font
					(size 1 1)
					(thickness 0.15)
				)
			)
		)
		(property "License" "Apache-2.0"
			(at 199.35 -86.59 0)
			(layer "F.Fab")
			(hide yes)
			(effects
				(font
					(size 1 1)
					(thickness 0.15)
				)
			)
		)
		(property "MPN" "61300311021"
			(at 199.35 -86.59 0)
			(layer "F.Fab")
			(hide yes)
			(effects
				(font
					(size 1 1)
					(thickness 0.15)
				)
			)
		)
		(property "Manufacturer" "Würth Elektronik"
			(at 199.35 -86.59 0)
			(layer "F.Fab")
			(hide yes)
			(effects
				(font
					(size 1 1)
					(thickness 0.15)
				)
			)
		)
		(sheetname "Supply")
		(sheetfile "supply.kicad_sch")
		(attr through_hole)
		(fp_line
			(start 4.099 -1.331)
			(end 1.439 -1.331)
			(stroke
				(width 0.15)
				(type solid)
			)
			(layer "F.SilkS")
		)
		(fp_line
			(start 1.439 -1.331)
			(end 1.439 6.41)
			(stroke
				(width 0.15)
				(type solid)
			)
			(layer "F.SilkS")
		)
		(fp_line
			(start 10.098 -0.38)
			(end 10.098 0.378)
			(stroke
				(width 0.15)
				(type solid)
			)
			(layer "F.SilkS")
		)
		(fp_line
			(start 4.099 -0.38)
			(end 10.098 -0.38)
			(stroke
				(width 0.15)
				(type solid)
			)
			(layer "F.SilkS")
		)
		(fp_line
			(start 1.11 -0.38)
			(end 1.439 -0.38)
			(stroke
				(width 0.15)
				(type solid)
			)
			(layer "F.SilkS")
		)
		(fp_line
			(start 4.099 -0.32)
			(end 10.098 -0.32)
			(stroke
				(width 0.15)
				(type solid)
			)
			(layer "F.SilkS")
		)
		(fp_line
			(start 4.099 -0.202)
			(end 10.098 -0.202)
			(stroke
				(width 0.15)
				(type solid)
			)
			(layer "F.SilkS")
		)
		(fp_line
			(start 4.099 -0.08)
			(end 10.098 -0.08)
			(stroke
				(width 0.15)
				(type solid)
			)
			(layer "F.SilkS")
		)
		(fp_line
			(start 4.099 0.04)
			(end 10.098 0.04)
			(stroke
				(width 0.15)
				(type solid)
			)
			(layer "F.SilkS")
		)
		(fp_line
			(start 4.099 0.16)
			(end 10.098 0.16)
			(stroke
				(width 0.15)
				(type solid)
			)
			(layer "F.SilkS")
		)
		(fp_line
			(start 4.099 0.28)
			(end 10.098 0.28)
			(stroke
				(width 0.15)
				(type solid)
			)
			(layer "F.SilkS")
		)
		(fp_line
			(start 10.098 0.378)
			(end 4.099 0.378)
			(stroke
				(width 0.15)
				(type solid)
			)
			(layer "F.SilkS")
		)
		(fp_line
			(start 1.11 0.378)
			(end 1.439 0.378)
			(stroke
				(width 0.15)
				(type solid)
			)
			(layer "F.SilkS")
		)
		(fp_line
			(start 1.439 1.269)
			(end 4.099 1.269)
			(stroke
				(width 0.15)
				(type solid)
			)
			(layer "F.SilkS")
		)
		(fp_line
			(start 10.098 2.16)
			(end 10.098 2.918)
			(stroke
				(width 0.15)
				(type solid)
			)
			(layer "F.SilkS")
		)
		(fp_line
			(start 4.099 2.16)
			(end 10.098 2.16)
			(stroke
				(width 0.15)
				(type solid)
			)
			(layer "F.SilkS")
		)
		(fp_line
			(start 1.042 2.16)
			(end 1.439 2.16)
			(stroke
				(width 0.15)
				(type solid)
			)
			(layer "F.SilkS")
		)
		(fp_line
			(start 10.098 2.918)
			(end 4.099 2.918)
			(stroke
				(width 0.15)
				(type solid)
			)
			(layer "F.SilkS")
		)
		(fp_line
			(start 1.042 2.918)
			(end 1.439 2.918)
			(stroke
				(width 0.15)
				(type solid)
			)
			(layer "F.SilkS")
		)
		(fp_line
			(start 1.439 3.809)
			(end 4.099 3.809)
			(stroke
				(width 0.15)
				(type solid)
			)
			(layer "F.SilkS")
		)
		(fp_line
			(start 10.098 4.7)
			(end 10.098 5.459)
			(stroke
				(width 0.15)
				(type solid)
			)
			(layer "F.SilkS")
		)
		(fp_line
			(start 4.099 4.7)
			(end 10.098 4.7)
			(stroke
				(width 0.15)
				(type solid)
			)
			(layer "F.SilkS")
		)
		(fp_line
			(start 1.042 4.7)
			(end 1.439 4.7)
			(stroke
				(width 0.15)
				(type solid)
			)
			(layer "F.SilkS")
		)
		(fp_line
			(start 10.098 5.459)
			(end 4.099 5.459)
			(stroke
				(width 0.15)
				(type solid)
			)
			(layer "F.SilkS")
		)
		(fp_line
			(start 1.042 5.459)
			(end 1.439 5.459)
			(stroke
				(width 0.15)
				(type solid)
			)
			(layer "F.SilkS")
		)
		(fp_line
			(start 4.099 6.41)
			(end 4.099 -1.331)
			(stroke
				(width 0.15)
				(type solid)
			)
			(layer "F.SilkS")
		)
		(fp_line
			(start 1.439 6.41)
			(end 4.099 6.41)
			(stroke
				(width 0.15)
				(type solid)
			)
			(layer "F.SilkS")
		)
		(fp_circle
			(center -1.3 0)
			(end -1.25 0)
			(stroke
				(width 0.15)
				(type solid)
			)
			(fill yes)
			(layer "F.SilkS")
		)
		(fp_rect
			(start -0.82 -1.77)
			(end 10.538 6.849)
			(stroke
				(width 0.05)
				(type solid)
			)
			(fill no)
			(layer "F.CrtYd")
		)
		(fp_line
			(start 4.038 -1.27)
			(end 4.038 6.349)
			(stroke
				(width 0.15)
				(type solid)
			)
			(layer "F.Fab")
		)
		(fp_line
			(start 2.133 -1.27)
			(end 4.038 -1.27)
			(stroke
				(width 0.15)
				(type solid)
			)
			(layer "F.Fab")
		)
		(fp_line
			(start 1.499 -0.635)
			(end 2.133 -1.27)
			(stroke
				(width 0.15)
				(type solid)
			)
			(layer "F.Fab")
		)
		(fp_line
			(start 10.038 -0.32)
			(end 10.038 0.32)
			(stroke
				(width 0.15)
				(type solid)
			)
			(layer "F.Fab")
		)
		(fp_line
			(start 4.038 -0.32)
			(end 10.038 -0.32)
			(stroke
				(width 0.15)
				(type solid)
			)
			(layer "F.Fab")
		)
		(fp_line
			(start -0.32 -0.32)
			(end 1.499 -0.32)
			(stroke
				(width 0.15)
				(type solid)
			)
			(layer "F.Fab")
		)
		(fp_line
			(start -0.32 -0.32)
			(end -0.32 0.32)
			(stroke
				(width 0.15)
				(type solid)
			)
			(layer "F.Fab")
		)
		(fp_line
			(start 4.038 0.32)
			(end 10.038 0.32)
			(stroke
				(width 0.15)
				(type solid)
			)
			(layer "F.Fab")
		)
		(fp_line
			(start -0.32 0.32)
			(end 1.499 0.32)
			(stroke
				(width 0.15)
				(type solid)
			)
			(layer "F.Fab")
		)
		(fp_line
			(start 10.038 2.22)
			(end 10.038 2.858)
			(stroke
				(width 0.15)
				(type solid)
			)
			(layer "F.Fab")
		)
		(fp_line
			(start 4.038 2.22)
			(end 10.038 2.22)
			(stroke
				(width 0.15)
				(type solid)
			)
			(layer "F.Fab")
		)
		(fp_line
			(start -0.32 2.22)
			(end 1.499 2.22)
			(stroke
				(width 0.15)
				(type solid)
			)
			(layer "F.Fab")
		)
		(fp_line
			(start -0.32 2.22)
			(end -0.32 2.858)
			(stroke
				(width 0.15)
				(type solid)
			)
			(layer "F.Fab")
		)
		(fp_line
			(start 4.038 2.858)
			(end 10.038 2.858)
			(stroke
				(width 0.15)
				(type solid)
			)
			(layer "F.Fab")
		)
		(fp_line
			(start -0.32 2.858)
			(end 1.499 2.858)
			(stroke
				(width 0.15)
				(type solid)
			)
			(layer "F.Fab")
		)
		(fp_line
			(start 10.038 4.759)
			(end 10.038 5.4)
			(stroke
				(width 0.15)
				(type solid)
			)
			(layer "F.Fab")
		)
		(fp_line
			(start 4.038 4.759)
			(end 10.038 4.759)
			(stroke
				(width 0.15)
				(type solid)
			)
			(layer "F.Fab")
		)
		(fp_line
			(start -0.32 4.759)
			(end 1.499 4.759)
			(stroke
				(width 0.15)
				(type solid)
			)
			(layer "F.Fab")
		)
		(fp_line
			(start -0.32 4.759)
			(end -0.32 5.4)
			(stroke
				(width 0.15)
				(type solid)
			)
			(layer "F.Fab")
		)
		(fp_line
			(start 4.038 5.4)
			(end 10.038 5.4)
			(stroke
				(width 0.15)
				(type solid)
			)
			(layer "F.Fab")
		)
		(fp_line
			(start -0.32 5.4)
			(end 1.499 5.4)
			(stroke
				(width 0.15)
				(type solid)
			)
			(layer "F.Fab")
		)
		(fp_line
			(start 4.038 6.349)
			(end 1.499 6.349)
			(stroke
				(width 0.15)
				(type solid)
			)
			(layer "F.Fab")
		)
		(fp_line
			(start 1.499 6.349)
			(end 1.499 -0.635)
			(stroke
				(width 0.15)
				(type solid)
			)
			(layer "F.Fab")
		)
		(pad "1" thru_hole rect
			(at 0 0 90)
			(size 1.7 1.7)
			(drill 1)
			(layers "*.Cu" "*.Mask")
			(remove_unused_layers no)
			(net 273 "1V1_DDR")
			(pintype "passive")
		)
		(pad "2" thru_hole oval
			(at 0 2.539 90)
			(size 1.7 1.7)
			(drill 1)
			(layers "*.Cu" "*.Mask")
			(remove_unused_layers no)
			(net 66 "VDDQ")
			(pintype "passive")
		)
		(pad "3" thru_hole oval
			(at 0 5.078 90)
			(size 1.7 1.7)
			(drill 1)
			(layers "*.Cu" "*.Mask")
			(remove_unused_layers no)
			(net 640 "0V6_DDR")
			(pintype "passive")
		)
	)
	(footprint "lpddr4-test-board-footprints:mounting-hole-3.2mm"
		(layer "F.Cu")
		(at 213.9 132.9)
		(property "Reference" "MH3"
			(at -0.178 4.025 0)
			(layer "F.SilkS")
			(hide yes)
			(effects
				(font
					(size 0.7 0.7)
					(thickness 0.15)
				)
				(justify left bottom)
			)
		)
		(property "Value" "M3.2"
			(at -0.153 -4.153 0)
			(layer "F.Fab")
			(hide yes)
			(effects
				(font
					(size 0.7 0.7)
					(thickness 0.15)
				)
				(justify left bottom)
			)
		)
		(attr through_hole board_only exclude_from_bom)
		(pad "1" thru_hole circle
			(at 0 0)
			(size 6 6)
			(drill 3.2)
			(layers "*.Cu" "*.Mask")
			(remove_unused_layers no)
		)
	)
	(footprint "antmicro-footprints:C_0603_1608Metric"
		(layer "F.Cu")
		(at 120.8 53.475 90)
		(descr "Capacitor SMD 0603")
		(tags "capacitor 0603")
		(property "Reference" "C187"
			(at 1.075 0.3 90)
			(layer "F.SilkS")
			(effects
				(font
					(size 0.7 0.7)
					(thickness 0.15)
				)
				(justify left bottom)
			)
		)
		(property "Value" "C_10u_25V_0603"
			(at 0 1.6 90)
			(layer "F.Fab")
			(effects
				(font
					(size 0.7 0.7)
					(thickness 0.15)
				)
				(justify left bottom)
			)
		)
		(property "Description" " "
			(at 0 0 90)
			(layer "F.Fab")
			(hide yes)
			(effects
				(font
					(size 1.27 1.27)
					(thickness 0.15)
				)
			)
		)
		(property "Author" "Antmicro"
			(at 174.275 -67.325 0)
			(layer "F.Fab")
			(hide yes)
			(effects
				(font
					(size 1 1)
					(thickness 0.15)
				)
			)
		)
		(property "Dielectric" ""
			(at 174.275 -67.325 0)
			(layer "F.Fab")
			(hide yes)
			(effects
				(font
					(size 1 1)
					(thickness 0.15)
				)
			)
		)
		(property "License" "Apache-2.0"
			(at 174.275 -67.325 0)
			(layer "F.Fab")
			(hide yes)
			(effects
				(font
					(size 1 1)
					(thickness 0.15)
				)
			)
		)
		(property "MPN" "C1608X5R1E106M080AC"
			(at 174.275 -67.325 0)
			(layer "F.Fab")
			(hide yes)
			(effects
				(font
					(size 1 1)
					(thickness 0.15)
				)
			)
		)
		(property "Manufacturer" "TDK"
			(at 174.275 -67.325 0)
			(layer "F.Fab")
			(hide yes)
			(effects
				(font
					(size 1 1)
					(thickness 0.15)
				)
			)
		)
		(property "Val" "10u/25V"
			(at 174.275 -67.325 0)
			(layer "F.Fab")
			(hide yes)
			(effects
				(font
					(size 1 1)
					(thickness 0.15)
				)
			)
		)
		(property "Voltage" ""
			(at 174.275 -67.325 0)
			(layer "F.Fab")
			(hide yes)
			(effects
				(font
					(size 1 1)
					(thickness 0.15)
				)
			)
		)
		(sheetname "Supply")
		(sheetfile "supply.kicad_sch")
		(attr exclude_from_pos_files exclude_from_bom dnp)
		(fp_line
			(start -0.3 -0.3)
			(end 0.3 -0.3)
			(stroke
				(width 0.15)
				(type solid)
			)
			(layer "F.SilkS")
		)
		(fp_line
			(start -0.3 0.3)
			(end 0.3 0.3)
			(stroke
				(width 0.15)
				(type solid)
			)
			(layer "F.SilkS")
		)
		(fp_rect
			(start -1.24 -0.7)
			(end 1.24 0.7)
			(stroke
				(width 0.05)
				(type solid)
			)
			(fill no)
			(layer "F.CrtYd")
		)
		(fp_rect
			(start -0.8 -0.4)
			(end 0.8 0.4)
			(stroke
				(width 0.15)
				(type solid)
			)
			(fill no)
			(layer "F.Fab")
		)
		(pad "1" smd roundrect
			(at -0.7 0 90)
			(size 0.6 0.8)
			(layers "F.Cu" "F.Mask" "F.Paste")
			(roundrect_rratio 0.2)
			(net 224 "VIN")
			(pintype "passive")
		)
		(pad "2" smd roundrect
			(at 0.7 0 90)
			(size 0.6 0.8)
			(layers "F.Cu" "F.Mask" "F.Paste")
			(roundrect_rratio 0.2)
			(net 5 "GND")
			(pintype "passive")
		)
	)
	(footprint "antmicro-footprints:TP_SMD_1mm"
		(layer "F.Cu")
		(at 146.1 109.099 180)
		(property "Reference" "TP1"
			(at -0.4 0.499 90)
			(layer "F.SilkS")
			(effects
				(font
					(size 0.7 0.7)
					(thickness 0.15)
				)
				(justify left bottom)
			)
		)
		(property "Value" "TP_1mm_SMD"
			(at 0 1.4 180)
			(layer "F.Fab")
			(effects
				(font
					(size 0.7 0.7)
					(thickness 0.15)
				)
				(justify left bottom)
			)
		)
		(property "Description" "Test Point 1mm"
			(at 0 0 180)
			(layer "F.Fab")
			(hide yes)
			(effects
				(font
					(size 1.27 1.27)
					(thickness 0.15)
				)
			)
		)
		(property "Author" "Antmicro"
			(at 292.2 218.198 0)
			(layer "F.Fab")
			(hide yes)
			(effects
				(font
					(size 1 1)
					(thickness 0.15)
				)
			)
		)
		(property "License" "Apache-2.0"
			(at 292.2 218.198 0)
			(layer "F.Fab")
			(hide yes)
			(effects
				(font
					(size 1 1)
					(thickness 0.15)
				)
			)
		)
		(property "MPN" ""
			(at 292.2 218.198 0)
			(layer "F.Fab")
			(hide yes)
			(effects
				(font
					(size 1 1)
					(thickness 0.15)
				)
			)
		)
		(property "Manufacturer" ""
			(at 292.2 218.198 0)
			(layer "F.Fab")
			(hide yes)
			(effects
				(font
					(size 1 1)
					(thickness 0.15)
				)
			)
		)
		(sheetname "Interfaces")
		(sheetfile "interfaces.kicad_sch")
		(attr exclude_from_pos_files)
		(pad "1" smd circle
			(at 0 0 180)
			(size 1 1)
			(layers "F.Cu" "F.Mask")
			(net 265 "Net-(U4-ADBUS5)")
			(pinfunction "1")
			(pintype "passive")
		)
	)
	(footprint "antmicro-footprints:C_0402_1005Metric"
		(layer "F.Cu")
		(at 138.8 61.2 -90)
		(descr "Capacitor SMD 0402")
		(tags "capacitor SMD 0402")
		(property "Reference" "C135"
			(at 1.1 -1.3 270)
			(layer "F.SilkS")
			(effects
				(font
					(size 0.7 0.7)
					(thickness 0.15)
				)
				(justify left bottom)
			)
		)
		(property "Value" "C_10u_0402"
			(at 0 1.4 270)
			(layer "F.Fab")
			(effects
				(font
					(size 0.7 0.7)
					(thickness 0.15)
				)
				(justify left bottom)
			)
		)
		(property "Description" " "
			(at 0 0 270)
			(layer "F.Fab")
			(hide yes)
			(effects
				(font
					(size 1.27 1.27)
					(thickness 0.15)
				)
			)
		)
		(property "Author" "Antmicro"
			(at 77.6 200 0)
			(layer "F.Fab")
			(hide yes)
			(effects
				(font
					(size 1 1)
					(thickness 0.15)
				)
			)
		)
		(property "Dielectric" ""
			(at 77.6 200 0)
			(layer "F.Fab")
			(hide yes)
			(effects
				(font
					(size 1 1)
					(thickness 0.15)
				)
			)
		)
		(property "License" "Apache-2.0"
			(at 77.6 200 0)
			(layer "F.Fab")
			(hide yes)
			(effects
				(font
					(size 1 1)
					(thickness 0.15)
				)
			)
		)
		(property "MPN" "CC0402MRX5R5BB106"
			(at 77.6 200 0)
			(layer "F.Fab")
			(hide yes)
			(effects
				(font
					(size 1 1)
					(thickness 0.15)
				)
			)
		)
		(property "Manufacturer" "Yaego"
			(at 77.6 200 0)
			(layer "F.Fab")
			(hide yes)
			(effects
				(font
					(size 1 1)
					(thickness 0.15)
				)
			)
		)
		(property "Val" "10u"
			(at 77.6 200 0)
			(layer "F.Fab")
			(hide yes)
			(effects
				(font
					(size 1 1)
					(thickness 0.15)
				)
			)
		)
		(property "Voltage" ""
			(at 77.6 200 0)
			(layer "F.Fab")
			(hide yes)
			(effects
				(font
					(size 1 1)
					(thickness 0.15)
				)
			)
		)
		(sheetname "Supply")
		(sheetfile "supply.kicad_sch")
		(attr smd)
		(fp_rect
			(start -0.94 -0.47)
			(end 0.94 0.47)
			(stroke
				(width 0.05)
				(type solid)
			)
			(fill no)
			(layer "F.CrtYd")
		)
		(fp_rect
			(start -0.499 -0.249)
			(end 0.499 0.249)
			(stroke
				(width 0.15)
				(type solid)
			)
			(fill no)
			(layer "F.Fab")
		)
		(pad "1" smd roundrect
			(at -0.484 0 270)
			(size 0.59 0.64)
			(layers "F.Cu" "F.Mask" "F.Paste")
			(roundrect_rratio 0.25)
			(net 461 "1V1_SYS")
			(pintype "passive")
		)
		(pad "2" smd roundrect
			(at 0.484 0 270)
			(size 0.59 0.64)
			(layers "F.Cu" "F.Mask" "F.Paste")
			(roundrect_rratio 0.25)
			(net 5 "GND")
			(pintype "passive")
		)
	)
	(footprint "antmicro-footprints:R_0402_1005Metric"
		(layer "F.Cu")
		(at 123.6475 102.449)
		(descr "Resistor SMD 0402")
		(tags "resistor SMD 0402")
		(property "Reference" "R142"
			(at -3.5475 0.351 0)
			(layer "F.SilkS")
			(effects
				(font
					(size 0.7 0.7)
					(thickness 0.15)
				)
				(justify left bottom)
			)
		)
		(property "Value" "R_31k6_0402"
			(at 0 1.4 0)
			(layer "F.Fab")
			(effects
				(font
					(size 0.7 0.7)
					(thickness 0.15)
				)
				(justify left bottom)
			)
		)
		(property "Description" "31k6 resistor in 0402 package with 1% tolerance"
			(at 0 0 0)
			(layer "F.Fab")
			(hide yes)
			(effects
				(font
					(size 1.27 1.27)
					(thickness 0.15)
				)
			)
		)
		(property "Author" "Antmicro"
			(at 0 0 0)
			(layer "F.Fab")
			(hide yes)
			(effects
				(font
					(size 1 1)
					(thickness 0.15)
				)
			)
		)
		(property "License" "Apache-2.0"
			(at 0 0 0)
			(layer "F.Fab")
			(hide yes)
			(effects
				(font
					(size 1 1)
					(thickness 0.15)
				)
			)
		)
		(property "MPN" "CR0402-FX-3162GLF"
			(at 0 0 0)
			(layer "F.Fab")
			(hide yes)
			(effects
				(font
					(size 1 1)
					(thickness 0.15)
				)
			)
		)
		(property "Manufacturer" "Bourns"
			(at 0 0 0)
			(layer "F.Fab")
			(hide yes)
			(effects
				(font
					(size 1 1)
					(thickness 0.15)
				)
			)
		)
		(property "Tolerance" "1%"
			(at 0 0 0)
			(layer "F.Fab")
			(hide yes)
			(effects
				(font
					(size 1 1)
					(thickness 0.15)
				)
			)
		)
		(property "Val" "31k6"
			(at 0 0 0)
			(layer "F.Fab")
			(hide yes)
			(effects
				(font
					(size 1 1)
					(thickness 0.15)
				)
			)
		)
		(sheetname "Supply")
		(sheetfile "supply.kicad_sch")
		(attr smd)
		(fp_rect
			(start -0.93 -0.47)
			(end 0.93 0.47)
			(stroke
				(width 0.05)
				(type solid)
			)
			(fill no)
			(layer "F.CrtYd")
		)
		(fp_rect
			(start -0.5 -0.25)
			(end 0.5 0.25)
			(stroke
				(width 0.15)
				(type solid)
			)
			(fill no)
			(layer "F.Fab")
		)
		(pad "1" smd roundrect
			(at -0.485 0)
			(size 0.59 0.64)
			(layers "F.Cu" "F.Mask" "F.Paste")
			(roundrect_rratio 0.25)
			(net 588 "/Supply/1V0_REG")
			(pintype "passive")
		)
		(pad "2" smd roundrect
			(at 0.485 0)
			(size 0.59 0.64)
			(layers "F.Cu" "F.Mask" "F.Paste")
			(roundrect_rratio 0.25)
			(net 599 "/Supply/1V0_FB")
			(pintype "passive")
		)
	)
	(footprint "antmicro-footprints:R_0402_1005Metric"
		(layer "F.Cu")
		(at 123.65 90.974)
		(descr "Resistor SMD 0402")
		(tags "resistor SMD 0402")
		(property "Reference" "R138"
			(at -3.65 0.326 0)
			(layer "F.SilkS")
			(effects
				(font
					(size 0.7 0.7)
					(thickness 0.15)
				)
				(justify left bottom)
			)
		)
		(property "Value" "R_31k6_0402"
			(at 0 1.4 0)
			(layer "F.Fab")
			(effects
				(font
					(size 0.7 0.7)
					(thickness 0.15)
				)
				(justify left bottom)
			)
		)
		(property "Description" "31k6 resistor in 0402 package with 1% tolerance"
			(at 0 0 0)
			(layer "F.Fab")
			(hide yes)
			(effects
				(font
					(size 1.27 1.27)
					(thickness 0.15)
				)
			)
		)
		(property "Author" "Antmicro"
			(at 0 0 0)
			(layer "F.Fab")
			(hide yes)
			(effects
				(font
					(size 1 1)
					(thickness 0.15)
				)
			)
		)
		(property "License" "Apache-2.0"
			(at 0 0 0)
			(layer "F.Fab")
			(hide yes)
			(effects
				(font
					(size 1 1)
					(thickness 0.15)
				)
			)
		)
		(property "MPN" "CR0402-FX-3162GLF"
			(at 0 0 0)
			(layer "F.Fab")
			(hide yes)
			(effects
				(font
					(size 1 1)
					(thickness 0.15)
				)
			)
		)
		(property "Manufacturer" "Bourns"
			(at 0 0 0)
			(layer "F.Fab")
			(hide yes)
			(effects
				(font
					(size 1 1)
					(thickness 0.15)
				)
			)
		)
		(property "Tolerance" "1%"
			(at 0 0 0)
			(layer "F.Fab")
			(hide yes)
			(effects
				(font
					(size 1 1)
					(thickness 0.15)
				)
			)
		)
		(property "Val" "31k6"
			(at 0 0 0)
			(layer "F.Fab")
			(hide yes)
			(effects
				(font
					(size 1 1)
					(thickness 0.15)
				)
			)
		)
		(sheetname "Supply")
		(sheetfile "supply.kicad_sch")
		(attr smd)
		(fp_rect
			(start -0.93 -0.47)
			(end 0.93 0.47)
			(stroke
				(width 0.05)
				(type solid)
			)
			(fill no)
			(layer "F.CrtYd")
		)
		(fp_rect
			(start -0.5 -0.25)
			(end 0.5 0.25)
			(stroke
				(width 0.15)
				(type solid)
			)
			(fill no)
			(layer "F.Fab")
		)
		(pad "1" smd roundrect
			(at -0.485 0)
			(size 0.59 0.64)
			(layers "F.Cu" "F.Mask" "F.Paste")
			(roundrect_rratio 0.25)
			(net 587 "/Supply/1V1_REG")
			(pintype "passive")
		)
		(pad "2" smd roundrect
			(at 0.485 0)
			(size 0.59 0.64)
			(layers "F.Cu" "F.Mask" "F.Paste")
			(roundrect_rratio 0.25)
			(net 598 "/Supply/1V1_FB")
			(pintype "passive")
		)
	)
	(footprint "antmicro-footprints:C_0603_1608Metric"
		(layer "F.Cu")
		(at 122.3 53.475 90)
		(descr "Capacitor SMD 0603")
		(tags "capacitor 0603")
		(property "Reference" "C186"
			(at 1.075 0.3 90)
			(layer "F.SilkS")
			(effects
				(font
					(size 0.7 0.7)
					(thickness 0.15)
				)
				(justify left bottom)
			)
		)
		(property "Value" "C_10u_25V_0603"
			(at 0 1.6 90)
			(layer "F.Fab")
			(effects
				(font
					(size 0.7 0.7)
					(thickness 0.15)
				)
				(justify left bottom)
			)
		)
		(property "Description" " "
			(at 0 0 90)
			(layer "F.Fab")
			(hide yes)
			(effects
				(font
					(size 1.27 1.27)
					(thickness 0.15)
				)
			)
		)
		(property "Author" "Antmicro"
			(at 175.775 -68.825 0)
			(layer "F.Fab")
			(hide yes)
			(effects
				(font
					(size 1 1)
					(thickness 0.15)
				)
			)
		)
		(property "Dielectric" ""
			(at 175.775 -68.825 0)
			(layer "F.Fab")
			(hide yes)
			(effects
				(font
					(size 1 1)
					(thickness 0.15)
				)
			)
		)
		(property "License" "Apache-2.0"
			(at 175.775 -68.825 0)
			(layer "F.Fab")
			(hide yes)
			(effects
				(font
					(size 1 1)
					(thickness 0.15)
				)
			)
		)
		(property "MPN" "C1608X5R1E106M080AC"
			(at 175.775 -68.825 0)
			(layer "F.Fab")
			(hide yes)
			(effects
				(font
					(size 1 1)
					(thickness 0.15)
				)
			)
		)
		(property "Manufacturer" "TDK"
			(at 175.775 -68.825 0)
			(layer "F.Fab")
			(hide yes)
			(effects
				(font
					(size 1 1)
					(thickness 0.15)
				)
			)
		)
		(property "Val" "10u/25V"
			(at 175.775 -68.825 0)
			(layer "F.Fab")
			(hide yes)
			(effects
				(font
					(size 1 1)
					(thickness 0.15)
				)
			)
		)
		(property "Voltage" ""
			(at 175.775 -68.825 0)
			(layer "F.Fab")
			(hide yes)
			(effects
				(font
					(size 1 1)
					(thickness 0.15)
				)
			)
		)
		(sheetname "Supply")
		(sheetfile "supply.kicad_sch")
		(attr exclude_from_pos_files exclude_from_bom dnp)
		(fp_line
			(start -0.3 -0.3)
			(end 0.3 -0.3)
			(stroke
				(width 0.15)
				(type solid)
			)
			(layer "F.SilkS")
		)
		(fp_line
			(start -0.3 0.3)
			(end 0.3 0.3)
			(stroke
				(width 0.15)
				(type solid)
			)
			(layer "F.SilkS")
		)
		(fp_rect
			(start -1.24 -0.7)
			(end 1.24 0.7)
			(stroke
				(width 0.05)
				(type solid)
			)
			(fill no)
			(layer "F.CrtYd")
		)
		(fp_rect
			(start -0.8 -0.4)
			(end 0.8 0.4)
			(stroke
				(width 0.15)
				(type solid)
			)
			(fill no)
			(layer "F.Fab")
		)
		(pad "1" smd roundrect
			(at -0.7 0 90)
			(size 0.6 0.8)
			(layers "F.Cu" "F.Mask" "F.Paste")
			(roundrect_rratio 0.2)
			(net 224 "VIN")
			(pintype "passive")
		)
		(pad "2" smd roundrect
			(at 0.7 0 90)
			(size 0.6 0.8)
			(layers "F.Cu" "F.Mask" "F.Paste")
			(roundrect_rratio 0.2)
			(net 5 "GND")
			(pintype "passive")
		)
	)
	(footprint "antmicro-footprints:C_0402_1005Metric"
		(layer "F.Cu")
		(at 111.147806 84.774 180)
		(descr "Capacitor SMD 0402")
		(tags "capacitor SMD 0402")
		(property "Reference" "C168"
			(at 3.647806 -0.326 180)
			(layer "F.SilkS")
			(effects
				(font
					(size 0.7 0.7)
					(thickness 0.15)
				)
				(justify left bottom)
			)
		)
		(property "Value" "C_22u_0402"
			(at 0 1.4 180)
			(layer "F.Fab")
			(effects
				(font
					(size 0.7 0.7)
					(thickness 0.15)
				)
				(justify left bottom)
			)
		)
		(property "Description" " "
			(at 0 0 180)
			(layer "F.Fab")
			(hide yes)
			(effects
				(font
					(size 1.27 1.27)
					(thickness 0.15)
				)
			)
		)
		(property "Author" "Antmicro"
			(at 222.295612 169.548 0)
			(layer "F.Fab")
			(hide yes)
			(effects
				(font
					(size 1 1)
					(thickness 0.15)
				)
			)
		)
		(property "Dielectric" ""
			(at 222.295612 169.548 0)
			(layer "F.Fab")
			(hide yes)
			(effects
				(font
					(size 1 1)
					(thickness 0.15)
				)
			)
		)
		(property "License" "Apache-2.0"
			(at 222.295612 169.548 0)
			(layer "F.Fab")
			(hide yes)
			(effects
				(font
					(size 1 1)
					(thickness 0.15)
				)
			)
		)
		(property "MPN" "04024W226MAT2A"
			(at 222.295612 169.548 0)
			(layer "F.Fab")
			(hide yes)
			(effects
				(font
					(size 1 1)
					(thickness 0.15)
				)
			)
		)
		(property "Manufacturer" "AVX"
			(at 222.295612 169.548 0)
			(layer "F.Fab")
			(hide yes)
			(effects
				(font
					(size 1 1)
					(thickness 0.15)
				)
			)
		)
		(property "Val" "22u"
			(at 222.295612 169.548 0)
			(layer "F.Fab")
			(hide yes)
			(effects
				(font
					(size 1 1)
					(thickness 0.15)
				)
			)
		)
		(property "Voltage" ""
			(at 222.295612 169.548 0)
			(layer "F.Fab")
			(hide yes)
			(effects
				(font
					(size 1 1)
					(thickness 0.15)
				)
			)
		)
		(sheetname "Supply")
		(sheetfile "supply.kicad_sch")
		(attr smd)
		(fp_rect
			(start -0.94 -0.47)
			(end 0.94 0.47)
			(stroke
				(width 0.05)
				(type solid)
			)
			(fill no)
			(layer "F.CrtYd")
		)
		(fp_rect
			(start -0.499 -0.249)
			(end 0.499 0.249)
			(stroke
				(width 0.15)
				(type solid)
			)
			(fill no)
			(layer "F.Fab")
		)
		(pad "1" smd roundrect
			(at -0.484 0 180)
			(size 0.59 0.64)
			(layers "F.Cu" "F.Mask" "F.Paste")
			(roundrect_rratio 0.25)
			(net 583 "/Supply/1V8_REG")
			(pintype "passive")
		)
		(pad "2" smd roundrect
			(at 0.484 0 180)
			(size 0.59 0.64)
			(layers "F.Cu" "F.Mask" "F.Paste")
			(roundrect_rratio 0.25)
			(net 5 "GND")
			(pintype "passive")
		)
	)
	(footprint "lpddr4-test-board-footprints:mounting-hole-3.2mm"
		(layer "F.Cu")
		(at 110.1 49.1)
		(property "Reference" "MH1"
			(at -0.178 4.025 0)
			(layer "F.SilkS")
			(hide yes)
			(effects
				(font
					(size 0.7 0.7)
					(thickness 0.15)
				)
				(justify left bottom)
			)
		)
		(property "Value" "M3.2"
			(at -0.153 -4.153 0)
			(layer "F.Fab")
			(hide yes)
			(effects
				(font
					(size 0.7 0.7)
					(thickness 0.15)
				)
				(justify left bottom)
			)
		)
		(attr through_hole board_only exclude_from_bom)
		(pad "1" thru_hole circle
			(at 0 0)
			(size 6 6)
			(drill 3.2)
			(layers "*.Cu" "*.Mask")
			(remove_unused_layers no)
		)
	)
	(footprint "antmicro-footprints:C_0603_1608Metric"
		(layer "F.Cu")
		(at 135.8 52.7 90)
		(descr "Capacitor SMD 0603")
		(tags "capacitor 0603")
		(property "Reference" "C197"
			(at 1 0.3 90)
			(layer "F.SilkS")
			(effects
				(font
					(size 0.7 0.7)
					(thickness 0.15)
				)
				(justify left bottom)
			)
		)
		(property "Value" "C_22u_0603"
			(at 0 1.6 90)
			(layer "F.Fab")
			(effects
				(font
					(size 0.7 0.7)
					(thickness 0.15)
				)
				(justify left bottom)
			)
		)
		(property "Description" " "
			(at 0 0 90)
			(layer "F.Fab")
			(hide yes)
			(effects
				(font
					(size 1.27 1.27)
					(thickness 0.15)
				)
			)
		)
		(property "Author" "Antmicro"
			(at 188.5 -83.1 0)
			(layer "F.Fab")
			(hide yes)
			(effects
				(font
					(size 1 1)
					(thickness 0.15)
				)
			)
		)
		(property "Dielectric" ""
			(at 188.5 -83.1 0)
			(layer "F.Fab")
			(hide yes)
			(effects
				(font
					(size 1 1)
					(thickness 0.15)
				)
			)
		)
		(property "License" "Apache-2.0"
			(at 188.5 -83.1 0)
			(layer "F.Fab")
			(hide yes)
			(effects
				(font
					(size 1 1)
					(thickness 0.15)
				)
			)
		)
		(property "MPN" "GRM188R60J226MEA0D"
			(at 188.5 -83.1 0)
			(layer "F.Fab")
			(hide yes)
			(effects
				(font
					(size 1 1)
					(thickness 0.15)
				)
			)
		)
		(property "Manufacturer" "Murata"
			(at 188.5 -83.1 0)
			(layer "F.Fab")
			(hide yes)
			(effects
				(font
					(size 1 1)
					(thickness 0.15)
				)
			)
		)
		(property "Val" "22u"
			(at 188.5 -83.1 0)
			(layer "F.Fab")
			(hide yes)
			(effects
				(font
					(size 1 1)
					(thickness 0.15)
				)
			)
		)
		(property "Voltage" ""
			(at 188.5 -83.1 0)
			(layer "F.Fab")
			(hide yes)
			(effects
				(font
					(size 1 1)
					(thickness 0.15)
				)
			)
		)
		(sheetname "Supply")
		(sheetfile "supply.kicad_sch")
		(attr exclude_from_pos_files exclude_from_bom dnp)
		(fp_line
			(start -0.3 -0.3)
			(end 0.3 -0.3)
			(stroke
				(width 0.15)
				(type solid)
			)
			(layer "F.SilkS")
		)
		(fp_line
			(start -0.3 0.3)
			(end 0.3 0.3)
			(stroke
				(width 0.15)
				(type solid)
			)
			(layer "F.SilkS")
		)
		(fp_rect
			(start -1.24 -0.7)
			(end 1.24 0.7)
			(stroke
				(width 0.05)
				(type solid)
			)
			(fill no)
			(layer "F.CrtYd")
		)
		(fp_rect
			(start -0.8 -0.4)
			(end 0.8 0.4)
			(stroke
				(width 0.15)
				(type solid)
			)
			(fill no)
			(layer "F.Fab")
		)
		(pad "1" smd roundrect
			(at -0.7 0 90)
			(size 0.6 0.8)
			(layers "F.Cu" "F.Mask" "F.Paste")
			(roundrect_rratio 0.2)
			(net 550 "VDD1V1")
			(pintype "passive")
		)
		(pad "2" smd roundrect
			(at 0.7 0 90)
			(size 0.6 0.8)
			(layers "F.Cu" "F.Mask" "F.Paste")
			(roundrect_rratio 0.2)
			(net 5 "GND")
			(pintype "passive")
		)
	)
	(footprint "antmicro-footprints:C_0402_1005Metric"
		(layer "F.Cu")
		(at 126.9 90.974 180)
		(descr "Capacitor SMD 0402")
		(tags "capacitor SMD 0402")
		(property "Reference" "C154"
			(at 1.9 -1.226 180)
			(layer "F.SilkS")
			(effects
				(font
					(size 0.7 0.7)
					(thickness 0.15)
				)
				(justify left bottom)
			)
		)
		(property "Value" "C_10u_0402"
			(at 0 1.4 180)
			(layer "F.Fab")
			(effects
				(font
					(size 0.7 0.7)
					(thickness 0.15)
				)
				(justify left bottom)
			)
		)
		(property "Description" " "
			(at 0 0 180)
			(layer "F.Fab")
			(hide yes)
			(effects
				(font
					(size 1.27 1.27)
					(thickness 0.15)
				)
			)
		)
		(property "Author" "Antmicro"
			(at 253.8 181.948 0)
			(layer "F.Fab")
			(hide yes)
			(effects
				(font
					(size 1 1)
					(thickness 0.15)
				)
			)
		)
		(property "Dielectric" ""
			(at 253.8 181.948 0)
			(layer "F.Fab")
			(hide yes)
			(effects
				(font
					(size 1 1)
					(thickness 0.15)
				)
			)
		)
		(property "License" "Apache-2.0"
			(at 253.8 181.948 0)
			(layer "F.Fab")
			(hide yes)
			(effects
				(font
					(size 1 1)
					(thickness 0.15)
				)
			)
		)
		(property "MPN" "CC0402MRX5R5BB106"
			(at 253.8 181.948 0)
			(layer "F.Fab")
			(hide yes)
			(effects
				(font
					(size 1 1)
					(thickness 0.15)
				)
			)
		)
		(property "Manufacturer" "Yaego"
			(at 253.8 181.948 0)
			(layer "F.Fab")
			(hide yes)
			(effects
				(font
					(size 1 1)
					(thickness 0.15)
				)
			)
		)
		(property "Val" "10u"
			(at 253.8 181.948 0)
			(layer "F.Fab")
			(hide yes)
			(effects
				(font
					(size 1 1)
					(thickness 0.15)
				)
			)
		)
		(property "Voltage" ""
			(at 253.8 181.948 0)
			(layer "F.Fab")
			(hide yes)
			(effects
				(font
					(size 1 1)
					(thickness 0.15)
				)
			)
		)
		(sheetname "Supply")
		(sheetfile "supply.kicad_sch")
		(attr smd)
		(fp_rect
			(start -0.94 -0.47)
			(end 0.94 0.47)
			(stroke
				(width 0.05)
				(type solid)
			)
			(fill no)
			(layer "F.CrtYd")
		)
		(fp_rect
			(start -0.499 -0.249)
			(end 0.499 0.249)
			(stroke
				(width 0.15)
				(type solid)
			)
			(fill no)
			(layer "F.Fab")
		)
		(pad "1" smd roundrect
			(at -0.484 0 180)
			(size 0.59 0.64)
			(layers "F.Cu" "F.Mask" "F.Paste")
			(roundrect_rratio 0.25)
			(net 463 "VCC5V0_INT")
			(pintype "passive")
		)
		(pad "2" smd roundrect
			(at 0.484 0 180)
			(size 0.59 0.64)
			(layers "F.Cu" "F.Mask" "F.Paste")
			(roundrect_rratio 0.25)
			(net 5 "GND")
			(pintype "passive")
		)
	)
	(footprint "antmicro-footprints:R_0402_1005Metric"
		(layer "F.Cu")
		(at 129.9825 99.549 180)
		(descr "Resistor SMD 0402")
		(tags "resistor SMD 0402")
		(property "Reference" "R124"
			(at -0.7175 -0.451 180)
			(layer "F.SilkS")
			(effects
				(font
					(size 0.7 0.7)
					(thickness 0.15)
				)
				(justify left bottom)
			)
		)
		(property "Value" "R_0R_0402"
			(at 0 1.4 180)
			(layer "F.Fab")
			(effects
				(font
					(size 0.7 0.7)
					(thickness 0.15)
				)
				(justify left bottom)
			)
		)
		(property "Description" "0R resistor in 0402 package with unspecified tolerance"
			(at 0 0 180)
			(layer "F.Fab")
			(hide yes)
			(effects
				(font
					(size 1.27 1.27)
					(thickness 0.15)
				)
			)
		)
		(property "Author" "Antmicro"
			(at 259.965 199.098 0)
			(layer "F.Fab")
			(hide yes)
			(effects
				(font
					(size 1 1)
					(thickness 0.15)
				)
			)
		)
		(property "Current" "1A"
			(at 259.965 199.098 0)
			(layer "F.Fab")
			(hide yes)
			(effects
				(font
					(size 1 1)
					(thickness 0.15)
				)
			)
		)
		(property "License" "Apache-2.0"
			(at 259.965 199.098 0)
			(layer "F.Fab")
			(hide yes)
			(effects
				(font
					(size 1 1)
					(thickness 0.15)
				)
			)
		)
		(property "MPN" "ERJ2GE0R00X"
			(at 259.965 199.098 0)
			(layer "F.Fab")
			(hide yes)
			(effects
				(font
					(size 1 1)
					(thickness 0.15)
				)
			)
		)
		(property "Manufacturer" "Panasonic"
			(at 259.965 199.098 0)
			(layer "F.Fab")
			(hide yes)
			(effects
				(font
					(size 1 1)
					(thickness 0.15)
				)
			)
		)
		(property "Tolerance" ""
			(at 259.965 199.098 0)
			(layer "F.Fab")
			(hide yes)
			(effects
				(font
					(size 1 1)
					(thickness 0.15)
				)
			)
		)
		(property "Val" "0R"
			(at 259.965 199.098 0)
			(layer "F.Fab")
			(hide yes)
			(effects
				(font
					(size 1 1)
					(thickness 0.15)
				)
			)
		)
		(sheetname "Supply")
		(sheetfile "supply.kicad_sch")
		(attr smd)
		(fp_rect
			(start -0.93 -0.47)
			(end 0.93 0.47)
			(stroke
				(width 0.05)
				(type solid)
			)
			(fill no)
			(layer "F.CrtYd")
		)
		(fp_rect
			(start -0.5 -0.25)
			(end 0.5 0.25)
			(stroke
				(width 0.15)
				(type solid)
			)
			(fill no)
			(layer "F.Fab")
		)
		(pad "1" smd roundrect
			(at -0.485 0 180)
			(size 0.59 0.64)
			(layers "F.Cu" "F.Mask" "F.Paste")
			(roundrect_rratio 0.25)
			(net 593 "/Supply/1V0_VCC_INT")
			(pintype "passive")
		)
		(pad "2" smd roundrect
			(at 0.485 0 180)
			(size 0.59 0.64)
			(layers "F.Cu" "F.Mask" "F.Paste")
			(roundrect_rratio 0.25)
			(net 611 "/Supply/1V0_FSEL")
			(pintype "passive")
		)
	)
	(footprint "antmicro-footprints:LED_0603_1608Metric_G"
		(layer "F.Cu")
		(at 137.7825 92.099)
		(descr "LED SMD 0603 Green")
		(tags "LED SMD 0603 Green")
		(property "Reference" "PWR3"
			(at -4.6825 -0.799 0)
			(layer "F.SilkS")
			(effects
				(font
					(size 0.7 0.7)
					(thickness 0.15)
				)
				(justify left bottom)
			)
		)
		(property "Value" "LED_G_0603_KP-1608CGCK"
			(at 0 1.6 0)
			(layer "F.Fab")
			(effects
				(font
					(size 0.7 0.7)
					(thickness 0.15)
				)
				(justify left bottom)
			)
		)
		(property "Author" "Antmicro"
			(at 0 0 0)
			(layer "F.Fab")
			(hide yes)
			(effects
				(font
					(size 1 1)
					(thickness 0.15)
				)
			)
		)
		(property "License" "Apache-2.0"
			(at 0 0 0)
			(layer "F.Fab")
			(hide yes)
			(effects
				(font
					(size 1 1)
					(thickness 0.15)
				)
			)
		)
		(property "MPN" "KP-1608CGCK"
			(at 0 0 0)
			(layer "F.Fab")
			(hide yes)
			(effects
				(font
					(size 1 1)
					(thickness 0.15)
				)
			)
		)
		(property "Manufacturer" "Kingbright"
			(at 0 0 0)
			(layer "F.Fab")
			(hide yes)
			(effects
				(font
					(size 1 1)
					(thickness 0.15)
				)
			)
		)
		(sheetname "Supply")
		(sheetfile "supply.kicad_sch")
		(attr smd)
		(fp_line
			(start -0.27 -0.35)
			(end 0.27 -0.35)
			(stroke
				(width 0.15)
				(type solid)
			)
			(layer "F.SilkS")
		)
		(fp_line
			(start -0.27 0.351)
			(end 0.27 0.351)
			(stroke
				(width 0.15)
				(type solid)
			)
			(layer "F.SilkS")
		)
		(fp_line
			(start -0.106328 -0.200008)
			(end -0.106328 0.199992)
			(stroke
				(width 0.1)
				(type solid)
			)
			(layer "F.SilkS")
		)
		(fp_line
			(start -0.106328 -0.200008)
			(end 0.093672 -8e-06)
			(stroke
				(width 0.1)
				(type solid)
			)
			(layer "F.SilkS")
		)
		(fp_line
			(start -0.106328 -8e-06)
			(end -0.29 0)
			(stroke
				(width 0.1)
				(type solid)
			)
			(layer "F.SilkS")
		)
		(fp_line
			(start 0.093672 -0.200008)
			(end 0.093672 0.199992)
			(stroke
				(width 0.1)
				(type solid)
			)
			(layer "F.SilkS")
		)
		(fp_line
			(start 0.093672 -8e-06)
			(end -0.106328 0.199992)
			(stroke
				(width 0.1)
				(type solid)
			)
			(layer "F.SilkS")
		)
		(fp_line
			(start 0.093672 -8e-06)
			(end 0.293672 -8e-06)
			(stroke
				(width 0.1)
				(type solid)
			)
			(layer "F.SilkS")
		)
		(fp_line
			(start 1.25 0.32)
			(end 1.25 -0.32)
			(stroke
				(width 0.15)
				(type solid)
			)
			(layer "F.SilkS")
		)
		(fp_rect
			(start 1.26 0.65)
			(end -1.26 -0.65)
			(stroke
				(width 0.05)
				(type solid)
			)
			(fill no)
			(layer "F.CrtYd")
		)
		(fp_line
			(start -0.599 0)
			(end -0.201 0)
			(stroke
				(width 0.15)
				(type solid)
			)
			(layer "F.Fab")
		)
		(fp_line
			(start -0.201 -0.2)
			(end -0.201 0)
			(stroke
				(width 0.15)
				(type solid)
			)
			(layer "F.Fab")
		)
		(fp_line
			(start -0.201 0)
			(end -0.201 0.202)
			(stroke
				(width 0.15)
				(type solid)
			)
			(layer "F.Fab")
		)
		(fp_line
			(start -0.201 0.202)
			(end 0.101 0)
			(stroke
				(width 0.15)
				(type solid)
			)
			(layer "F.Fab")
		)
		(fp_line
			(start 0.101 0)
			(end -0.201 -0.2)
			(stroke
				(width 0.15)
				(type solid)
			)
			(layer "F.Fab")
		)
		(fp_line
			(start 0.199 -0.2)
			(end 0.199 -0.1)
			(stroke
				(width 0.15)
				(type solid)
			)
			(layer "F.Fab")
		)
		(fp_line
			(start 0.199 0)
			(end 0.597 0)
			(stroke
				(width 0.15)
				(type solid)
			)
			(layer "F.Fab")
		)
		(fp_line
			(start 0.199 0.202)
			(end 0.199 -0.1)
			(stroke
				(width 0.15)
				(type solid)
			)
			(layer "F.Fab")
		)
		(fp_rect
			(start -0.848 -0.4)
			(end 0.85 0.402)
			(stroke
				(width 0.15)
				(type solid)
			)
			(fill no)
			(layer "F.Fab")
		)
		(pad "1" smd rect
			(at -0.75 0 180)
			(size 0.8 0.8)
			(layers "F.Cu" "F.Mask" "F.Paste")
			(net 459 "3V3_SYS")
			(pinfunction "1")
			(pintype "passive")
		)
		(pad "2" smd rect
			(at 0.75 0 180)
			(size 0.8 0.8)
			(layers "F.Cu" "F.Mask" "F.Paste")
			(net 555 "Net-(PWR3-Pad2)")
			(pinfunction "2")
			(pintype "passive")
		)
	)
	(footprint "antmicro-footprints:LED_0603_1608Metric_G"
		(layer "F.Cu")
		(at 137.7825 87.099)
		(descr "LED SMD 0603 Green")
		(tags "LED SMD 0603 Green")
		(property "Reference" "PWR4"
			(at -4.6825 -0.799 0)
			(layer "F.SilkS")
			(effects
				(font
					(size 0.7 0.7)
					(thickness 0.15)
				)
				(justify left bottom)
			)
		)
		(property "Value" "LED_G_0603_KP-1608CGCK"
			(at 0 1.6 0)
			(layer "F.Fab")
			(effects
				(font
					(size 0.7 0.7)
					(thickness 0.15)
				)
				(justify left bottom)
			)
		)
		(property "Author" "Antmicro"
			(at 0 0 0)
			(layer "F.Fab")
			(hide yes)
			(effects
				(font
					(size 1 1)
					(thickness 0.15)
				)
			)
		)
		(property "License" "Apache-2.0"
			(at 0 0 0)
			(layer "F.Fab")
			(hide yes)
			(effects
				(font
					(size 1 1)
					(thickness 0.15)
				)
			)
		)
		(property "MPN" "KP-1608CGCK"
			(at 0 0 0)
			(layer "F.Fab")
			(hide yes)
			(effects
				(font
					(size 1 1)
					(thickness 0.15)
				)
			)
		)
		(property "Manufacturer" "Kingbright"
			(at 0 0 0)
			(layer "F.Fab")
			(hide yes)
			(effects
				(font
					(size 1 1)
					(thickness 0.15)
				)
			)
		)
		(sheetname "Supply")
		(sheetfile "supply.kicad_sch")
		(attr smd)
		(fp_line
			(start -0.27 -0.35)
			(end 0.27 -0.35)
			(stroke
				(width 0.15)
				(type solid)
			)
			(layer "F.SilkS")
		)
		(fp_line
			(start -0.27 0.351)
			(end 0.27 0.351)
			(stroke
				(width 0.15)
				(type solid)
			)
			(layer "F.SilkS")
		)
		(fp_line
			(start -0.106328 -0.200008)
			(end -0.106328 0.199992)
			(stroke
				(width 0.1)
				(type solid)
			)
			(layer "F.SilkS")
		)
		(fp_line
			(start -0.106328 -0.200008)
			(end 0.093672 -8e-06)
			(stroke
				(width 0.1)
				(type solid)
			)
			(layer "F.SilkS")
		)
		(fp_line
			(start -0.106328 -8e-06)
			(end -0.29 0)
			(stroke
				(width 0.1)
				(type solid)
			)
			(layer "F.SilkS")
		)
		(fp_line
			(start 0.093672 -0.200008)
			(end 0.093672 0.199992)
			(stroke
				(width 0.1)
				(type solid)
			)
			(layer "F.SilkS")
		)
		(fp_line
			(start 0.093672 -8e-06)
			(end -0.106328 0.199992)
			(stroke
				(width 0.1)
				(type solid)
			)
			(layer "F.SilkS")
		)
		(fp_line
			(start 0.093672 -8e-06)
			(end 0.293672 -8e-06)
			(stroke
				(width 0.1)
				(type solid)
			)
			(layer "F.SilkS")
		)
		(fp_line
			(start 1.25 0.32)
			(end 1.25 -0.32)
			(stroke
				(width 0.15)
				(type solid)
			)
			(layer "F.SilkS")
		)
		(fp_rect
			(start 1.26 0.65)
			(end -1.26 -0.65)
			(stroke
				(width 0.05)
				(type solid)
			)
			(fill no)
			(layer "F.CrtYd")
		)
		(fp_line
			(start -0.599 0)
			(end -0.201 0)
			(stroke
				(width 0.15)
				(type solid)
			)
			(layer "F.Fab")
		)
		(fp_line
			(start -0.201 -0.2)
			(end -0.201 0)
			(stroke
				(width 0.15)
				(type solid)
			)
			(layer "F.Fab")
		)
		(fp_line
			(start -0.201 0)
			(end -0.201 0.202)
			(stroke
				(width 0.15)
				(type solid)
			)
			(layer "F.Fab")
		)
		(fp_line
			(start -0.201 0.202)
			(end 0.101 0)
			(stroke
				(width 0.15)
				(type solid)
			)
			(layer "F.Fab")
		)
		(fp_line
			(start 0.101 0)
			(end -0.201 -0.2)
			(stroke
				(width 0.15)
				(type solid)
			)
			(layer "F.Fab")
		)
		(fp_line
			(start 0.199 -0.2)
			(end 0.199 -0.1)
			(stroke
				(width 0.15)
				(type solid)
			)
			(layer "F.Fab")
		)
		(fp_line
			(start 0.199 0)
			(end 0.597 0)
			(stroke
				(width 0.15)
				(type solid)
			)
			(layer "F.Fab")
		)
		(fp_line
			(start 0.199 0.202)
			(end 0.199 -0.1)
			(stroke
				(width 0.15)
				(type solid)
			)
			(layer "F.Fab")
		)
		(fp_rect
			(start -0.848 -0.4)
			(end 0.85 0.402)
			(stroke
				(width 0.15)
				(type solid)
			)
			(fill no)
			(layer "F.Fab")
		)
		(pad "1" smd rect
			(at -0.75 0 180)
			(size 0.8 0.8)
			(layers "F.Cu" "F.Mask" "F.Paste")
			(net 459 "3V3_SYS")
			(pinfunction "1")
			(pintype "passive")
		)
		(pad "2" smd rect
			(at 0.75 0 180)
			(size 0.8 0.8)
			(layers "F.Cu" "F.Mask" "F.Paste")
			(net 556 "Net-(PWR4-Pad2)")
			(pinfunction "2")
			(pintype "passive")
		)
	)
	(footprint "antmicro-footprints:R_0402_1005Metric"
		(layer "F.Cu")
		(at 111.94 100.449)
		(descr "Resistor SMD 0402")
		(tags "resistor SMD 0402")
		(property "Reference" "R129"
			(at -3.64 0.351 0)
			(layer "F.SilkS")
			(effects
				(font
					(size 0.7 0.7)
					(thickness 0.15)
				)
				(justify left bottom)
			)
		)
		(property "Value" "R_0R_0402"
			(at 0 1.4 0)
			(layer "F.Fab")
			(effects
				(font
					(size 0.7 0.7)
					(thickness 0.15)
				)
				(justify left bottom)
			)
		)
		(property "Description" "0R resistor in 0402 package with unspecified tolerance"
			(at 0 0 0)
			(layer "F.Fab")
			(hide yes)
			(effects
				(font
					(size 1.27 1.27)
					(thickness 0.15)
				)
			)
		)
		(property "Author" "Antmicro"
			(at 0 0 0)
			(layer "F.Fab")
			(hide yes)
			(effects
				(font
					(size 1 1)
					(thickness 0.15)
				)
			)
		)
		(property "Current" "1A"
			(at 0 0 0)
			(layer "F.Fab")
			(hide yes)
			(effects
				(font
					(size 1 1)
					(thickness 0.15)
				)
			)
		)
		(property "License" "Apache-2.0"
			(at 0 0 0)
			(layer "F.Fab")
			(hide yes)
			(effects
				(font
					(size 1 1)
					(thickness 0.15)
				)
			)
		)
		(property "MPN" "ERJ2GE0R00X"
			(at 0 0 0)
			(layer "F.Fab")
			(hide yes)
			(effects
				(font
					(size 1 1)
					(thickness 0.15)
				)
			)
		)
		(property "Manufacturer" "Panasonic"
			(at 0 0 0)
			(layer "F.Fab")
			(hide yes)
			(effects
				(font
					(size 1 1)
					(thickness 0.15)
				)
			)
		)
		(property "Tolerance" ""
			(at 0 0 0)
			(layer "F.Fab")
			(hide yes)
			(effects
				(font
					(size 1 1)
					(thickness 0.15)
				)
			)
		)
		(property "Val" "0R"
			(at 0 0 0)
			(layer "F.Fab")
			(hide yes)
			(effects
				(font
					(size 1 1)
					(thickness 0.15)
				)
			)
		)
		(sheetname "Supply")
		(sheetfile "supply.kicad_sch")
		(attr smd)
		(fp_rect
			(start -0.93 -0.47)
			(end 0.93 0.47)
			(stroke
				(width 0.05)
				(type solid)
			)
			(fill no)
			(layer "F.CrtYd")
		)
		(fp_rect
			(start -0.5 -0.25)
			(end 0.5 0.25)
			(stroke
				(width 0.15)
				(type solid)
			)
			(fill no)
			(layer "F.Fab")
		)
		(pad "1" smd roundrect
			(at -0.485 0)
			(size 0.59 0.64)
			(layers "F.Cu" "F.Mask" "F.Paste")
			(roundrect_rratio 0.25)
			(net 5 "GND")
			(pintype "passive")
		)
		(pad "2" smd roundrect
			(at 0.485 0)
			(size 0.59 0.64)
			(layers "F.Cu" "F.Mask" "F.Paste")
			(roundrect_rratio 0.25)
			(net 618 "/Supply/3V3_SS{slash}TR")
			(pintype "passive")
		)
	)
	(footprint "antmicro-footprints:SOT-523"
		(layer "F.Cu")
		(at 142.3825 87.099 90)
		(property "Reference" "Q10"
			(at 0.599 -2.5825 0)
			(layer "F.SilkS")
			(effects
				(font
					(size 0.7 0.7)
					(thickness 0.15)
				)
				(justify left bottom)
			)
		)
		(property "Value" "DMG1012T-7"
			(at 0.1 1.824 90)
			(layer "F.Fab")
			(effects
				(font
					(size 0.7 0.7)
					(thickness 0.15)
				)
				(justify left bottom)
			)
		)
		(property "Author" "Antmicro"
			(at 229.4815 -55.2835 0)
			(layer "F.Fab")
			(hide yes)
			(effects
				(font
					(size 1 1)
					(thickness 0.15)
				)
			)
		)
		(property "License" "Apache-2.0"
			(at 229.4815 -55.2835 0)
			(layer "F.Fab")
			(hide yes)
			(effects
				(font
					(size 1 1)
					(thickness 0.15)
				)
			)
		)
		(property "MPN" "DMG1012T-7"
			(at 229.4815 -55.2835 0)
			(layer "F.Fab")
			(hide yes)
			(effects
				(font
					(size 1 1)
					(thickness 0.15)
				)
			)
		)
		(property "Manufacturer" "Diodes Incorporated"
			(at 229.4815 -55.2835 0)
			(layer "F.Fab")
			(hide yes)
			(effects
				(font
					(size 1 1)
					(thickness 0.15)
				)
			)
		)
		(sheetname "Supply")
		(sheetfile "supply.kicad_sch")
		(attr smd)
		(fp_line
			(start -0.277 -0.551)
			(end -0.277 -0.75)
			(stroke
				(width 0.15)
				(type solid)
			)
			(layer "F.SilkS")
		)
		(fp_line
			(start -0.725 -0.551)
			(end -0.277 -0.551)
			(stroke
				(width 0.15)
				(type solid)
			)
			(layer "F.SilkS")
		)
		(fp_line
			(start -0.927 -0.351)
			(end -0.725 -0.551)
			(stroke
				(width 0.15)
				(type solid)
			)
			(layer "F.SilkS")
		)
		(fp_line
			(start -0.927 -0.051)
			(end -0.927 -0.351)
			(stroke
				(width 0.15)
				(type solid)
			)
			(layer "F.SilkS")
		)
		(fp_circle
			(center -0.9652 0.9652)
			(end -0.9152 0.9652)
			(stroke
				(width 0.15)
				(type solid)
			)
			(fill yes)
			(layer "F.SilkS")
		)
		(fp_line
			(start 1.1 -1.16)
			(end 1.1 1.15)
			(stroke
				(width 0.05)
				(type solid)
			)
			(layer "F.CrtYd")
		)
		(fp_line
			(start -1.12 -1.16)
			(end 1.1 -1.16)
			(stroke
				(width 0.05)
				(type solid)
			)
			(layer "F.CrtYd")
		)
		(fp_line
			(start -1.12 -1.16)
			(end -1.12 1.15)
			(stroke
				(width 0.05)
				(type solid)
			)
			(layer "F.CrtYd")
		)
		(fp_line
			(start -1.12 1.15)
			(end 1.1 1.15)
			(stroke
				(width 0.05)
				(type solid)
			)
			(layer "F.CrtYd")
		)
		(fp_line
			(start 0.8 -0.425)
			(end -0.652 -0.425)
			(stroke
				(width 0.15)
				(type solid)
			)
			(layer "F.Fab")
		)
		(fp_line
			(start 0.8 -0.425)
			(end 0.8 0.424)
			(stroke
				(width 0.15)
				(type solid)
			)
			(layer "F.Fab")
		)
		(fp_line
			(start -0.652 -0.425)
			(end -0.802 -0.276)
			(stroke
				(width 0.15)
				(type solid)
			)
			(layer "F.Fab")
		)
		(fp_line
			(start -0.802 -0.276)
			(end -0.802 0.424)
			(stroke
				(width 0.15)
				(type solid)
			)
			(layer "F.Fab")
		)
		(fp_line
			(start 0.8 0.424)
			(end -0.802 0.424)
			(stroke
				(width 0.15)
				(type solid)
			)
			(layer "F.Fab")
		)
		(fp_circle
			(center -0.9652 0.9652)
			(end -0.9144 0.9652)
			(stroke
				(width 0.15)
				(type solid)
			)
			(fill no)
			(layer "F.Fab")
		)
		(pad "1" smd rect
			(at -0.5 0.65 90)
			(size 0.4 0.51)
			(layers "F.Cu" "F.Mask" "F.Paste")
			(net 461 "1V1_SYS")
			(pinfunction "G")
			(pintype "bidirectional")
		)
		(pad "2" smd rect
			(at 0.498 0.65 90)
			(size 0.4 0.51)
			(layers "F.Cu" "F.Mask" "F.Paste")
			(net 5 "GND")
			(pinfunction "S")
			(pintype "bidirectional")
		)
		(pad "3" smd rect
			(at 0 -0.652 90)
			(size 0.4 0.51)
			(layers "F.Cu" "F.Mask" "F.Paste")
			(net 236 "Net-(Q10-D)")
			(pinfunction "D")
			(pintype "bidirectional")
		)
	)
	(footprint "antmicro-footprints:LED_0603_1608Metric_G"
		(layer "F.Cu")
		(at 137.7825 89.599)
		(descr "LED SMD 0603 Green")
		(tags "LED SMD 0603 Green")
		(property "Reference" "PWR2"
			(at -4.6825 -0.799 0)
			(layer "F.SilkS")
			(effects
				(font
					(size 0.7 0.7)
					(thickness 0.15)
				)
				(justify left bottom)
			)
		)
		(property "Value" "LED_G_0603_KP-1608CGCK"
			(at 0 1.6 0)
			(layer "F.Fab")
			(effects
				(font
					(size 0.7 0.7)
					(thickness 0.15)
				)
				(justify left bottom)
			)
		)
		(property "Author" "Antmicro"
			(at 0 0 0)
			(layer "F.Fab")
			(hide yes)
			(effects
				(font
					(size 1 1)
					(thickness 0.15)
				)
			)
		)
		(property "License" "Apache-2.0"
			(at 0 0 0)
			(layer "F.Fab")
			(hide yes)
			(effects
				(font
					(size 1 1)
					(thickness 0.15)
				)
			)
		)
		(property "MPN" "KP-1608CGCK"
			(at 0 0 0)
			(layer "F.Fab")
			(hide yes)
			(effects
				(font
					(size 1 1)
					(thickness 0.15)
				)
			)
		)
		(property "Manufacturer" "Kingbright"
			(at 0 0 0)
			(layer "F.Fab")
			(hide yes)
			(effects
				(font
					(size 1 1)
					(thickness 0.15)
				)
			)
		)
		(sheetname "Supply")
		(sheetfile "supply.kicad_sch")
		(attr smd)
		(fp_line
			(start -0.27 -0.35)
			(end 0.27 -0.35)
			(stroke
				(width 0.15)
				(type solid)
			)
			(layer "F.SilkS")
		)
		(fp_line
			(start -0.27 0.351)
			(end 0.27 0.351)
			(stroke
				(width 0.15)
				(type solid)
			)
			(layer "F.SilkS")
		)
		(fp_line
			(start -0.106328 -0.200008)
			(end -0.106328 0.199992)
			(stroke
				(width 0.1)
				(type solid)
			)
			(layer "F.SilkS")
		)
		(fp_line
			(start -0.106328 -0.200008)
			(end 0.093672 -8e-06)
			(stroke
				(width 0.1)
				(type solid)
			)
			(layer "F.SilkS")
		)
		(fp_line
			(start -0.106328 -8e-06)
			(end -0.29 0)
			(stroke
				(width 0.1)
				(type solid)
			)
			(layer "F.SilkS")
		)
		(fp_line
			(start 0.093672 -0.200008)
			(end 0.093672 0.199992)
			(stroke
				(width 0.1)
				(type solid)
			)
			(layer "F.SilkS")
		)
		(fp_line
			(start 0.093672 -8e-06)
			(end -0.106328 0.199992)
			(stroke
				(width 0.1)
				(type solid)
			)
			(layer "F.SilkS")
		)
		(fp_line
			(start 0.093672 -8e-06)
			(end 0.293672 -8e-06)
			(stroke
				(width 0.1)
				(type solid)
			)
			(layer "F.SilkS")
		)
		(fp_line
			(start 1.25 0.32)
			(end 1.25 -0.32)
			(stroke
				(width 0.15)
				(type solid)
			)
			(layer "F.SilkS")
		)
		(fp_rect
			(start 1.26 0.65)
			(end -1.26 -0.65)
			(stroke
				(width 0.05)
				(type solid)
			)
			(fill no)
			(layer "F.CrtYd")
		)
		(fp_line
			(start -0.599 0)
			(end -0.201 0)
			(stroke
				(width 0.15)
				(type solid)
			)
			(layer "F.Fab")
		)
		(fp_line
			(start -0.201 -0.2)
			(end -0.201 0)
			(stroke
				(width 0.15)
				(type solid)
			)
			(layer "F.Fab")
		)
		(fp_line
			(start -0.201 0)
			(end -0.201 0.202)
			(stroke
				(width 0.15)
				(type solid)
			)
			(layer "F.Fab")
		)
		(fp_line
			(start -0.201 0.202)
			(end 0.101 0)
			(stroke
				(width 0.15)
				(type solid)
			)
			(layer "F.Fab")
		)
		(fp_line
			(start 0.101 0)
			(end -0.201 -0.2)
			(stroke
				(width 0.15)
				(type solid)
			)
			(layer "F.Fab")
		)
		(fp_line
			(start 0.199 -0.2)
			(end 0.199 -0.1)
			(stroke
				(width 0.15)
				(type solid)
			)
			(layer "F.Fab")
		)
		(fp_line
			(start 0.199 0)
			(end 0.597 0)
			(stroke
				(width 0.15)
				(type solid)
			)
			(layer "F.Fab")
		)
		(fp_line
			(start 0.199 0.202)
			(end 0.199 -0.1)
			(stroke
				(width 0.15)
				(type solid)
			)
			(layer "F.Fab")
		)
		(fp_rect
			(start -0.848 -0.4)
			(end 0.85 0.402)
			(stroke
				(width 0.15)
				(type solid)
			)
			(fill no)
			(layer "F.Fab")
		)
		(pad "1" smd rect
			(at -0.75 0 180)
			(size 0.8 0.8)
			(layers "F.Cu" "F.Mask" "F.Paste")
			(net 459 "3V3_SYS")
			(pinfunction "1")
			(pintype "passive")
		)
		(pad "2" smd rect
			(at 0.75 0 180)
			(size 0.8 0.8)
			(layers "F.Cu" "F.Mask" "F.Paste")
			(net 553 "Net-(PWR2-Pad2)")
			(pinfunction "2")
			(pintype "passive")
		)
	)
	(footprint "antmicro-footprints:C_0402_1005Metric"
		(layer "F.Cu")
		(at 128.675 56.725 180)
		(descr "Capacitor SMD 0402")
		(tags "capacitor SMD 0402")
		(property "Reference" "C191"
			(at 1.216843 -1.312672 0)
			(layer "F.SilkS")
			(effects
				(font
					(size 0.7 0.7)
					(thickness 0.15)
				)
				(justify left bottom)
			)
		)
		(property "Value" "C_100n_6V3_0402"
			(at 0 1.4 180)
			(layer "F.Fab")
			(effects
				(font
					(size 0.7 0.7)
					(thickness 0.15)
				)
				(justify left bottom)
			)
		)
		(property "Description" " "
			(at 0 0 180)
			(layer "F.Fab")
			(hide yes)
			(effects
				(font
					(size 1.27 1.27)
					(thickness 0.15)
				)
			)
		)
		(property "Author" "Antmicro"
			(at 257.35 113.45 0)
			(layer "F.Fab")
			(hide yes)
			(effects
				(font
					(size 1 1)
					(thickness 0.15)
				)
			)
		)
		(property "Dielectric" ""
			(at 257.35 113.45 0)
			(layer "F.Fab")
			(hide yes)
			(effects
				(font
					(size 1 1)
					(thickness 0.15)
				)
			)
		)
		(property "License" "Apache-2.0"
			(at 257.35 113.45 0)
			(layer "F.Fab")
			(hide yes)
			(effects
				(font
					(size 1 1)
					(thickness 0.15)
				)
			)
		)
		(property "MPN" "0402X104K6R3CT"
			(at 257.35 113.45 0)
			(layer "F.Fab")
			(hide yes)
			(effects
				(font
					(size 1 1)
					(thickness 0.15)
				)
			)
		)
		(property "Manufacturer" "Walsin"
			(at 257.35 113.45 0)
			(layer "F.Fab")
			(hide yes)
			(effects
				(font
					(size 1 1)
					(thickness 0.15)
				)
			)
		)
		(property "Val" "100n"
			(at 257.35 113.45 0)
			(layer "F.Fab")
			(hide yes)
			(effects
				(font
					(size 1 1)
					(thickness 0.15)
				)
			)
		)
		(property "Voltage" ""
			(at 257.35 113.45 0)
			(layer "F.Fab")
			(hide yes)
			(effects
				(font
					(size 1 1)
					(thickness 0.15)
				)
			)
		)
		(sheetname "Supply")
		(sheetfile "supply.kicad_sch")
		(attr exclude_from_pos_files exclude_from_bom dnp)
		(fp_rect
			(start -0.94 -0.47)
			(end 0.94 0.47)
			(stroke
				(width 0.05)
				(type solid)
			)
			(fill no)
			(layer "F.CrtYd")
		)
		(fp_rect
			(start -0.499 -0.249)
			(end 0.499 0.249)
			(stroke
				(width 0.15)
				(type solid)
			)
			(fill no)
			(layer "F.Fab")
		)
		(pad "1" smd roundrect
			(at -0.484 0 180)
			(size 0.59 0.64)
			(layers "F.Cu" "F.Mask" "F.Paste")
			(roundrect_rratio 0.25)
			(net 659 "Net-(C191-Pad1)")
			(pintype "passive")
		)
		(pad "2" smd roundrect
			(at 0.484 0 180)
			(size 0.59 0.64)
			(layers "F.Cu" "F.Mask" "F.Paste")
			(roundrect_rratio 0.25)
			(net 625 "/Supply/VDD2_SW")
			(pintype "passive")
		)
	)
	(footprint "antmicro-footprints:Oscillator_SMD_Abracon_ASFL1-4Pin_5.0x3.2mm"
		(layer "F.Cu")
		(at 177.5 111.7 180)
		(property "Reference" "U2"
			(at -1.57 -3.108 180)
			(layer "F.SilkS")
			(effects
				(font
					(size 0.7 0.7)
					(thickness 0.15)
				)
				(justify left bottom)
			)
		)
		(property "Value" "ASFL1-100.000MHZ-L-T"
			(at -11.7 3.3 180)
			(layer "F.Fab")
			(effects
				(font
					(size 0.7 0.7)
					(thickness 0.15)
				)
				(justify left bottom)
			)
		)
		(property "Description" "Oscillator, 100 MHz, 100 ppm, SMT, 5mm x 3.2mm, 3.3 V, ASFL1 Series"
			(at 0 0 180)
			(layer "F.Fab")
			(hide yes)
			(effects
				(font
					(size 1.27 1.27)
					(thickness 0.15)
				)
			)
		)
		(property "Author" "Antmicro"
			(at 355 223.4 0)
			(layer "F.Fab")
			(hide yes)
			(effects
				(font
					(size 1 1)
					(thickness 0.15)
				)
			)
		)
		(property "License" "Apache-2.0"
			(at 355 223.4 0)
			(layer "F.Fab")
			(hide yes)
			(effects
				(font
					(size 1 1)
					(thickness 0.15)
				)
			)
		)
		(property "MPN" "ASFL1-100.000MHZ-L-T"
			(at 355 223.4 0)
			(layer "F.Fab")
			(hide yes)
			(effects
				(font
					(size 1 1)
					(thickness 0.15)
				)
			)
		)
		(property "Manufacturer" "Abracon"
			(at 355 223.4 0)
			(layer "F.Fab")
			(hide yes)
			(effects
				(font
					(size 1 1)
					(thickness 0.15)
				)
			)
		)
		(property "Val" "100 MHz"
			(at 355 223.4 0)
			(layer "F.Fab")
			(hide yes)
			(effects
				(font
					(size 1 1)
					(thickness 0.15)
				)
			)
		)
		(sheetname "FPGA Banks")
		(sheetfile "fpga-banks.kicad_sch")
		(attr smd)
		(fp_line
			(start 2.7 1.8)
			(end 2.298 1.8)
			(stroke
				(width 0.15)
				(type solid)
			)
			(layer "F.SilkS")
		)
		(fp_line
			(start 2.7 1.398)
			(end 2.7 1.8)
			(stroke
				(width 0.15)
				(type solid)
			)
			(layer "F.SilkS")
		)
		(fp_line
			(start 2.7 -1.801)
			(end 2.7 -1.401)
			(stroke
				(width 0.15)
				(type solid)
			)
			(layer "F.SilkS")
		)
		(fp_line
			(start 2.298 -1.801)
			(end 2.7 -1.801)
			(stroke
				(width 0.15)
				(type solid)
			)
			(layer "F.SilkS")
		)
		(fp_line
			(start -2.702 1.8)
			(end -2.702 1.398)
			(stroke
				(width 0.15)
				(type solid)
			)
			(layer "F.SilkS")
		)
		(fp_line
			(start -2.702 -1.401)
			(end -2.702 -1.801)
			(stroke
				(width 0.15)
				(type solid)
			)
			(layer "F.SilkS")
		)
		(fp_line
			(start -2.702 -1.801)
			(end -2.301 -1.801)
			(stroke
				(width 0.15)
				(type solid)
			)
			(layer "F.SilkS")
		)
		(fp_circle
			(center -2.4 2.1)
			(end -2.35 2.1)
			(stroke
				(width 0.15)
				(type solid)
			)
			(fill no)
			(layer "F.SilkS")
		)
		(fp_rect
			(start -3 -2.101)
			(end 2.999 2.1)
			(stroke
				(width 0.05)
				(type solid)
			)
			(fill no)
			(layer "F.CrtYd")
		)
		(fp_line
			(start -2 1.6)
			(end -2.5 1.1)
			(stroke
				(width 0.15)
				(type solid)
			)
			(layer "F.Fab")
		)
		(fp_line
			(start -2.1 1.6)
			(end -2.5 1.2)
			(stroke
				(width 0.15)
				(type solid)
			)
			(layer "F.Fab")
		)
		(fp_line
			(start -2.2 1.6)
			(end -2.5 1.3)
			(stroke
				(width 0.15)
				(type solid)
			)
			(layer "F.Fab")
		)
		(fp_line
			(start -2.3 1.6)
			(end -2.5 1.4)
			(stroke
				(width 0.15)
				(type solid)
			)
			(layer "F.Fab")
		)
		(fp_rect
			(start -2.5 -1.601)
			(end 2.499 1.6)
			(stroke
				(width 0.15)
				(type solid)
			)
			(fill no)
			(layer "F.Fab")
		)
		(pad "1" smd rect
			(at -1.27 1.1)
			(size 1.7 1.5)
			(layers "F.Cu" "F.Mask" "F.Paste")
			(net 459 "3V3_SYS")
			(pinfunction "EN")
			(pintype "input")
		)
		(pad "2" smd rect
			(at 1.269 1.1 180)
			(size 1.7 1.5)
			(layers "F.Cu" "F.Mask" "F.Paste")
			(net 5 "GND")
			(pinfunction "GND")
			(pintype "power_in")
		)
		(pad "3" smd rect
			(at 1.269 -1.101 180)
			(size 1.7 1.5)
			(layers "F.Cu" "F.Mask" "F.Paste")
			(net 38 "GCLK100")
			(pinfunction "OUT")
			(pintype "output")
		)
		(pad "4" smd rect
			(at -1.27 -1.101 180)
			(size 1.7 1.5)
			(layers "F.Cu" "F.Mask" "F.Paste")
			(net 459 "3V3_SYS")
			(pinfunction "VDD")
			(pintype "power_in")
		)
	)
	(footprint "antmicro-footprints:L_WE-MAIA-2512"
		(layer "F.Cu")
		(at 114.475 96.249 180)
		(property "Reference" "L2"
			(at -1.5 -1.4 180)
			(layer "F.SilkS")
			(effects
				(font
					(size 0.7 0.7)
					(thickness 0.15)
				)
				(justify left bottom)
			)
		)
		(property "Value" "784383240047"
			(at 0 2.3 180)
			(layer "F.Fab")
			(effects
				(font
					(size 0.7 0.7)
					(thickness 0.15)
				)
				(justify left bottom)
			)
		)
		(property "Description" "Power Inductor (SMT), AEC-Q200, 470 nH, 3.4 A, Shielded, 6.25 A, WE-MAIA"
			(at 0 0 180)
			(layer "F.Fab")
			(hide yes)
			(effects
				(font
					(size 1.27 1.27)
					(thickness 0.15)
				)
			)
		)
		(property "Author" "Antmicro"
			(at 228.95 192.498 0)
			(layer "F.Fab")
			(hide yes)
			(effects
				(font
					(size 1 1)
					(thickness 0.15)
				)
			)
		)
		(property "IMax" "3.4 A"
			(at 228.95 192.498 0)
			(layer "F.Fab")
			(hide yes)
			(effects
				(font
					(size 1 1)
					(thickness 0.15)
				)
			)
		)
		(property "ISat" "6.25 A"
			(at 228.95 192.498 0)
			(layer "F.Fab")
			(hide yes)
			(effects
				(font
					(size 1 1)
					(thickness 0.15)
				)
			)
		)
		(property "License" "Apache-2.0"
			(at 228.95 192.498 0)
			(layer "F.Fab")
			(hide yes)
			(effects
				(font
					(size 1 1)
					(thickness 0.15)
				)
			)
		)
		(property "MPN" "784383240047"
			(at 228.95 192.498 0)
			(layer "F.Fab")
			(hide yes)
			(effects
				(font
					(size 1 1)
					(thickness 0.15)
				)
			)
		)
		(property "Manufacturer" "Würth Elektronik"
			(at 228.95 192.498 0)
			(layer "F.Fab")
			(hide yes)
			(effects
				(font
					(size 1 1)
					(thickness 0.15)
				)
			)
		)
		(property "Size" "2x2.5"
			(at 228.95 192.498 0)
			(layer "F.Fab")
			(hide yes)
			(effects
				(font
					(size 1 1)
					(thickness 0.15)
				)
			)
		)
		(property "Val" "470n/3.4A"
			(at 228.95 192.498 0)
			(layer "F.Fab")
			(hide yes)
			(effects
				(font
					(size 1 1)
					(thickness 0.15)
				)
			)
		)
		(sheetname "Supply")
		(sheetfile "supply.kicad_sch")
		(attr smd)
		(fp_line
			(start -0.325 1.125)
			(end 0.325 1.125)
			(stroke
				(width 0.15)
				(type solid)
			)
			(layer "F.SilkS")
		)
		(fp_line
			(start -0.325 -1.125)
			(end 0.325 -1.125)
			(stroke
				(width 0.15)
				(type solid)
			)
			(layer "F.SilkS")
		)
		(fp_rect
			(start -1.65 -1.4)
			(end 1.65 1.4)
			(stroke
				(width 0.05)
				(type solid)
			)
			(fill no)
			(layer "F.CrtYd")
		)
		(fp_rect
			(start -1.25 -1)
			(end 1.25 1)
			(stroke
				(width 0.15)
				(type solid)
			)
			(fill no)
			(layer "F.Fab")
		)
		(pad "1" smd roundrect
			(at -0.975 0 180)
			(size 0.85 2.3)
			(layers "F.Cu" "F.Mask" "F.Paste")
			(roundrect_rratio 0.1)
			(net 575 "/Supply/3V3_SW")
			(pintype "passive")
		)
		(pad "2" smd roundrect
			(at 0.975 0 180)
			(size 0.85 2.3)
			(layers "F.Cu" "F.Mask" "F.Paste")
			(roundrect_rratio 0.1)
			(net 576 "/Supply/3V3_REG")
			(pintype "passive")
		)
	)
	(footprint "antmicro-footprints:LED_0603_1608Metric_G"
		(layer "F.Cu")
		(at 137.7825 84.699)
		(descr "LED SMD 0603 Green")
		(tags "LED SMD 0603 Green")
		(property "Reference" "PWR5"
			(at -4.6825 -0.799 0)
			(layer "F.SilkS")
			(effects
				(font
					(size 0.7 0.7)
					(thickness 0.15)
				)
				(justify left bottom)
			)
		)
		(property "Value" "LED_G_0603_KP-1608CGCK"
			(at 0 1.6 0)
			(layer "F.Fab")
			(effects
				(font
					(size 0.7 0.7)
					(thickness 0.15)
				)
				(justify left bottom)
			)
		)
		(property "Author" "Antmicro"
			(at 0 0 0)
			(layer "F.Fab")
			(hide yes)
			(effects
				(font
					(size 1 1)
					(thickness 0.15)
				)
			)
		)
		(property "License" "Apache-2.0"
			(at 0 0 0)
			(layer "F.Fab")
			(hide yes)
			(effects
				(font
					(size 1 1)
					(thickness 0.15)
				)
			)
		)
		(property "MPN" "KP-1608CGCK"
			(at 0 0 0)
			(layer "F.Fab")
			(hide yes)
			(effects
				(font
					(size 1 1)
					(thickness 0.15)
				)
			)
		)
		(property "Manufacturer" "Kingbright"
			(at 0 0 0)
			(layer "F.Fab")
			(hide yes)
			(effects
				(font
					(size 1 1)
					(thickness 0.15)
				)
			)
		)
		(sheetname "Supply")
		(sheetfile "supply.kicad_sch")
		(attr smd)
		(fp_line
			(start -0.27 -0.35)
			(end 0.27 -0.35)
			(stroke
				(width 0.15)
				(type solid)
			)
			(layer "F.SilkS")
		)
		(fp_line
			(start -0.27 0.351)
			(end 0.27 0.351)
			(stroke
				(width 0.15)
				(type solid)
			)
			(layer "F.SilkS")
		)
		(fp_line
			(start -0.106328 -0.200008)
			(end -0.106328 0.199992)
			(stroke
				(width 0.1)
				(type solid)
			)
			(layer "F.SilkS")
		)
		(fp_line
			(start -0.106328 -0.200008)
			(end 0.093672 -8e-06)
			(stroke
				(width 0.1)
				(type solid)
			)
			(layer "F.SilkS")
		)
		(fp_line
			(start -0.106328 -8e-06)
			(end -0.29 0)
			(stroke
				(width 0.1)
				(type solid)
			)
			(layer "F.SilkS")
		)
		(fp_line
			(start 0.093672 -0.200008)
			(end 0.093672 0.199992)
			(stroke
				(width 0.1)
				(type solid)
			)
			(layer "F.SilkS")
		)
		(fp_line
			(start 0.093672 -8e-06)
			(end -0.106328 0.199992)
			(stroke
				(width 0.1)
				(type solid)
			)
			(layer "F.SilkS")
		)
		(fp_line
			(start 0.093672 -8e-06)
			(end 0.293672 -8e-06)
			(stroke
				(width 0.1)
				(type solid)
			)
			(layer "F.SilkS")
		)
		(fp_line
			(start 1.25 0.32)
			(end 1.25 -0.32)
			(stroke
				(width 0.15)
				(type solid)
			)
			(layer "F.SilkS")
		)
		(fp_rect
			(start 1.26 0.65)
			(end -1.26 -0.65)
			(stroke
				(width 0.05)
				(type solid)
			)
			(fill no)
			(layer "F.CrtYd")
		)
		(fp_line
			(start -0.599 0)
			(end -0.201 0)
			(stroke
				(width 0.15)
				(type solid)
			)
			(layer "F.Fab")
		)
		(fp_line
			(start -0.201 -0.2)
			(end -0.201 0)
			(stroke
				(width 0.15)
				(type solid)
			)
			(layer "F.Fab")
		)
		(fp_line
			(start -0.201 0)
			(end -0.201 0.202)
			(stroke
				(width 0.15)
				(type solid)
			)
			(layer "F.Fab")
		)
		(fp_line
			(start -0.201 0.202)
			(end 0.101 0)
			(stroke
				(width 0.15)
				(type solid)
			)
			(layer "F.Fab")
		)
		(fp_line
			(start 0.101 0)
			(end -0.201 -0.2)
			(stroke
				(width 0.15)
				(type solid)
			)
			(layer "F.Fab")
		)
		(fp_line
			(start 0.199 -0.2)
			(end 0.199 -0.1)
			(stroke
				(width 0.15)
				(type solid)
			)
			(layer "F.Fab")
		)
		(fp_line
			(start 0.199 0)
			(end 0.597 0)
			(stroke
				(width 0.15)
				(type solid)
			)
			(layer "F.Fab")
		)
		(fp_line
			(start 0.199 0.202)
			(end 0.199 -0.1)
			(stroke
				(width 0.15)
				(type solid)
			)
			(layer "F.Fab")
		)
		(fp_rect
			(start -0.848 -0.4)
			(end 0.85 0.402)
			(stroke
				(width 0.15)
				(type solid)
			)
			(fill no)
			(layer "F.Fab")
		)
		(pad "1" smd rect
			(at -0.75 0 180)
			(size 0.8 0.8)
			(layers "F.Cu" "F.Mask" "F.Paste")
			(net 459 "3V3_SYS")
			(pinfunction "1")
			(pintype "passive")
		)
		(pad "2" smd rect
			(at 0.75 0 180)
			(size 0.8 0.8)
			(layers "F.Cu" "F.Mask" "F.Paste")
			(net 557 "Net-(PWR5-Pad2)")
			(pinfunction "2")
			(pintype "passive")
		)
	)
	(footprint "antmicro-footprints:C_0402_1005Metric"
		(layer "F.Cu")
		(at 123.4325 96.249 180)
		(descr "Capacitor SMD 0402")
		(tags "capacitor SMD 0402")
		(property "Reference" "C176"
			(at 1.9325 2.449 180)
			(layer "F.SilkS")
			(effects
				(font
					(size 0.7 0.7)
					(thickness 0.15)
				)
				(justify left bottom)
			)
		)
		(property "Value" "C_22u_0402"
			(at 0 1.4 180)
			(layer "F.Fab")
			(effects
				(font
					(size 0.7 0.7)
					(thickness 0.15)
				)
				(justify left bottom)
			)
		)
		(property "Description" " "
			(at 0 0 180)
			(layer "F.Fab")
			(hide yes)
			(effects
				(font
					(size 1.27 1.27)
					(thickness 0.15)
				)
			)
		)
		(property "Author" "Antmicro"
			(at 246.865 192.498 0)
			(layer "F.Fab")
			(hide yes)
			(effects
				(font
					(size 1 1)
					(thickness 0.15)
				)
			)
		)
		(property "Dielectric" ""
			(at 246.865 192.498 0)
			(layer "F.Fab")
			(hide yes)
			(effects
				(font
					(size 1 1)
					(thickness 0.15)
				)
			)
		)
		(property "License" "Apache-2.0"
			(at 246.865 192.498 0)
			(layer "F.Fab")
			(hide yes)
			(effects
				(font
					(size 1 1)
					(thickness 0.15)
				)
			)
		)
		(property "MPN" "04024W226MAT2A"
			(at 246.865 192.498 0)
			(layer "F.Fab")
			(hide yes)
			(effects
				(font
					(size 1 1)
					(thickness 0.15)
				)
			)
		)
		(property "Manufacturer" "AVX"
			(at 246.865 192.498 0)
			(layer "F.Fab")
			(hide yes)
			(effects
				(font
					(size 1 1)
					(thickness 0.15)
				)
			)
		)
		(property "Val" "22u"
			(at 246.865 192.498 0)
			(layer "F.Fab")
			(hide yes)
			(effects
				(font
					(size 1 1)
					(thickness 0.15)
				)
			)
		)
		(property "Voltage" ""
			(at 246.865 192.498 0)
			(layer "F.Fab")
			(hide yes)
			(effects
				(font
					(size 1 1)
					(thickness 0.15)
				)
			)
		)
		(sheetname "Supply")
		(sheetfile "supply.kicad_sch")
		(attr smd)
		(fp_rect
			(start -0.94 -0.47)
			(end 0.94 0.47)
			(stroke
				(width 0.05)
				(type solid)
			)
			(fill no)
			(layer "F.CrtYd")
		)
		(fp_rect
			(start -0.499 -0.249)
			(end 0.499 0.249)
			(stroke
				(width 0.15)
				(type solid)
			)
			(fill no)
			(layer "F.Fab")
		)
		(pad "1" smd roundrect
			(at -0.484 0 180)
			(size 0.59 0.64)
			(layers "F.Cu" "F.Mask" "F.Paste")
			(roundrect_rratio 0.25)
			(net 588 "/Supply/1V0_REG")
			(pintype "passive")
		)
		(pad "2" smd roundrect
			(at 0.484 0 180)
			(size 0.59 0.64)
			(layers "F.Cu" "F.Mask" "F.Paste")
			(roundrect_rratio 0.25)
			(net 5 "GND")
			(pintype "passive")
		)
	)
	(footprint "antmicro-footprints:R_0402_1005Metric"
		(layer "F.Cu")
		(at 118.275 99.549 180)
		(descr "Resistor SMD 0402")
		(tags "resistor SMD 0402")
		(property "Reference" "R119"
			(at 0.875 2.549 180)
			(layer "F.SilkS")
			(effects
				(font
					(size 0.7 0.7)
					(thickness 0.15)
				)
				(justify left bottom)
			)
		)
		(property "Value" "R_0R_0402"
			(at 0 1.4 180)
			(layer "F.Fab")
			(effects
				(font
					(size 0.7 0.7)
					(thickness 0.15)
				)
				(justify left bottom)
			)
		)
		(property "Description" "0R resistor in 0402 package with unspecified tolerance"
			(at 0 0 180)
			(layer "F.Fab")
			(hide yes)
			(effects
				(font
					(size 1.27 1.27)
					(thickness 0.15)
				)
			)
		)
		(property "Author" "Antmicro"
			(at 236.55 199.098 0)
			(layer "F.Fab")
			(hide yes)
			(effects
				(font
					(size 1 1)
					(thickness 0.15)
				)
			)
		)
		(property "Current" "1A"
			(at 236.55 199.098 0)
			(layer "F.Fab")
			(hide yes)
			(effects
				(font
					(size 1 1)
					(thickness 0.15)
				)
			)
		)
		(property "License" "Apache-2.0"
			(at 236.55 199.098 0)
			(layer "F.Fab")
			(hide yes)
			(effects
				(font
					(size 1 1)
					(thickness 0.15)
				)
			)
		)
		(property "MPN" "ERJ2GE0R00X"
			(at 236.55 199.098 0)
			(layer "F.Fab")
			(hide yes)
			(effects
				(font
					(size 1 1)
					(thickness 0.15)
				)
			)
		)
		(property "Manufacturer" "Panasonic"
			(at 236.55 199.098 0)
			(layer "F.Fab")
			(hide yes)
			(effects
				(font
					(size 1 1)
					(thickness 0.15)
				)
			)
		)
		(property "Tolerance" ""
			(at 236.55 199.098 0)
			(layer "F.Fab")
			(hide yes)
			(effects
				(font
					(size 1 1)
					(thickness 0.15)
				)
			)
		)
		(property "Val" "0R"
			(at 236.55 199.098 0)
			(layer "F.Fab")
			(hide yes)
			(effects
				(font
					(size 1 1)
					(thickness 0.15)
				)
			)
		)
		(sheetname "Supply")
		(sheetfile "supply.kicad_sch")
		(attr smd)
		(fp_rect
			(start -0.93 -0.47)
			(end 0.93 0.47)
			(stroke
				(width 0.05)
				(type solid)
			)
			(fill no)
			(layer "F.CrtYd")
		)
		(fp_rect
			(start -0.5 -0.25)
			(end 0.5 0.25)
			(stroke
				(width 0.15)
				(type solid)
			)
			(fill no)
			(layer "F.Fab")
		)
		(pad "1" smd roundrect
			(at -0.485 0 180)
			(size 0.59 0.64)
			(layers "F.Cu" "F.Mask" "F.Paste")
			(roundrect_rratio 0.25)
			(net 609 "/Supply/3V3_VCC_INT")
			(pintype "passive")
		)
		(pad "2" smd roundrect
			(at 0.485 0 180)
			(size 0.59 0.64)
			(layers "F.Cu" "F.Mask" "F.Paste")
			(roundrect_rratio 0.25)
			(net 610 "/Supply/3V3_FSEL")
			(pintype "passive")
		)
	)
	(footprint "antmicro-footprints:R_0402_1005Metric"
		(layer "F.Cu")
		(at 117.697806 88.074 180)
		(descr "Resistor SMD 0402")
		(tags "resistor SMD 0402")
		(property "Reference" "R120"
			(at 0.897806 3.574 180)
			(layer "F.SilkS")
			(effects
				(font
					(size 0.7 0.7)
					(thickness 0.15)
				)
				(justify left bottom)
			)
		)
		(property "Value" "R_0R_0402"
			(at 0 1.4 180)
			(layer "F.Fab")
			(effects
				(font
					(size 0.7 0.7)
					(thickness 0.15)
				)
				(justify left bottom)
			)
		)
		(property "Description" "0R resistor in 0402 package with unspecified tolerance"
			(at 0 0 180)
			(layer "F.Fab")
			(hide yes)
			(effects
				(font
					(size 1.27 1.27)
					(thickness 0.15)
				)
			)
		)
		(property "Author" "Antmicro"
			(at 235.395612 176.148 0)
			(layer "F.Fab")
			(hide yes)
			(effects
				(font
					(size 1 1)
					(thickness 0.15)
				)
			)
		)
		(property "Current" "1A"
			(at 235.395612 176.148 0)
			(layer "F.Fab")
			(hide yes)
			(effects
				(font
					(size 1 1)
					(thickness 0.15)
				)
			)
		)
		(property "License" "Apache-2.0"
			(at 235.395612 176.148 0)
			(layer "F.Fab")
			(hide yes)
			(effects
				(font
					(size 1 1)
					(thickness 0.15)
				)
			)
		)
		(property "MPN" "ERJ2GE0R00X"
			(at 235.395612 176.148 0)
			(layer "F.Fab")
			(hide yes)
			(effects
				(font
					(size 1 1)
					(thickness 0.15)
				)
			)
		)
		(property "Manufacturer" "Panasonic"
			(at 235.395612 176.148 0)
			(layer "F.Fab")
			(hide yes)
			(effects
				(font
					(size 1 1)
					(thickness 0.15)
				)
			)
		)
		(property "Tolerance" ""
			(at 235.395612 176.148 0)
			(layer "F.Fab")
			(hide yes)
			(effects
				(font
					(size 1 1)
					(thickness 0.15)
				)
			)
		)
		(property "Val" "0R"
			(at 235.395612 176.148 0)
			(layer "F.Fab")
			(hide yes)
			(effects
				(font
					(size 1 1)
					(thickness 0.15)
				)
			)
		)
		(sheetname "Supply")
		(sheetfile "supply.kicad_sch")
		(attr smd)
		(fp_rect
			(start -0.93 -0.47)
			(end 0.93 0.47)
			(stroke
				(width 0.05)
				(type solid)
			)
			(fill no)
			(layer "F.CrtYd")
		)
		(fp_rect
			(start -0.5 -0.25)
			(end 0.5 0.25)
			(stroke
				(width 0.15)
				(type solid)
			)
			(fill no)
			(layer "F.Fab")
		)
		(pad "1" smd roundrect
			(at -0.485 0 180)
			(size 0.59 0.64)
			(layers "F.Cu" "F.Mask" "F.Paste")
			(roundrect_rratio 0.25)
			(net 595 "/Supply/1V8_VCC_INT")
			(pintype "passive")
		)
		(pad "2" smd roundrect
			(at 0.485 0 180)
			(size 0.59 0.64)
			(layers "F.Cu" "F.Mask" "F.Paste")
			(roundrect_rratio 0.25)
			(net 614 "/Supply/1V8_FSEL")
			(pintype "passive")
		)
	)
	(footprint "antmicro-footprints:R_0402_1005Metric"
		(layer "F.Cu")
		(at 125.697157 53.213672)
		(descr "Resistor SMD 0402")
		(tags "resistor SMD 0402")
		(property "Reference" "R149"
			(at -1.197157 -1.613672 0)
			(layer "F.SilkS")
			(effects
				(font
					(size 0.7 0.7)
					(thickness 0.15)
				)
				(justify left bottom)
			)
		)
		(property "Value" "R_0R_0402"
			(at 0 1.4 0)
			(layer "F.Fab")
			(effects
				(font
					(size 0.7 0.7)
					(thickness 0.15)
				)
				(justify left bottom)
			)
		)
		(property "Description" "0R resistor in 0402 package with unspecified tolerance"
			(at 0 0 0)
			(layer "F.Fab")
			(hide yes)
			(effects
				(font
					(size 1.27 1.27)
					(thickness 0.15)
				)
			)
		)
		(property "Author" "Antmicro"
			(at 0 0 0)
			(layer "F.Fab")
			(hide yes)
			(effects
				(font
					(size 1 1)
					(thickness 0.15)
				)
			)
		)
		(property "Current" "1A"
			(at 0 0 0)
			(layer "F.Fab")
			(hide yes)
			(effects
				(font
					(size 1 1)
					(thickness 0.15)
				)
			)
		)
		(property "License" "Apache-2.0"
			(at 0 0 0)
			(layer "F.Fab")
			(hide yes)
			(effects
				(font
					(size 1 1)
					(thickness 0.15)
				)
			)
		)
		(property "MPN" "ERJ2GE0R00X"
			(at 0 0 0)
			(layer "F.Fab")
			(hide yes)
			(effects
				(font
					(size 1 1)
					(thickness 0.15)
				)
			)
		)
		(property "Manufacturer" "Panasonic"
			(at 0 0 0)
			(layer "F.Fab")
			(hide yes)
			(effects
				(font
					(size 1 1)
					(thickness 0.15)
				)
			)
		)
		(property "Tolerance" ""
			(at 0 0 0)
			(layer "F.Fab")
			(hide yes)
			(effects
				(font
					(size 1 1)
					(thickness 0.15)
				)
			)
		)
		(property "Val" "0R"
			(at 0 0 0)
			(layer "F.Fab")
			(hide yes)
			(effects
				(font
					(size 1 1)
					(thickness 0.15)
				)
			)
		)
		(sheetname "Supply")
		(sheetfile "supply.kicad_sch")
		(attr exclude_from_pos_files exclude_from_bom dnp)
		(fp_rect
			(start -0.93 -0.47)
			(end 0.93 0.47)
			(stroke
				(width 0.05)
				(type solid)
			)
			(fill no)
			(layer "F.CrtYd")
		)
		(fp_rect
			(start -0.5 -0.25)
			(end 0.5 0.25)
			(stroke
				(width 0.15)
				(type solid)
			)
			(fill no)
			(layer "F.Fab")
		)
		(pad "1" smd roundrect
			(at -0.485 0)
			(size 0.59 0.64)
			(layers "F.Cu" "F.Mask" "F.Paste")
			(roundrect_rratio 0.25)
			(net 631 "/Supply/VDDQ_SNS")
			(pintype "passive")
		)
		(pad "2" smd roundrect
			(at 0.485 0)
			(size 0.59 0.64)
			(layers "F.Cu" "F.Mask" "F.Paste")
			(roundrect_rratio 0.25)
			(net 627 "/Supply/VDDQ_0V6")
			(pintype "passive")
		)
	)
	(footprint "antmicro-footprints:R_0805_2012Metric"
		(layer "F.Cu")
		(at 131.6 50.6)
		(property "Reference" "R98"
			(at -1.1 -1 0)
			(layer "F.SilkS")
			(effects
				(font
					(size 0.7 0.7)
					(thickness 0.15)
				)
				(justify left bottom)
			)
		)
		(property "Value" "R_0R_0805"
			(at 0 1.8 0)
			(layer "F.Fab")
			(effects
				(font
					(size 0.7 0.7)
					(thickness 0.15)
				)
				(justify left bottom)
			)
		)
		(property "Description" "0R resistor in 0805 package with unspecified tolerance"
			(at 0 0 0)
			(layer "F.Fab")
			(hide yes)
			(effects
				(font
					(size 1.27 1.27)
					(thickness 0.15)
				)
			)
		)
		(property "Author" "Antmicro"
			(at 0 0 0)
			(layer "F.Fab")
			(hide yes)
			(effects
				(font
					(size 1 1)
					(thickness 0.15)
				)
			)
		)
		(property "Current" "2.5A"
			(at 0 0 0)
			(layer "F.Fab")
			(hide yes)
			(effects
				(font
					(size 1 1)
					(thickness 0.15)
				)
			)
		)
		(property "License" "Apache-2.0"
			(at 0 0 0)
			(layer "F.Fab")
			(hide yes)
			(effects
				(font
					(size 1 1)
					(thickness 0.15)
				)
			)
		)
		(property "MPN" "CRCW08050000Z0EA"
			(at 0 0 0)
			(layer "F.Fab")
			(hide yes)
			(effects
				(font
					(size 1 1)
					(thickness 0.15)
				)
			)
		)
		(property "Manufacturer" "Vishay"
			(at 0 0 0)
			(layer "F.Fab")
			(hide yes)
			(effects
				(font
					(size 1 1)
					(thickness 0.15)
				)
			)
		)
		(property "Tolerance" ""
			(at 0 0 0)
			(layer "F.Fab")
			(hide yes)
			(effects
				(font
					(size 1 1)
					(thickness 0.15)
				)
			)
		)
		(property "Val" "0R"
			(at 0 0 0)
			(layer "F.Fab")
			(hide yes)
			(effects
				(font
					(size 1 1)
					(thickness 0.15)
				)
			)
		)
		(sheetname "Supply")
		(sheetfile "supply.kicad_sch")
		(attr exclude_from_pos_files exclude_from_bom dnp)
		(fp_line
			(start -0.32 0.699)
			(end 0.28 0.699)
			(stroke
				(width 0.15)
				(type solid)
			)
			(layer "F.SilkS")
		)
		(fp_line
			(start -0.3 -0.701)
			(end 0.298 -0.701)
			(stroke
				(width 0.15)
				(type solid)
			)
			(layer "F.SilkS")
		)
		(fp_rect
			(start -1.75 -0.85)
			(end 1.75 0.85)
			(stroke
				(width 0.05)
				(type solid)
			)
			(fill no)
			(layer "F.CrtYd")
		)
		(fp_line
			(start -0.951 -0.682)
			(end 0.949 -0.682)
			(stroke
				(width 0.15)
				(type solid)
			)
			(layer "F.Fab")
		)
		(fp_line
			(start -0.951 -0.677)
			(end -0.951 0.675)
			(stroke
				(width 0.15)
				(type solid)
			)
			(layer "F.Fab")
		)
		(fp_line
			(start -0.951 0.68)
			(end 0.949 0.68)
			(stroke
				(width 0.15)
				(type solid)
			)
			(layer "F.Fab")
		)
		(fp_line
			(start 0.949 -0.677)
			(end 0.949 0.675)
			(stroke
				(width 0.15)
				(type solid)
			)
			(layer "F.Fab")
		)
		(pad "1" smd roundrect
			(at -1.1 -0.001)
			(size 1 1.4)
			(layers "F.Cu" "F.Mask" "F.Paste")
			(roundrect_rratio 0.15)
			(net 627 "/Supply/VDDQ_0V6")
			(pintype "passive")
		)
		(pad "2" smd roundrect
			(at 1.1 -0.001)
			(size 1 1.4)
			(layers "F.Cu" "F.Mask" "F.Paste")
			(roundrect_rratio 0.15)
			(net 640 "0V6_DDR")
			(pintype "passive")
		)
	)
	(footprint "antmicro-footprints:C_0402_1005Metric"
		(layer "F.Cu")
		(at 123.4325 95.249 180)
		(descr "Capacitor SMD 0402")
		(tags "capacitor SMD 0402")
		(property "Reference" "C181"
			(at 1.9325 2.449 180)
			(layer "F.SilkS")
			(effects
				(font
					(size 0.7 0.7)
					(thickness 0.15)
				)
				(justify left bottom)
			)
		)
		(property "Value" "C_1u_0402"
			(at 0 1.4 180)
			(layer "F.Fab")
			(effects
				(font
					(size 0.7 0.7)
					(thickness 0.15)
				)
				(justify left bottom)
			)
		)
		(property "Description" " "
			(at 0 0 180)
			(layer "F.Fab")
			(hide yes)
			(effects
				(font
					(size 1.27 1.27)
					(thickness 0.15)
				)
			)
		)
		(property "Author" "Antmicro"
			(at 246.865 190.498 0)
			(layer "F.Fab")
			(hide yes)
			(effects
				(font
					(size 1 1)
					(thickness 0.15)
				)
			)
		)
		(property "Dielectric" ""
			(at 246.865 190.498 0)
			(layer "F.Fab")
			(hide yes)
			(effects
				(font
					(size 1 1)
					(thickness 0.15)
				)
			)
		)
		(property "License" "Apache-2.0"
			(at 246.865 190.498 0)
			(layer "F.Fab")
			(hide yes)
			(effects
				(font
					(size 1 1)
					(thickness 0.15)
				)
			)
		)
		(property "MPN" "C1005X6S1A105K050BC"
			(at 246.865 190.498 0)
			(layer "F.Fab")
			(hide yes)
			(effects
				(font
					(size 1 1)
					(thickness 0.15)
				)
			)
		)
		(property "Manufacturer" "TDK"
			(at 246.865 190.498 0)
			(layer "F.Fab")
			(hide yes)
			(effects
				(font
					(size 1 1)
					(thickness 0.15)
				)
			)
		)
		(property "Val" "1u"
			(at 246.865 190.498 0)
			(layer "F.Fab")
			(hide yes)
			(effects
				(font
					(size 1 1)
					(thickness 0.15)
				)
			)
		)
		(property "Voltage" ""
			(at 246.865 190.498 0)
			(layer "F.Fab")
			(hide yes)
			(effects
				(font
					(size 1 1)
					(thickness 0.15)
				)
			)
		)
		(sheetname "Supply")
		(sheetfile "supply.kicad_sch")
		(attr smd)
		(fp_rect
			(start -0.94 -0.47)
			(end 0.94 0.47)
			(stroke
				(width 0.05)
				(type solid)
			)
			(fill no)
			(layer "F.CrtYd")
		)
		(fp_rect
			(start -0.499 -0.249)
			(end 0.499 0.249)
			(stroke
				(width 0.15)
				(type solid)
			)
			(fill no)
			(layer "F.Fab")
		)
		(pad "1" smd roundrect
			(at -0.484 0 180)
			(size 0.59 0.64)
			(layers "F.Cu" "F.Mask" "F.Paste")
			(roundrect_rratio 0.25)
			(net 588 "/Supply/1V0_REG")
			(pintype "passive")
		)
		(pad "2" smd roundrect
			(at 0.484 0 180)
			(size 0.59 0.64)
			(layers "F.Cu" "F.Mask" "F.Paste")
			(roundrect_rratio 0.25)
			(net 5 "GND")
			(pintype "passive")
		)
	)
	(footprint "antmicro-footprints:TP_SMD_1mm"
		(layer "F.Cu")
		(at 144.7 92.599 180)
		(property "Reference" "TP18"
			(at 1.4 9.029098 180)
			(layer "F.SilkS")
			(effects
				(font
					(size 0.7 0.7)
					(thickness 0.15)
				)
				(justify left bottom)
			)
		)
		(property "Value" "TP_1mm_SMD"
			(at 0 1.4 180)
			(layer "F.Fab")
			(effects
				(font
					(size 0.7 0.7)
					(thickness 0.15)
				)
				(justify left bottom)
			)
		)
		(property "Description" "Test Point 1mm"
			(at 0 0 180)
			(layer "F.Fab")
			(hide yes)
			(effects
				(font
					(size 1.27 1.27)
					(thickness 0.15)
				)
			)
		)
		(property "Author" "Antmicro"
			(at 289.4 185.198 0)
			(layer "F.Fab")
			(hide yes)
			(effects
				(font
					(size 1 1)
					(thickness 0.15)
				)
			)
		)
		(property "License" "Apache-2.0"
			(at 289.4 185.198 0)
			(layer "F.Fab")
			(hide yes)
			(effects
				(font
					(size 1 1)
					(thickness 0.15)
				)
			)
		)
		(property "MPN" ""
			(at 289.4 185.198 0)
			(layer "F.Fab")
			(hide yes)
			(effects
				(font
					(size 1 1)
					(thickness 0.15)
				)
			)
		)
		(property "Manufacturer" ""
			(at 289.4 185.198 0)
			(layer "F.Fab")
			(hide yes)
			(effects
				(font
					(size 1 1)
					(thickness 0.15)
				)
			)
		)
		(sheetname "Supply")
		(sheetfile "supply.kicad_sch")
		(attr exclude_from_pos_files)
		(pad "1" smd circle
			(at 0 0 180)
			(size 1 1)
			(layers "F.Cu" "F.Mask")
			(net 460 "1V8_SYS")
			(pinfunction "1")
			(pintype "passive")
		)
	)
	(footprint "antmicro-footprints:R_0402_1005Metric"
		(layer "F.Cu")
		(at 114.9492 109 180)
		(descr "Resistor SMD 0402")
		(tags "resistor SMD 0402")
		(property "Reference" "R110"
			(at -0.7508 -0.4 180)
			(layer "F.SilkS")
			(effects
				(font
					(size 0.7 0.7)
					(thickness 0.15)
				)
				(justify left bottom)
			)
		)
		(property "Value" "R_330R_0402"
			(at 0 1.4 180)
			(layer "F.Fab")
			(effects
				(font
					(size 0.7 0.7)
					(thickness 0.15)
				)
				(justify left bottom)
			)
		)
		(property "Description" "330R resistor in 0402 package with 1% tolerance"
			(at 0 0 180)
			(layer "F.Fab")
			(hide yes)
			(effects
				(font
					(size 1.27 1.27)
					(thickness 0.15)
				)
			)
		)
		(property "Author" "Antmicro"
			(at 229.8984 218 0)
			(layer "F.Fab")
			(hide yes)
			(effects
				(font
					(size 1 1)
					(thickness 0.15)
				)
			)
		)
		(property "License" "Apache-2.0"
			(at 229.8984 218 0)
			(layer "F.Fab")
			(hide yes)
			(effects
				(font
					(size 1 1)
					(thickness 0.15)
				)
			)
		)
		(property "MPN" "CR0402-FX-3300GLF"
			(at 229.8984 218 0)
			(layer "F.Fab")
			(hide yes)
			(effects
				(font
					(size 1 1)
					(thickness 0.15)
				)
			)
		)
		(property "Manufacturer" "Bourns"
			(at 229.8984 218 0)
			(layer "F.Fab")
			(hide yes)
			(effects
				(font
					(size 1 1)
					(thickness 0.15)
				)
			)
		)
		(property "Tolerance" "1%"
			(at 229.8984 218 0)
			(layer "F.Fab")
			(hide yes)
			(effects
				(font
					(size 1 1)
					(thickness 0.15)
				)
			)
		)
		(property "Val" "330R"
			(at 229.8984 218 0)
			(layer "F.Fab")
			(hide yes)
			(effects
				(font
					(size 1 1)
					(thickness 0.15)
				)
			)
		)
		(sheetname "Supply")
		(sheetfile "supply.kicad_sch")
		(attr smd)
		(fp_rect
			(start -0.93 -0.47)
			(end 0.93 0.47)
			(stroke
				(width 0.05)
				(type solid)
			)
			(fill no)
			(layer "F.CrtYd")
		)
		(fp_rect
			(start -0.5 -0.25)
			(end 0.5 0.25)
			(stroke
				(width 0.15)
				(type solid)
			)
			(fill no)
			(layer "F.Fab")
		)
		(pad "1" smd roundrect
			(at -0.485 0 180)
			(size 0.59 0.64)
			(layers "F.Cu" "F.Mask" "F.Paste")
			(roundrect_rratio 0.25)
			(net 632 "Net-(PWR6-Pad2)")
			(pintype "passive")
		)
		(pad "2" smd roundrect
			(at 0.485 0 180)
			(size 0.59 0.64)
			(layers "F.Cu" "F.Mask" "F.Paste")
			(roundrect_rratio 0.25)
			(net 5 "GND")
			(pintype "passive")
		)
	)
	(footprint "antmicro-footprints:C_0402_1005Metric"
		(layer "F.Cu")
		(at 184.1 115.135 90)
		(descr "Capacitor SMD 0402")
		(tags "capacitor SMD 0402")
		(property "Reference" "C155"
			(at -3.665 0.4 270)
			(layer "F.SilkS")
			(effects
				(font
					(size 0.7 0.7)
					(thickness 0.15)
				)
				(justify left bottom)
			)
		)
		(property "Value" "C_10u_0402"
			(at 0 1.4 90)
			(layer "F.Fab")
			(effects
				(font
					(size 0.7 0.7)
					(thickness 0.15)
				)
				(justify left bottom)
			)
		)
		(property "Description" " "
			(at 0 0 90)
			(layer "F.Fab")
			(hide yes)
			(effects
				(font
					(size 1.27 1.27)
					(thickness 0.15)
				)
			)
		)
		(property "Author" "Antmicro"
			(at 299.235 -68.965 0)
			(layer "F.Fab")
			(hide yes)
			(effects
				(font
					(size 1 1)
					(thickness 0.15)
				)
			)
		)
		(property "Dielectric" ""
			(at 299.235 -68.965 0)
			(layer "F.Fab")
			(hide yes)
			(effects
				(font
					(size 1 1)
					(thickness 0.15)
				)
			)
		)
		(property "License" "Apache-2.0"
			(at 299.235 -68.965 0)
			(layer "F.Fab")
			(hide yes)
			(effects
				(font
					(size 1 1)
					(thickness 0.15)
				)
			)
		)
		(property "MPN" "CC0402MRX5R5BB106"
			(at 299.235 -68.965 0)
			(layer "F.Fab")
			(hide yes)
			(effects
				(font
					(size 1 1)
					(thickness 0.15)
				)
			)
		)
		(property "Manufacturer" "Yaego"
			(at 299.235 -68.965 0)
			(layer "F.Fab")
			(hide yes)
			(effects
				(font
					(size 1 1)
					(thickness 0.15)
				)
			)
		)
		(property "Val" "10u"
			(at 299.235 -68.965 0)
			(layer "F.Fab")
			(hide yes)
			(effects
				(font
					(size 1 1)
					(thickness 0.15)
				)
			)
		)
		(property "Voltage" ""
			(at 299.235 -68.965 0)
			(layer "F.Fab")
			(hide yes)
			(effects
				(font
					(size 1 1)
					(thickness 0.15)
				)
			)
		)
		(sheetname "Supply")
		(sheetfile "supply.kicad_sch")
		(attr smd)
		(fp_rect
			(start -0.94 -0.47)
			(end 0.94 0.47)
			(stroke
				(width 0.05)
				(type solid)
			)
			(fill no)
			(layer "F.CrtYd")
		)
		(fp_rect
			(start -0.499 -0.249)
			(end 0.499 0.249)
			(stroke
				(width 0.15)
				(type solid)
			)
			(fill no)
			(layer "F.Fab")
		)
		(pad "1" smd roundrect
			(at -0.484 0 90)
			(size 0.59 0.64)
			(layers "F.Cu" "F.Mask" "F.Paste")
			(roundrect_rratio 0.25)
			(net 463 "VCC5V0_INT")
			(pintype "passive")
		)
		(pad "2" smd roundrect
			(at 0.484 0 90)
			(size 0.59 0.64)
			(layers "F.Cu" "F.Mask" "F.Paste")
			(roundrect_rratio 0.25)
			(net 5 "GND")
			(pintype "passive")
		)
	)
	(footprint "antmicro-footprints:DDR5-testbed"
		(layer "F.Cu")
		(at 150.4 60.09 180)
		(property "Reference" "M1"
			(at -0.65 -0.31 180)
			(layer "F.SilkS")
			(hide yes)
			(effects
				(font
					(size 0.7 0.7)
					(thickness 0.15)
				)
				(justify left bottom)
			)
		)
		(property "Value" "ddr5-testbed"
			(at -3.2 0.4 180)
			(layer "F.Fab")
			(effects
				(font
					(size 0.7 0.7)
					(thickness 0.15)
				)
				(justify left bottom)
			)
		)
		(property "Description" "DDR5 testbed"
			(at 0 0 180)
			(layer "F.Fab")
			(hide yes)
			(effects
				(font
					(size 1.27 1.27)
					(thickness 0.15)
				)
			)
		)
		(property "Author" "Antmicro"
			(at 300.8 120.18 0)
			(layer "F.Fab")
			(hide yes)
			(effects
				(font
					(size 1 1)
					(thickness 0.15)
				)
			)
		)
		(property "License" "Apache-2.0"
			(at 300.8 120.18 0)
			(layer "F.Fab")
			(hide yes)
			(effects
				(font
					(size 1 1)
					(thickness 0.15)
				)
			)
		)
		(property "MPN" ""
			(at 300.8 120.18 0)
			(layer "F.Fab")
			(hide yes)
			(effects
				(font
					(size 1 1)
					(thickness 0.15)
				)
			)
		)
		(property "Manufacturer" "Antmicro "
			(at 300.8 120.18 0)
			(layer "F.Fab")
			(hide yes)
			(effects
				(font
					(size 1 1)
					(thickness 0.15)
				)
			)
		)
		(sheetname "SO-DIMM")
		(sheetfile "sodimm.kicad_sch")
		(attr exclude_from_pos_files exclude_from_bom dnp)
		(fp_rect
			(start -35 -15.151)
			(end 34.999 15.349)
			(stroke
				(width 0.15)
				(type solid)
			)
			(fill no)
			(layer "F.Fab")
		)
	)
	(footprint "antmicro-footprints:R_0402_1005Metric"
		(layer "F.Cu")
		(at 123.6475 101.449 180)
		(descr "Resistor SMD 0402")
		(tags "resistor SMD 0402")
		(property "Reference" "R143"
			(at 3.5475 -0.351 180)
			(layer "F.SilkS")
			(effects
				(font
					(size 0.7 0.7)
					(thickness 0.15)
				)
				(justify left bottom)
			)
		)
		(property "Value" "R_10k_0402"
			(at 0 1.4 180)
			(layer "F.Fab")
			(effects
				(font
					(size 0.7 0.7)
					(thickness 0.15)
				)
				(justify left bottom)
			)
		)
		(property "Description" "10k resistor in 0402 package with 1% tolerance"
			(at 0 0 180)
			(layer "F.Fab")
			(hide yes)
			(effects
				(font
					(size 1.27 1.27)
					(thickness 0.15)
				)
			)
		)
		(property "Author" "Antmicro"
			(at 247.295 202.898 0)
			(layer "F.Fab")
			(hide yes)
			(effects
				(font
					(size 1 1)
					(thickness 0.15)
				)
			)
		)
		(property "License" "Apache-2.0"
			(at 247.295 202.898 0)
			(layer "F.Fab")
			(hide yes)
			(effects
				(font
					(size 1 1)
					(thickness 0.15)
				)
			)
		)
		(property "MPN" "CR0402-FX-1002GLF"
			(at 247.295 202.898 0)
			(layer "F.Fab")
			(hide yes)
			(effects
				(font
					(size 1 1)
					(thickness 0.15)
				)
			)
		)
		(property "Manufacturer" "Bourns"
			(at 247.295 202.898 0)
			(layer "F.Fab")
			(hide yes)
			(effects
				(font
					(size 1 1)
					(thickness 0.15)
				)
			)
		)
		(property "Tolerance" "1%"
			(at 247.295 202.898 0)
			(layer "F.Fab")
			(hide yes)
			(effects
				(font
					(size 1 1)
					(thickness 0.15)
				)
			)
		)
		(property "Val" "10k"
			(at 247.295 202.898 0)
			(layer "F.Fab")
			(hide yes)
			(effects
				(font
					(size 1 1)
					(thickness 0.15)
				)
			)
		)
		(sheetname "Supply")
		(sheetfile "supply.kicad_sch")
		(attr smd)
		(fp_rect
			(start -0.93 -0.47)
			(end 0.93 0.47)
			(stroke
				(width 0.05)
				(type solid)
			)
			(fill no)
			(layer "F.CrtYd")
		)
		(fp_rect
			(start -0.5 -0.25)
			(end 0.5 0.25)
			(stroke
				(width 0.15)
				(type solid)
			)
			(fill no)
			(layer "F.Fab")
		)
		(pad "1" smd roundrect
			(at -0.485 0 180)
			(size 0.59 0.64)
			(layers "F.Cu" "F.Mask" "F.Paste")
			(roundrect_rratio 0.25)
			(net 599 "/Supply/1V0_FB")
			(pintype "passive")
		)
		(pad "2" smd roundrect
			(at 0.485 0 180)
			(size 0.59 0.64)
			(layers "F.Cu" "F.Mask" "F.Paste")
			(roundrect_rratio 0.25)
			(net 5 "GND")
			(pintype "passive")
		)
	)
	(footprint "antmicro-footprints:TP_SMD_1mm"
		(layer "F.Cu")
		(at 171.1 112.1508)
		(property "Reference" "TP7"
			(at -2.5 0.4492 0)
			(layer "F.SilkS")
			(effects
				(font
					(size 0.7 0.7)
					(thickness 0.15)
				)
				(justify left bottom)
			)
		)
		(property "Value" "TP_1mm_SMD"
			(at 0 1.4 0)
			(layer "F.Fab")
			(effects
				(font
					(size 0.7 0.7)
					(thickness 0.15)
				)
				(justify left bottom)
			)
		)
		(property "Description" "Test Point 1mm"
			(at 0 0 0)
			(layer "F.Fab")
			(hide yes)
			(effects
				(font
					(size 1.27 1.27)
					(thickness 0.15)
				)
			)
		)
		(property "Author" "Antmicro"
			(at 0 0 0)
			(layer "F.Fab")
			(hide yes)
			(effects
				(font
					(size 1 1)
					(thickness 0.15)
				)
			)
		)
		(property "License" "Apache-2.0"
			(at 0 0 0)
			(layer "F.Fab")
			(hide yes)
			(effects
				(font
					(size 1 1)
					(thickness 0.15)
				)
			)
		)
		(property "MPN" ""
			(at 0 0 0)
			(layer "F.Fab")
			(hide yes)
			(effects
				(font
					(size 1 1)
					(thickness 0.15)
				)
			)
		)
		(property "Manufacturer" ""
			(at 0 0 0)
			(layer "F.Fab")
			(hide yes)
			(effects
				(font
					(size 1 1)
					(thickness 0.15)
				)
			)
		)
		(sheetname "Config SPI flash")
		(sheetfile "config-spi.kicad_sch")
		(attr exclude_from_pos_files)
		(pad "1" smd circle
			(at 0 0)
			(size 1 1)
			(layers "F.Cu" "F.Mask")
			(net 95 "PUDC_B")
			(pinfunction "1")
			(pintype "passive")
		)
	)
	(footprint "antmicro-footprints:C_0603_1608Metric"
		(layer "F.Cu")
		(at 125.3 61.475 180)
		(descr "Capacitor SMD 0603")
		(tags "capacitor 0603")
		(property "Reference" "C182"
			(at 3.9 -0.35 180)
			(layer "F.SilkS")
			(effects
				(font
					(size 0.7 0.7)
					(thickness 0.15)
				)
				(justify left bottom)
			)
		)
		(property "Value" "C_10u_0603"
			(at 0 1.6 180)
			(layer "F.Fab")
			(effects
				(font
					(size 0.7 0.7)
					(thickness 0.15)
				)
				(justify left bottom)
			)
		)
		(property "Description" " "
			(at 0 0 180)
			(layer "F.Fab")
			(hide yes)
			(effects
				(font
					(size 1.27 1.27)
					(thickness 0.15)
				)
			)
		)
		(property "Author" "Antmicro"
			(at 250.6 122.95 0)
			(layer "F.Fab")
			(hide yes)
			(effects
				(font
					(size 1 1)
					(thickness 0.15)
				)
			)
		)
		(property "License" "Apache-2.0"
			(at 250.6 122.95 0)
			(layer "F.Fab")
			(hide yes)
			(effects
				(font
					(size 1 1)
					(thickness 0.15)
				)
			)
		)
		(property "MPN" "GRM188R61A106KE69D"
			(at 250.6 122.95 0)
			(layer "F.Fab")
			(hide yes)
			(effects
				(font
					(size 1 1)
					(thickness 0.15)
				)
			)
		)
		(property "Manufacturer" "Murata"
			(at 250.6 122.95 0)
			(layer "F.Fab")
			(hide yes)
			(effects
				(font
					(size 1 1)
					(thickness 0.15)
				)
			)
		)
		(property "Val" "10u"
			(at 250.6 122.95 0)
			(layer "F.Fab")
			(hide yes)
			(effects
				(font
					(size 1 1)
					(thickness 0.15)
				)
			)
		)
		(property "Voltage" ""
			(at 250.6 122.95 0)
			(layer "F.Fab")
			(hide yes)
			(effects
				(font
					(size 1 1)
					(thickness 0.15)
				)
			)
		)
		(sheetname "Supply")
		(sheetfile "supply.kicad_sch")
		(attr exclude_from_pos_files exclude_from_bom dnp)
		(fp_line
			(start -0.3 0.3)
			(end 0.3 0.3)
			(stroke
				(width 0.15)
				(type solid)
			)
			(layer "F.SilkS")
		)
		(fp_line
			(start -0.3 -0.3)
			(end 0.3 -0.3)
			(stroke
				(width 0.15)
				(type solid)
			)
			(layer "F.SilkS")
		)
		(fp_rect
			(start -1.24 -0.7)
			(end 1.24 0.7)
			(stroke
				(width 0.05)
				(type solid)
			)
			(fill no)
			(layer "F.CrtYd")
		)
		(fp_rect
			(start -0.8 -0.4)
			(end 0.8 0.4)
			(stroke
				(width 0.15)
				(type solid)
			)
			(fill no)
			(layer "F.Fab")
		)
		(pad "1" smd roundrect
			(at -0.7 0 180)
			(size 0.6 0.8)
			(layers "F.Cu" "F.Mask" "F.Paste")
			(roundrect_rratio 0.2)
			(net 463 "VCC5V0_INT")
			(pintype "passive")
		)
		(pad "2" smd roundrect
			(at 0.7 0 180)
			(size 0.6 0.8)
			(layers "F.Cu" "F.Mask" "F.Paste")
			(roundrect_rratio 0.2)
			(net 5 "GND")
			(pintype "passive")
		)
	)
	(footprint "antmicro-footprints:R_0402_1005Metric"
		(layer "F.Cu")
		(at 109.2492 115.7)
		(descr "Resistor SMD 0402")
		(tags "resistor SMD 0402")
		(property "Reference" "R166"
			(at -1.9492 -0.5 0)
			(layer "F.SilkS")
			(effects
				(font
					(size 0.7 0.7)
					(thickness 0.15)
				)
				(justify left bottom)
			)
		)
		(property "Value" "R_243k_0402"
			(at 0 1.4 0)
			(layer "F.Fab")
			(effects
				(font
					(size 0.7 0.7)
					(thickness 0.15)
				)
				(justify left bottom)
			)
		)
		(property "Description" "243k resistor in 0402 package with 1% tolerance"
			(at 0 0 0)
			(layer "F.Fab")
			(hide yes)
			(effects
				(font
					(size 1.27 1.27)
					(thickness 0.15)
				)
			)
		)
		(property "Author" "Antmicro"
			(at 0 0 0)
			(layer "F.Fab")
			(hide yes)
			(effects
				(font
					(size 1 1)
					(thickness 0.15)
				)
			)
		)
		(property "License" "Apache-2.0"
			(at 0 0 0)
			(layer "F.Fab")
			(hide yes)
			(effects
				(font
					(size 1 1)
					(thickness 0.15)
				)
			)
		)
		(property "MPN" "CR0402-FX-2433GLF"
			(at 0 0 0)
			(layer "F.Fab")
			(hide yes)
			(effects
				(font
					(size 1 1)
					(thickness 0.15)
				)
			)
		)
		(property "Manufacturer" "Bourns"
			(at 0 0 0)
			(layer "F.Fab")
			(hide yes)
			(effects
				(font
					(size 1 1)
					(thickness 0.15)
				)
			)
		)
		(property "Tolerance" "1%"
			(at 0 0 0)
			(layer "F.Fab")
			(hide yes)
			(effects
				(font
					(size 1 1)
					(thickness 0.15)
				)
			)
		)
		(property "Val" "243k"
			(at 0 0 0)
			(layer "F.Fab")
			(hide yes)
			(effects
				(font
					(size 1 1)
					(thickness 0.15)
				)
			)
		)
		(sheetname "Supply")
		(sheetfile "supply.kicad_sch")
		(attr smd)
		(fp_rect
			(start -0.93 -0.47)
			(end 0.93 0.47)
			(stroke
				(width 0.05)
				(type solid)
			)
			(fill no)
			(layer "F.CrtYd")
		)
		(fp_rect
			(start -0.5 -0.25)
			(end 0.5 0.25)
			(stroke
				(width 0.15)
				(type solid)
			)
			(fill no)
			(layer "F.Fab")
		)
		(pad "1" smd roundrect
			(at -0.485 0)
			(size 0.59 0.64)
			(layers "F.Cu" "F.Mask" "F.Paste")
			(roundrect_rratio 0.25)
			(net 224 "VIN")
			(pintype "passive")
		)
		(pad "2" smd roundrect
			(at 0.485 0)
			(size 0.59 0.64)
			(layers "F.Cu" "F.Mask" "F.Paste")
			(roundrect_rratio 0.25)
			(net 514 "/Supply/SYS_EN")
			(pintype "passive")
		)
	)
	(footprint "antmicro-footprints:C_0402_1005Metric"
		(layer "F.Cu")
		(at 123.14 83.724 180)
		(descr "Capacitor SMD 0402")
		(tags "capacitor SMD 0402")
		(property "Reference" "C179"
			(at 1.94 2.524 180)
			(layer "F.SilkS")
			(effects
				(font
					(size 0.7 0.7)
					(thickness 0.15)
				)
				(justify left bottom)
			)
		)
		(property "Value" "C_1u_0402"
			(at 0 1.4 180)
			(layer "F.Fab")
			(effects
				(font
					(size 0.7 0.7)
					(thickness 0.15)
				)
				(justify left bottom)
			)
		)
		(property "Description" " "
			(at 0 0 180)
			(layer "F.Fab")
			(hide yes)
			(effects
				(font
					(size 1.27 1.27)
					(thickness 0.15)
				)
			)
		)
		(property "Author" "Antmicro"
			(at 246.28 167.448 0)
			(layer "F.Fab")
			(hide yes)
			(effects
				(font
					(size 1 1)
					(thickness 0.15)
				)
			)
		)
		(property "Dielectric" ""
			(at 246.28 167.448 0)
			(layer "F.Fab")
			(hide yes)
			(effects
				(font
					(size 1 1)
					(thickness 0.15)
				)
			)
		)
		(property "License" "Apache-2.0"
			(at 246.28 167.448 0)
			(layer "F.Fab")
			(hide yes)
			(effects
				(font
					(size 1 1)
					(thickness 0.15)
				)
			)
		)
		(property "MPN" "C1005X6S1A105K050BC"
			(at 246.28 167.448 0)
			(layer "F.Fab")
			(hide yes)
			(effects
				(font
					(size 1 1)
					(thickness 0.15)
				)
			)
		)
		(property "Manufacturer" "TDK"
			(at 246.28 167.448 0)
			(layer "F.Fab")
			(hide yes)
			(effects
				(font
					(size 1 1)
					(thickness 0.15)
				)
			)
		)
		(property "Val" "1u"
			(at 246.28 167.448 0)
			(layer "F.Fab")
			(hide yes)
			(effects
				(font
					(size 1 1)
					(thickness 0.15)
				)
			)
		)
		(property "Voltage" ""
			(at 246.28 167.448 0)
			(layer "F.Fab")
			(hide yes)
			(effects
				(font
					(size 1 1)
					(thickness 0.15)
				)
			)
		)
		(sheetname "Supply")
		(sheetfile "supply.kicad_sch")
		(attr smd)
		(fp_rect
			(start -0.94 -0.47)
			(end 0.94 0.47)
			(stroke
				(width 0.05)
				(type solid)
			)
			(fill no)
			(layer "F.CrtYd")
		)
		(fp_rect
			(start -0.499 -0.249)
			(end 0.499 0.249)
			(stroke
				(width 0.15)
				(type solid)
			)
			(fill no)
			(layer "F.Fab")
		)
		(pad "1" smd roundrect
			(at -0.484 0 180)
			(size 0.59 0.64)
			(layers "F.Cu" "F.Mask" "F.Paste")
			(roundrect_rratio 0.25)
			(net 587 "/Supply/1V1_REG")
			(pintype "passive")
		)
		(pad "2" smd roundrect
			(at 0.484 0 180)
			(size 0.59 0.64)
			(layers "F.Cu" "F.Mask" "F.Paste")
			(roundrect_rratio 0.25)
			(net 5 "GND")
			(pintype "passive")
		)
	)
	(footprint "antmicro-footprints:C_0402_1005Metric"
		(layer "F.Cu")
		(at 123.6475 99.449 180)
		(descr "Capacitor SMD 0402")
		(tags "capacitor SMD 0402")
		(property "Reference" "C166"
			(at 3.5475 -0.351 180)
			(layer "F.SilkS")
			(effects
				(font
					(size 0.7 0.7)
					(thickness 0.15)
				)
				(justify left bottom)
			)
		)
		(property "Value" "C_1u_0402"
			(at 0 1.4 180)
			(layer "F.Fab")
			(effects
				(font
					(size 0.7 0.7)
					(thickness 0.15)
				)
				(justify left bottom)
			)
		)
		(property "Description" " "
			(at 0 0 180)
			(layer "F.Fab")
			(hide yes)
			(effects
				(font
					(size 1.27 1.27)
					(thickness 0.15)
				)
			)
		)
		(property "Author" "Antmicro"
			(at 247.295 198.898 0)
			(layer "F.Fab")
			(hide yes)
			(effects
				(font
					(size 1 1)
					(thickness 0.15)
				)
			)
		)
		(property "Dielectric" ""
			(at 247.295 198.898 0)
			(layer "F.Fab")
			(hide yes)
			(effects
				(font
					(size 1 1)
					(thickness 0.15)
				)
			)
		)
		(property "License" "Apache-2.0"
			(at 247.295 198.898 0)
			(layer "F.Fab")
			(hide yes)
			(effects
				(font
					(size 1 1)
					(thickness 0.15)
				)
			)
		)
		(property "MPN" "C1005X6S1A105K050BC"
			(at 247.295 198.898 0)
			(layer "F.Fab")
			(hide yes)
			(effects
				(font
					(size 1 1)
					(thickness 0.15)
				)
			)
		)
		(property "Manufacturer" "TDK"
			(at 247.295 198.898 0)
			(layer "F.Fab")
			(hide yes)
			(effects
				(font
					(size 1 1)
					(thickness 0.15)
				)
			)
		)
		(property "Val" "1u"
			(at 247.295 198.898 0)
			(layer "F.Fab")
			(hide yes)
			(effects
				(font
					(size 1 1)
					(thickness 0.15)
				)
			)
		)
		(property "Voltage" ""
			(at 247.295 198.898 0)
			(layer "F.Fab")
			(hide yes)
			(effects
				(font
					(size 1 1)
					(thickness 0.15)
				)
			)
		)
		(sheetname "Supply")
		(sheetfile "supply.kicad_sch")
		(attr smd)
		(fp_rect
			(start -0.94 -0.47)
			(end 0.94 0.47)
			(stroke
				(width 0.05)
				(type solid)
			)
			(fill no)
			(layer "F.CrtYd")
		)
		(fp_rect
			(start -0.499 -0.249)
			(end 0.499 0.249)
			(stroke
				(width 0.15)
				(type solid)
			)
			(fill no)
			(layer "F.Fab")
		)
		(pad "1" smd roundrect
			(at -0.484 0 180)
			(size 0.59 0.64)
			(layers "F.Cu" "F.Mask" "F.Paste")
			(roundrect_rratio 0.25)
			(net 593 "/Supply/1V0_VCC_INT")
			(pintype "passive")
		)
		(pad "2" smd roundrect
			(at 0.484 0 180)
			(size 0.59 0.64)
			(layers "F.Cu" "F.Mask" "F.Paste")
			(roundrect_rratio 0.25)
			(net 5 "GND")
			(pintype "passive")
		)
	)
	(footprint "antmicro-footprints:C_0402_1005Metric"
		(layer "F.Cu")
		(at 115.397806 86.824)
		(descr "Capacitor SMD 0402")
		(tags "capacitor SMD 0402")
		(property "Reference" "C158"
			(at -3.597806 0.376 0)
			(layer "F.SilkS")
			(effects
				(font
					(size 0.7 0.7)
					(thickness 0.15)
				)
				(justify left bottom)
			)
		)
		(property "Value" "C_100n_6V3_0402"
			(at 0 1.4 0)
			(layer "F.Fab")
			(effects
				(font
					(size 0.7 0.7)
					(thickness 0.15)
				)
				(justify left bottom)
			)
		)
		(property "Description" " "
			(at 0 0 0)
			(layer "F.Fab")
			(hide yes)
			(effects
				(font
					(size 1.27 1.27)
					(thickness 0.15)
				)
			)
		)
		(property "Author" "Antmicro"
			(at 0 0 0)
			(layer "F.Fab")
			(hide yes)
			(effects
				(font
					(size 1 1)
					(thickness 0.15)
				)
			)
		)
		(property "Dielectric" ""
			(at 0 0 0)
			(layer "F.Fab")
			(hide yes)
			(effects
				(font
					(size 1 1)
					(thickness 0.15)
				)
			)
		)
		(property "License" "Apache-2.0"
			(at 0 0 0)
			(layer "F.Fab")
			(hide yes)
			(effects
				(font
					(size 1 1)
					(thickness 0.15)
				)
			)
		)
		(property "MPN" "0402X104K6R3CT"
			(at 0 0 0)
			(layer "F.Fab")
			(hide yes)
			(effects
				(font
					(size 1 1)
					(thickness 0.15)
				)
			)
		)
		(property "Manufacturer" "Walsin"
			(at 0 0 0)
			(layer "F.Fab")
			(hide yes)
			(effects
				(font
					(size 1 1)
					(thickness 0.15)
				)
			)
		)
		(property "Val" "100n"
			(at 0 0 0)
			(layer "F.Fab")
			(hide yes)
			(effects
				(font
					(size 1 1)
					(thickness 0.15)
				)
			)
		)
		(property "Voltage" ""
			(at 0 0 0)
			(layer "F.Fab")
			(hide yes)
			(effects
				(font
					(size 1 1)
					(thickness 0.15)
				)
			)
		)
		(sheetname "Supply")
		(sheetfile "supply.kicad_sch")
		(attr smd)
		(fp_rect
			(start -0.94 -0.47)
			(end 0.94 0.47)
			(stroke
				(width 0.05)
				(type solid)
			)
			(fill no)
			(layer "F.CrtYd")
		)
		(fp_rect
			(start -0.499 -0.249)
			(end 0.499 0.249)
			(stroke
				(width 0.15)
				(type solid)
			)
			(fill no)
			(layer "F.Fab")
		)
		(pad "1" smd roundrect
			(at -0.484 0)
			(size 0.59 0.64)
			(layers "F.Cu" "F.Mask" "F.Paste")
			(roundrect_rratio 0.25)
			(net 584 "/Supply/1V8_SW")
			(pintype "passive")
		)
		(pad "2" smd roundrect
			(at 0.484 0)
			(size 0.59 0.64)
			(layers "F.Cu" "F.Mask" "F.Paste")
			(roundrect_rratio 0.25)
			(net 552 "/Supply/1V8_BST")
			(pintype "passive")
		)
	)
	(footprint "antmicro-footprints:C_0402_1005Metric"
		(layer "F.Cu")
		(at 187.1 111.85 90)
		(descr "Capacitor SMD 0402")
		(tags "capacitor SMD 0402")
		(property "Reference" "C165"
			(at 0.751 0.4 90)
			(layer "F.SilkS")
			(effects
				(font
					(size 0.7 0.7)
					(thickness 0.15)
				)
				(justify left bottom)
			)
		)
		(property "Value" "C_1u_0402"
			(at 0 1.4 90)
			(layer "F.Fab")
			(effects
				(font
					(size 0.7 0.7)
					(thickness 0.15)
				)
				(justify left bottom)
			)
		)
		(property "Description" " "
			(at 0 0 90)
			(layer "F.Fab")
			(hide yes)
			(effects
				(font
					(size 1.27 1.27)
					(thickness 0.15)
				)
			)
		)
		(property "Author" "Antmicro"
			(at 298.95 -75.25 0)
			(layer "F.Fab")
			(hide yes)
			(effects
				(font
					(size 1 1)
					(thickness 0.15)
				)
			)
		)
		(property "Dielectric" ""
			(at 298.95 -75.25 0)
			(layer "F.Fab")
			(hide yes)
			(effects
				(font
					(size 1 1)
					(thickness 0.15)
				)
			)
		)
		(property "License" "Apache-2.0"
			(at 298.95 -75.25 0)
			(layer "F.Fab")
			(hide yes)
			(effects
				(font
					(size 1 1)
					(thickness 0.15)
				)
			)
		)
		(property "MPN" "C1005X6S1A105K050BC"
			(at 298.95 -75.25 0)
			(layer "F.Fab")
			(hide yes)
			(effects
				(font
					(size 1 1)
					(thickness 0.15)
				)
			)
		)
		(property "Manufacturer" "TDK"
			(at 298.95 -75.25 0)
			(layer "F.Fab")
			(hide yes)
			(effects
				(font
					(size 1 1)
					(thickness 0.15)
				)
			)
		)
		(property "Val" "1u"
			(at 298.95 -75.25 0)
			(layer "F.Fab")
			(hide yes)
			(effects
				(font
					(size 1 1)
					(thickness 0.15)
				)
			)
		)
		(property "Voltage" ""
			(at 298.95 -75.25 0)
			(layer "F.Fab")
			(hide yes)
			(effects
				(font
					(size 1 1)
					(thickness 0.15)
				)
			)
		)
		(sheetname "Supply")
		(sheetfile "supply.kicad_sch")
		(attr smd)
		(fp_rect
			(start -0.94 -0.47)
			(end 0.94 0.47)
			(stroke
				(width 0.05)
				(type solid)
			)
			(fill no)
			(layer "F.CrtYd")
		)
		(fp_rect
			(start -0.499 -0.249)
			(end 0.499 0.249)
			(stroke
				(width 0.15)
				(type solid)
			)
			(fill no)
			(layer "F.Fab")
		)
		(pad "1" smd roundrect
			(at -0.484 0 90)
			(size 0.59 0.64)
			(layers "F.Cu" "F.Mask" "F.Paste")
			(roundrect_rratio 0.25)
			(net 597 "/Supply/1V2_VCC_INT")
			(pintype "passive")
		)
		(pad "2" smd roundrect
			(at 0.484 0 90)
			(size 0.59 0.64)
			(layers "F.Cu" "F.Mask" "F.Paste")
			(roundrect_rratio 0.25)
			(net 5 "GND")
			(pintype "passive")
		)
	)
	(footprint "antmicro-footprints:R_0402_1005Metric"
		(layer "F.Cu")
		(at 118.275 101.549 180)
		(descr "Resistor SMD 0402")
		(tags "resistor SMD 0402")
		(property "Reference" "R114"
			(at 0.875 2.549 180)
			(layer "F.SilkS")
			(effects
				(font
					(size 0.7 0.7)
					(thickness 0.15)
				)
				(justify left bottom)
			)
		)
		(property "Value" "R_100k_0402"
			(at 0 1.4 180)
			(layer "F.Fab")
			(effects
				(font
					(size 0.7 0.7)
					(thickness 0.15)
				)
				(justify left bottom)
			)
		)
		(property "Description" "100k resistor in 0402 package with 1% tolerance"
			(at 0 0 180)
			(layer "F.Fab")
			(hide yes)
			(effects
				(font
					(size 1.27 1.27)
					(thickness 0.15)
				)
			)
		)
		(property "Author" "Antmicro"
			(at 236.55 203.098 0)
			(layer "F.Fab")
			(hide yes)
			(effects
				(font
					(size 1 1)
					(thickness 0.15)
				)
			)
		)
		(property "License" "Apache-2.0"
			(at 236.55 203.098 0)
			(layer "F.Fab")
			(hide yes)
			(effects
				(font
					(size 1 1)
					(thickness 0.15)
				)
			)
		)
		(property "MPN" "CR0402-FX-1003GLF"
			(at 236.55 203.098 0)
			(layer "F.Fab")
			(hide yes)
			(effects
				(font
					(size 1 1)
					(thickness 0.15)
				)
			)
		)
		(property "Manufacturer" "Bourns"
			(at 236.55 203.098 0)
			(layer "F.Fab")
			(hide yes)
			(effects
				(font
					(size 1 1)
					(thickness 0.15)
				)
			)
		)
		(property "Tolerance" "1%"
			(at 236.55 203.098 0)
			(layer "F.Fab")
			(hide yes)
			(effects
				(font
					(size 1 1)
					(thickness 0.15)
				)
			)
		)
		(property "Val" "100k"
			(at 236.55 203.098 0)
			(layer "F.Fab")
			(hide yes)
			(effects
				(font
					(size 1 1)
					(thickness 0.15)
				)
			)
		)
		(sheetname "Supply")
		(sheetfile "supply.kicad_sch")
		(attr smd)
		(fp_rect
			(start -0.93 -0.47)
			(end 0.93 0.47)
			(stroke
				(width 0.05)
				(type solid)
			)
			(fill no)
			(layer "F.CrtYd")
		)
		(fp_rect
			(start -0.5 -0.25)
			(end 0.5 0.25)
			(stroke
				(width 0.15)
				(type solid)
			)
			(fill no)
			(layer "F.Fab")
		)
		(pad "1" smd roundrect
			(at -0.485 0 180)
			(size 0.59 0.64)
			(layers "F.Cu" "F.Mask" "F.Paste")
			(roundrect_rratio 0.25)
			(net 470 "/Supply/VCC_IO_EN")
			(pintype "passive")
		)
		(pad "2" smd roundrect
			(at 0.485 0 180)
			(size 0.59 0.64)
			(layers "F.Cu" "F.Mask" "F.Paste")
			(roundrect_rratio 0.25)
			(net 577 "/Supply/3V3_EN")
			(pintype "passive")
		)
	)
	(footprint "antmicro-footprints:SOT-523"
		(layer "F.Cu")
		(at 142.3825 84.699 90)
		(property "Reference" "Q11"
			(at 0.599 -2.5825 0)
			(layer "F.SilkS")
			(effects
				(font
					(size 0.7 0.7)
					(thickness 0.15)
				)
				(justify left bottom)
			)
		)
		(property "Value" "DMG1012T-7"
			(at 0.1 1.824 90)
			(layer "F.Fab")
			(effects
				(font
					(size 0.7 0.7)
					(thickness 0.15)
				)
				(justify left bottom)
			)
		)
		(property "Author" "Antmicro"
			(at 227.0815 -57.6835 0)
			(layer "F.Fab")
			(hide yes)
			(effects
				(font
					(size 1 1)
					(thickness 0.15)
				)
			)
		)
		(property "License" "Apache-2.0"
			(at 227.0815 -57.6835 0)
			(layer "F.Fab")
			(hide yes)
			(effects
				(font
					(size 1 1)
					(thickness 0.15)
				)
			)
		)
		(property "MPN" "DMG1012T-7"
			(at 227.0815 -57.6835 0)
			(layer "F.Fab")
			(hide yes)
			(effects
				(font
					(size 1 1)
					(thickness 0.15)
				)
			)
		)
		(property "Manufacturer" "Diodes Incorporated"
			(at 227.0815 -57.6835 0)
			(layer "F.Fab")
			(hide yes)
			(effects
				(font
					(size 1 1)
					(thickness 0.15)
				)
			)
		)
		(sheetname "Supply")
		(sheetfile "supply.kicad_sch")
		(attr smd)
		(fp_line
			(start -0.277 -0.551)
			(end -0.277 -0.75)
			(stroke
				(width 0.15)
				(type solid)
			)
			(layer "F.SilkS")
		)
		(fp_line
			(start -0.725 -0.551)
			(end -0.277 -0.551)
			(stroke
				(width 0.15)
				(type solid)
			)
			(layer "F.SilkS")
		)
		(fp_line
			(start -0.927 -0.351)
			(end -0.725 -0.551)
			(stroke
				(width 0.15)
				(type solid)
			)
			(layer "F.SilkS")
		)
		(fp_line
			(start -0.927 -0.051)
			(end -0.927 -0.351)
			(stroke
				(width 0.15)
				(type solid)
			)
			(layer "F.SilkS")
		)
		(fp_circle
			(center -0.9652 0.9652)
			(end -0.9152 0.9652)
			(stroke
				(width 0.15)
				(type solid)
			)
			(fill yes)
			(layer "F.SilkS")
		)
		(fp_line
			(start 1.1 -1.16)
			(end 1.1 1.15)
			(stroke
				(width 0.05)
				(type solid)
			)
			(layer "F.CrtYd")
		)
		(fp_line
			(start -1.12 -1.16)
			(end 1.1 -1.16)
			(stroke
				(width 0.05)
				(type solid)
			)
			(layer "F.CrtYd")
		)
		(fp_line
			(start -1.12 -1.16)
			(end -1.12 1.15)
			(stroke
				(width 0.05)
				(type solid)
			)
			(layer "F.CrtYd")
		)
		(fp_line
			(start -1.12 1.15)
			(end 1.1 1.15)
			(stroke
				(width 0.05)
				(type solid)
			)
			(layer "F.CrtYd")
		)
		(fp_line
			(start 0.8 -0.425)
			(end -0.652 -0.425)
			(stroke
				(width 0.15)
				(type solid)
			)
			(layer "F.Fab")
		)
		(fp_line
			(start 0.8 -0.425)
			(end 0.8 0.424)
			(stroke
				(width 0.15)
				(type solid)
			)
			(layer "F.Fab")
		)
		(fp_line
			(start -0.652 -0.425)
			(end -0.802 -0.276)
			(stroke
				(width 0.15)
				(type solid)
			)
			(layer "F.Fab")
		)
		(fp_line
			(start -0.802 -0.276)
			(end -0.802 0.424)
			(stroke
				(width 0.15)
				(type solid)
			)
			(layer "F.Fab")
		)
		(fp_line
			(start 0.8 0.424)
			(end -0.802 0.424)
			(stroke
				(width 0.15)
				(type solid)
			)
			(layer "F.Fab")
		)
		(fp_circle
			(center -0.9652 0.9652)
			(end -0.9144 0.9652)
			(stroke
				(width 0.15)
				(type solid)
			)
			(fill no)
			(layer "F.Fab")
		)
		(pad "1" smd rect
			(at -0.5 0.65 90)
			(size 0.4 0.51)
			(layers "F.Cu" "F.Mask" "F.Paste")
			(net 465 "1V0_SYS")
			(pinfunction "G")
			(pintype "bidirectional")
		)
		(pad "2" smd rect
			(at 0.498 0.65 90)
			(size 0.4 0.51)
			(layers "F.Cu" "F.Mask" "F.Paste")
			(net 5 "GND")
			(pinfunction "S")
			(pintype "bidirectional")
		)
		(pad "3" smd rect
			(at 0 -0.652 90)
			(size 0.4 0.51)
			(layers "F.Cu" "F.Mask" "F.Paste")
			(net 237 "Net-(Q11-D)")
			(pinfunction "D")
			(pintype "bidirectional")
		)
	)
	(footprint "antmicro-footprints:R_0402_1005Metric"
		(layer "F.Cu")
		(at 123.65 88.974)
		(descr "Resistor SMD 0402")
		(tags "resistor SMD 0402")
		(property "Reference" "R150"
			(at -3.65 0.326 0)
			(layer "F.SilkS")
			(effects
				(font
					(size 0.7 0.7)
					(thickness 0.15)
				)
				(justify left bottom)
			)
		)
		(property "Value" "R_0R_0402"
			(at 0 1.4 0)
			(layer "F.Fab")
			(effects
				(font
					(size 0.7 0.7)
					(thickness 0.15)
				)
				(justify left bottom)
			)
		)
		(property "Description" "0R resistor in 0402 package with unspecified tolerance"
			(at 0 0 0)
			(layer "F.Fab")
			(hide yes)
			(effects
				(font
					(size 1.27 1.27)
					(thickness 0.15)
				)
			)
		)
		(property "Author" "Antmicro"
			(at 0 0 0)
			(layer "F.Fab")
			(hide yes)
			(effects
				(font
					(size 1 1)
					(thickness 0.15)
				)
			)
		)
		(property "Current" "1A"
			(at 0 0 0)
			(layer "F.Fab")
			(hide yes)
			(effects
				(font
					(size 1 1)
					(thickness 0.15)
				)
			)
		)
		(property "License" "Apache-2.0"
			(at 0 0 0)
			(layer "F.Fab")
			(hide yes)
			(effects
				(font
					(size 1 1)
					(thickness 0.15)
				)
			)
		)
		(property "MPN" "ERJ2GE0R00X"
			(at 0 0 0)
			(layer "F.Fab")
			(hide yes)
			(effects
				(font
					(size 1 1)
					(thickness 0.15)
				)
			)
		)
		(property "Manufacturer" "Panasonic"
			(at 0 0 0)
			(layer "F.Fab")
			(hide yes)
			(effects
				(font
					(size 1 1)
					(thickness 0.15)
				)
			)
		)
		(property "Tolerance" ""
			(at 0 0 0)
			(layer "F.Fab")
			(hide yes)
			(effects
				(font
					(size 1 1)
					(thickness 0.15)
				)
			)
		)
		(property "Val" "0R"
			(at 0 0 0)
			(layer "F.Fab")
			(hide yes)
			(effects
				(font
					(size 1 1)
					(thickness 0.15)
				)
			)
		)
		(sheetname "Supply")
		(sheetfile "supply.kicad_sch")
		(attr smd)
		(fp_rect
			(start -0.93 -0.47)
			(end 0.93 0.47)
			(stroke
				(width 0.05)
				(type solid)
			)
			(fill no)
			(layer "F.CrtYd")
		)
		(fp_rect
			(start -0.5 -0.25)
			(end 0.5 0.25)
			(stroke
				(width 0.15)
				(type solid)
			)
			(fill no)
			(layer "F.Fab")
		)
		(pad "1" smd roundrect
			(at -0.485 0)
			(size 0.59 0.64)
			(layers "F.Cu" "F.Mask" "F.Paste")
			(roundrect_rratio 0.25)
			(net 5 "GND")
			(pintype "passive")
		)
		(pad "2" smd roundrect
			(at 0.485 0)
			(size 0.59 0.64)
			(layers "F.Cu" "F.Mask" "F.Paste")
			(roundrect_rratio 0.25)
			(net 622 "/Supply/1V1_SS{slash}TR")
			(pintype "passive")
		)
	)
	(footprint "antmicro-footprints:R_0805_2012Metric"
		(layer "F.Cu")
		(at 126.34 81.274)
		(property "Reference" "R146"
			(at 1.56 0.426 0)
			(layer "F.SilkS")
			(effects
				(font
					(size 0.7 0.7)
					(thickness 0.15)
				)
				(justify left bottom)
			)
		)
		(property "Value" "R_0R_0805"
			(at 0 1.8 0)
			(layer "F.Fab")
			(effects
				(font
					(size 0.7 0.7)
					(thickness 0.15)
				)
				(justify left bottom)
			)
		)
		(property "Description" "0R resistor in 0805 package with unspecified tolerance"
			(at 0 0 0)
			(layer "F.Fab")
			(hide yes)
			(effects
				(font
					(size 1.27 1.27)
					(thickness 0.15)
				)
			)
		)
		(property "Author" "Antmicro"
			(at 0 0 0)
			(layer "F.Fab")
			(hide yes)
			(effects
				(font
					(size 1 1)
					(thickness 0.15)
				)
			)
		)
		(property "Current" "2.5A"
			(at 0 0 0)
			(layer "F.Fab")
			(hide yes)
			(effects
				(font
					(size 1 1)
					(thickness 0.15)
				)
			)
		)
		(property "License" "Apache-2.0"
			(at 0 0 0)
			(layer "F.Fab")
			(hide yes)
			(effects
				(font
					(size 1 1)
					(thickness 0.15)
				)
			)
		)
		(property "MPN" "CRCW08050000Z0EA"
			(at 0 0 0)
			(layer "F.Fab")
			(hide yes)
			(effects
				(font
					(size 1 1)
					(thickness 0.15)
				)
			)
		)
		(property "Manufacturer" "Vishay"
			(at 0 0 0)
			(layer "F.Fab")
			(hide yes)
			(effects
				(font
					(size 1 1)
					(thickness 0.15)
				)
			)
		)
		(property "Tolerance" ""
			(at 0 0 0)
			(layer "F.Fab")
			(hide yes)
			(effects
				(font
					(size 1 1)
					(thickness 0.15)
				)
			)
		)
		(property "Val" "0R"
			(at 0 0 0)
			(layer "F.Fab")
			(hide yes)
			(effects
				(font
					(size 1 1)
					(thickness 0.15)
				)
			)
		)
		(sheetname "Supply")
		(sheetfile "supply.kicad_sch")
		(attr smd)
		(fp_line
			(start -0.32 0.699)
			(end 0.28 0.699)
			(stroke
				(width 0.15)
				(type solid)
			)
			(layer "F.SilkS")
		)
		(fp_line
			(start -0.3 -0.701)
			(end 0.298 -0.701)
			(stroke
				(width 0.15)
				(type solid)
			)
			(layer "F.SilkS")
		)
		(fp_rect
			(start -1.75 -0.85)
			(end 1.75 0.85)
			(stroke
				(width 0.05)
				(type solid)
			)
			(fill no)
			(layer "F.CrtYd")
		)
		(fp_line
			(start -0.951 -0.682)
			(end 0.949 -0.682)
			(stroke
				(width 0.15)
				(type solid)
			)
			(layer "F.Fab")
		)
		(fp_line
			(start -0.951 -0.677)
			(end -0.951 0.675)
			(stroke
				(width 0.15)
				(type solid)
			)
			(layer "F.Fab")
		)
		(fp_line
			(start -0.951 0.68)
			(end 0.949 0.68)
			(stroke
				(width 0.15)
				(type solid)
			)
			(layer "F.Fab")
		)
		(fp_line
			(start 0.949 -0.677)
			(end 0.949 0.675)
			(stroke
				(width 0.15)
				(type solid)
			)
			(layer "F.Fab")
		)
		(pad "1" smd roundrect
			(at -1.1 -0.001)
			(size 1 1.4)
			(layers "F.Cu" "F.Mask" "F.Paste")
			(roundrect_rratio 0.15)
			(net 587 "/Supply/1V1_REG")
			(pintype "passive")
		)
		(pad "2" smd roundrect
			(at 1.1 -0.001)
			(size 1 1.4)
			(layers "F.Cu" "F.Mask" "F.Paste")
			(roundrect_rratio 0.15)
			(net 461 "1V1_SYS")
			(pintype "passive")
		)
	)
	(footprint "antmicro-footprints:TP_SMD_1mm"
		(layer "F.Cu")
		(at 144.7 90.1498)
		(property "Reference" "TP17"
			(at -1.4 -7.479898 0)
			(layer "F.SilkS")
			(effects
				(font
					(size 0.7 0.7)
					(thickness 0.15)
				)
				(justify left bottom)
			)
		)
		(property "Value" "TP_1mm_SMD"
			(at 0 1.4 0)
			(layer "F.Fab")
			(effects
				(font
					(size 0.7 0.7)
					(thickness 0.15)
				)
				(justify left bottom)
			)
		)
		(property "Description" "Test Point 1mm"
			(at 0 0 0)
			(layer "F.Fab")
			(hide yes)
			(effects
				(font
					(size 1.27 1.27)
					(thickness 0.15)
				)
			)
		)
		(property "Author" "Antmicro"
			(at 0 0 0)
			(layer "F.Fab")
			(hide yes)
			(effects
				(font
					(size 1 1)
					(thickness 0.15)
				)
			)
		)
		(property "License" "Apache-2.0"
			(at 0 0 0)
			(layer "F.Fab")
			(hide yes)
			(effects
				(font
					(size 1 1)
					(thickness 0.15)
				)
			)
		)
		(property "MPN" ""
			(at 0 0 0)
			(layer "F.Fab")
			(hide yes)
			(effects
				(font
					(size 1 1)
					(thickness 0.15)
				)
			)
		)
		(property "Manufacturer" ""
			(at 0 0 0)
			(layer "F.Fab")
			(hide yes)
			(effects
				(font
					(size 1 1)
					(thickness 0.15)
				)
			)
		)
		(sheetname "Supply")
		(sheetfile "supply.kicad_sch")
		(attr exclude_from_pos_files)
		(pad "1" smd circle
			(at 0 0)
			(size 1 1)
			(layers "F.Cu" "F.Mask")
			(net 602 "1V2_SYS")
			(pinfunction "1")
			(pintype "passive")
		)
	)
	(footprint "antmicro-footprints:C_0603_1608Metric"
		(layer "F.Cu")
		(at 125.3 63.1 180)
		(descr "Capacitor SMD 0603")
		(tags "capacitor 0603")
		(property "Reference" "C184"
			(at 3.9 -0.35 180)
			(layer "F.SilkS")
			(effects
				(font
					(size 0.7 0.7)
					(thickness 0.15)
				)
				(justify left bottom)
			)
		)
		(property "Value" "C_1u_0603"
			(at 0 1.6 180)
			(layer "F.Fab")
			(effects
				(font
					(size 0.7 0.7)
					(thickness 0.15)
				)
				(justify left bottom)
			)
		)
		(property "Description" " "
			(at 0 0 180)
			(layer "F.Fab")
			(hide yes)
			(effects
				(font
					(size 1.27 1.27)
					(thickness 0.15)
				)
			)
		)
		(property "Author" "Antmicro"
			(at 250.6 126.2 0)
			(layer "F.Fab")
			(hide yes)
			(effects
				(font
					(size 1 1)
					(thickness 0.15)
				)
			)
		)
		(property "Dielectric" ""
			(at 250.6 126.2 0)
			(layer "F.Fab")
			(hide yes)
			(effects
				(font
					(size 1 1)
					(thickness 0.15)
				)
			)
		)
		(property "License" "Apache-2.0"
			(at 250.6 126.2 0)
			(layer "F.Fab")
			(hide yes)
			(effects
				(font
					(size 1 1)
					(thickness 0.15)
				)
			)
		)
		(property "MPN" "0603YD105KAT2A"
			(at 250.6 126.2 0)
			(layer "F.Fab")
			(hide yes)
			(effects
				(font
					(size 1 1)
					(thickness 0.15)
				)
			)
		)
		(property "Manufacturer" "Walsin"
			(at 250.6 126.2 0)
			(layer "F.Fab")
			(hide yes)
			(effects
				(font
					(size 1 1)
					(thickness 0.15)
				)
			)
		)
		(property "Val" "1u"
			(at 250.6 126.2 0)
			(layer "F.Fab")
			(hide yes)
			(effects
				(font
					(size 1 1)
					(thickness 0.15)
				)
			)
		)
		(property "Voltage" ""
			(at 250.6 126.2 0)
			(layer "F.Fab")
			(hide yes)
			(effects
				(font
					(size 1 1)
					(thickness 0.15)
				)
			)
		)
		(sheetname "Supply")
		(sheetfile "supply.kicad_sch")
		(attr exclude_from_pos_files exclude_from_bom dnp)
		(fp_line
			(start -0.3 0.3)
			(end 0.3 0.3)
			(stroke
				(width 0.15)
				(type solid)
			)
			(layer "F.SilkS")
		)
		(fp_line
			(start -0.3 -0.3)
			(end 0.3 -0.3)
			(stroke
				(width 0.15)
				(type solid)
			)
			(layer "F.SilkS")
		)
		(fp_rect
			(start -1.24 -0.7)
			(end 1.24 0.7)
			(stroke
				(width 0.05)
				(type solid)
			)
			(fill no)
			(layer "F.CrtYd")
		)
		(fp_rect
			(start -0.8 -0.4)
			(end 0.8 0.4)
			(stroke
				(width 0.15)
				(type solid)
			)
			(fill no)
			(layer "F.Fab")
		)
		(pad "1" smd roundrect
			(at -0.7 0 180)
			(size 0.6 0.8)
			(layers "F.Cu" "F.Mask" "F.Paste")
			(roundrect_rratio 0.2)
			(net 463 "VCC5V0_INT")
			(pintype "passive")
		)
		(pad "2" smd roundrect
			(at 0.7 0 180)
			(size 0.6 0.8)
			(layers "F.Cu" "F.Mask" "F.Paste")
			(roundrect_rratio 0.2)
			(net 5 "GND")
			(pintype "passive")
		)
	)
	(footprint "antmicro-footprints:C_0805_2012Metric"
		(layer "F.Cu")
		(at 112.7492 111.975 90)
		(descr "Capacitor SMD 0805")
		(tags "capacitor SMD 0805")
		(property "Reference" "C126"
			(at 1.65 0.3508 90)
			(layer "F.SilkS")
			(effects
				(font
					(size 0.7 0.7)
					(thickness 0.15)
				)
				(justify left bottom)
			)
		)
		(property "Value" "C_22u_0805_16V"
			(at 0 1.947 90)
			(layer "F.Fab")
			(effects
				(font
					(size 0.7 0.7)
					(thickness 0.15)
				)
				(justify left bottom)
			)
		)
		(property "Description" " "
			(at 0 0 90)
			(layer "F.Fab")
			(hide yes)
			(effects
				(font
					(size 1.27 1.27)
					(thickness 0.15)
				)
			)
		)
		(property "Author" "Antmicro"
			(at 224.7242 -0.7742 0)
			(layer "F.Fab")
			(hide yes)
			(effects
				(font
					(size 1 1)
					(thickness 0.15)
				)
			)
		)
		(property "Dielectric" ""
			(at 224.7242 -0.7742 0)
			(layer "F.Fab")
			(hide yes)
			(effects
				(font
					(size 1 1)
					(thickness 0.15)
				)
			)
		)
		(property "License" "Apache-2.0"
			(at 224.7242 -0.7742 0)
			(layer "F.Fab")
			(hide yes)
			(effects
				(font
					(size 1 1)
					(thickness 0.15)
				)
			)
		)
		(property "MPN" "GRT21BR61C226ME13L"
			(at 224.7242 -0.7742 0)
			(layer "F.Fab")
			(hide yes)
			(effects
				(font
					(size 1 1)
					(thickness 0.15)
				)
			)
		)
		(property "Manufacturer" "Murata"
			(at 224.7242 -0.7742 0)
			(layer "F.Fab")
			(hide yes)
			(effects
				(font
					(size 1 1)
					(thickness 0.15)
				)
			)
		)
		(property "Val" "22u/16V"
			(at 224.7242 -0.7742 0)
			(layer "F.Fab")
			(hide yes)
			(effects
				(font
					(size 1 1)
					(thickness 0.15)
				)
			)
		)
		(property "Voltage" ""
			(at 224.7242 -0.7742 0)
			(layer "F.Fab")
			(hide yes)
			(effects
				(font
					(size 1 1)
					(thickness 0.15)
				)
			)
		)
		(sheetname "Supply")
		(sheetfile "supply.kicad_sch")
		(attr smd)
		(fp_line
			(start -0.3 -0.8)
			(end 0.3 -0.8)
			(stroke
				(width 0.15)
				(type solid)
			)
			(layer "F.SilkS")
		)
		(fp_line
			(start -0.3 0.8)
			(end 0.3 0.8)
			(stroke
				(width 0.15)
				(type solid)
			)
			(layer "F.SilkS")
		)
		(fp_rect
			(start -1.9 -0.93)
			(end 1.9 0.93)
			(stroke
				(width 0.05)
				(type solid)
			)
			(fill no)
			(layer "F.CrtYd")
		)
		(fp_rect
			(start -0.95 -0.675)
			(end 0.95 0.675)
			(stroke
				(width 0.15)
				(type solid)
			)
			(fill no)
			(layer "F.Fab")
		)
		(pad "1" smd rect
			(at -1.05 0 90)
			(size 1.2 1.2)
			(layers "F.Cu" "F.Mask" "F.Paste")
			(net 224 "VIN")
			(pintype "passive")
		)
		(pad "2" smd rect
			(at 1.05 0 90)
			(size 1.2 1.2)
			(layers "F.Cu" "F.Mask" "F.Paste")
			(net 5 "GND")
			(pintype "passive")
		)
	)
	(footprint "antmicro-footprints:C_0402_1005Metric"
		(layer "F.Cu")
		(at 135.6 65.2 -90)
		(descr "Capacitor SMD 0402")
		(tags "capacitor SMD 0402")
		(property "Reference" "C136"
			(at 3.7 -0.4 270)
			(layer "F.SilkS")
			(effects
				(font
					(size 0.7 0.7)
					(thickness 0.15)
				)
				(justify left bottom)
			)
		)
		(property "Value" "C_100n_6V3_0402"
			(at 0 1.4 270)
			(layer "F.Fab")
			(effects
				(font
					(size 0.7 0.7)
					(thickness 0.15)
				)
				(justify left bottom)
			)
		)
		(property "Description" " "
			(at 0 0 270)
			(layer "F.Fab")
			(hide yes)
			(effects
				(font
					(size 1.27 1.27)
					(thickness 0.15)
				)
			)
		)
		(property "Author" "Antmicro"
			(at 70.4 200.8 0)
			(layer "F.Fab")
			(hide yes)
			(effects
				(font
					(size 1 1)
					(thickness 0.15)
				)
			)
		)
		(property "Dielectric" ""
			(at 70.4 200.8 0)
			(layer "F.Fab")
			(hide yes)
			(effects
				(font
					(size 1 1)
					(thickness 0.15)
				)
			)
		)
		(property "License" "Apache-2.0"
			(at 70.4 200.8 0)
			(layer "F.Fab")
			(hide yes)
			(effects
				(font
					(size 1 1)
					(thickness 0.15)
				)
			)
		)
		(property "MPN" "0402X104K6R3CT"
			(at 70.4 200.8 0)
			(layer "F.Fab")
			(hide yes)
			(effects
				(font
					(size 1 1)
					(thickness 0.15)
				)
			)
		)
		(property "Manufacturer" "Walsin"
			(at 70.4 200.8 0)
			(layer "F.Fab")
			(hide yes)
			(effects
				(font
					(size 1 1)
					(thickness 0.15)
				)
			)
		)
		(property "Val" "100n"
			(at 70.4 200.8 0)
			(layer "F.Fab")
			(hide yes)
			(effects
				(font
					(size 1 1)
					(thickness 0.15)
				)
			)
		)
		(property "Voltage" ""
			(at 70.4 200.8 0)
			(layer "F.Fab")
			(hide yes)
			(effects
				(font
					(size 1 1)
					(thickness 0.15)
				)
			)
		)
		(sheetname "Supply")
		(sheetfile "supply.kicad_sch")
		(attr smd)
		(fp_rect
			(start -0.94 -0.47)
			(end 0.94 0.47)
			(stroke
				(width 0.05)
				(type solid)
			)
			(fill no)
			(layer "F.CrtYd")
		)
		(fp_rect
			(start -0.499 -0.249)
			(end 0.499 0.249)
			(stroke
				(width 0.15)
				(type solid)
			)
			(fill no)
			(layer "F.Fab")
		)
		(pad "1" smd roundrect
			(at -0.484 0 270)
			(size 0.59 0.64)
			(layers "F.Cu" "F.Mask" "F.Paste")
			(roundrect_rratio 0.25)
			(net 639 "/Supply/0V6_CP")
			(pintype "passive")
		)
		(pad "2" smd roundrect
			(at 0.484 0 270)
			(size 0.59 0.64)
			(layers "F.Cu" "F.Mask" "F.Paste")
			(roundrect_rratio 0.25)
			(net 5 "GND")
			(pintype "passive")
		)
	)
	(footprint "antmicro-footprints:C_0402_1005Metric"
		(layer "F.Cu")
		(at 115.975 98.299)
		(descr "Capacitor SMD 0402")
		(tags "capacitor SMD 0402")
		(property "Reference" "C157"
			(at -3.575 0.401 0)
			(layer "F.SilkS")
			(effects
				(font
					(size 0.7 0.7)
					(thickness 0.15)
				)
				(justify left bottom)
			)
		)
		(property "Value" "C_100n_6V3_0402"
			(at 0 1.4 0)
			(layer "F.Fab")
			(effects
				(font
					(size 0.7 0.7)
					(thickness 0.15)
				)
				(justify left bottom)
			)
		)
		(property "Description" " "
			(at 0 0 0)
			(layer "F.Fab")
			(hide yes)
			(effects
				(font
					(size 1.27 1.27)
					(thickness 0.15)
				)
			)
		)
		(property "Author" "Antmicro"
			(at 0 0 0)
			(layer "F.Fab")
			(hide yes)
			(effects
				(font
					(size 1 1)
					(thickness 0.15)
				)
			)
		)
		(property "Dielectric" ""
			(at 0 0 0)
			(layer "F.Fab")
			(hide yes)
			(effects
				(font
					(size 1 1)
					(thickness 0.15)
				)
			)
		)
		(property "License" "Apache-2.0"
			(at 0 0 0)
			(layer "F.Fab")
			(hide yes)
			(effects
				(font
					(size 1 1)
					(thickness 0.15)
				)
			)
		)
		(property "MPN" "0402X104K6R3CT"
			(at 0 0 0)
			(layer "F.Fab")
			(hide yes)
			(effects
				(font
					(size 1 1)
					(thickness 0.15)
				)
			)
		)
		(property "Manufacturer" "Walsin"
			(at 0 0 0)
			(layer "F.Fab")
			(hide yes)
			(effects
				(font
					(size 1 1)
					(thickness 0.15)
				)
			)
		)
		(property "Val" "100n"
			(at 0 0 0)
			(layer "F.Fab")
			(hide yes)
			(effects
				(font
					(size 1 1)
					(thickness 0.15)
				)
			)
		)
		(property "Voltage" ""
			(at 0 0 0)
			(layer "F.Fab")
			(hide yes)
			(effects
				(font
					(size 1 1)
					(thickness 0.15)
				)
			)
		)
		(sheetname "Supply")
		(sheetfile "supply.kicad_sch")
		(attr smd)
		(fp_rect
			(start -0.94 -0.47)
			(end 0.94 0.47)
			(stroke
				(width 0.05)
				(type solid)
			)
			(fill no)
			(layer "F.CrtYd")
		)
		(fp_rect
			(start -0.499 -0.249)
			(end 0.499 0.249)
			(stroke
				(width 0.15)
				(type solid)
			)
			(fill no)
			(layer "F.Fab")
		)
		(pad "1" smd roundrect
			(at -0.484 0)
			(size 0.59 0.64)
			(layers "F.Cu" "F.Mask" "F.Paste")
			(roundrect_rratio 0.25)
			(net 575 "/Supply/3V3_SW")
			(pintype "passive")
		)
		(pad "2" smd roundrect
			(at 0.484 0)
			(size 0.59 0.64)
			(layers "F.Cu" "F.Mask" "F.Paste")
			(roundrect_rratio 0.25)
			(net 574 "/Supply/3V3_BST")
			(pintype "passive")
		)
	)
	(footprint "antmicro-footprints:R_0805_2012Metric"
		(layer "F.Cu")
		(at 126.0825 93.749)
		(property "Reference" "R147"
			(at 1.6175 0.351 0)
			(layer "F.SilkS")
			(effects
				(font
					(size 0.7 0.7)
					(thickness 0.15)
				)
				(justify left bottom)
			)
		)
		(property "Value" "R_0R_0805"
			(at 0 1.8 0)
			(layer "F.Fab")
			(effects
				(font
					(size 0.7 0.7)
					(thickness 0.15)
				)
				(justify left bottom)
			)
		)
		(property "Description" "0R resistor in 0805 package with unspecified tolerance"
			(at 0 0 0)
			(layer "F.Fab")
			(hide yes)
			(effects
				(font
					(size 1.27 1.27)
					(thickness 0.15)
				)
			)
		)
		(property "Author" "Antmicro"
			(at 0 0 0)
			(layer "F.Fab")
			(hide yes)
			(effects
				(font
					(size 1 1)
					(thickness 0.15)
				)
			)
		)
		(property "Current" "2.5A"
			(at 0 0 0)
			(layer "F.Fab")
			(hide yes)
			(effects
				(font
					(size 1 1)
					(thickness 0.15)
				)
			)
		)
		(property "License" "Apache-2.0"
			(at 0 0 0)
			(layer "F.Fab")
			(hide yes)
			(effects
				(font
					(size 1 1)
					(thickness 0.15)
				)
			)
		)
		(property "MPN" "CRCW08050000Z0EA"
			(at 0 0 0)
			(layer "F.Fab")
			(hide yes)
			(effects
				(font
					(size 1 1)
					(thickness 0.15)
				)
			)
		)
		(property "Manufacturer" "Vishay"
			(at 0 0 0)
			(layer "F.Fab")
			(hide yes)
			(effects
				(font
					(size 1 1)
					(thickness 0.15)
				)
			)
		)
		(property "Tolerance" ""
			(at 0 0 0)
			(layer "F.Fab")
			(hide yes)
			(effects
				(font
					(size 1 1)
					(thickness 0.15)
				)
			)
		)
		(property "Val" "0R"
			(at 0 0 0)
			(layer "F.Fab")
			(hide yes)
			(effects
				(font
					(size 1 1)
					(thickness 0.15)
				)
			)
		)
		(sheetname "Supply")
		(sheetfile "supply.kicad_sch")
		(attr smd)
		(fp_line
			(start -0.32 0.699)
			(end 0.28 0.699)
			(stroke
				(width 0.15)
				(type solid)
			)
			(layer "F.SilkS")
		)
		(fp_line
			(start -0.3 -0.701)
			(end 0.298 -0.701)
			(stroke
				(width 0.15)
				(type solid)
			)
			(layer "F.SilkS")
		)
		(fp_rect
			(start -1.75 -0.85)
			(end 1.75 0.85)
			(stroke
				(width 0.05)
				(type solid)
			)
			(fill no)
			(layer "F.CrtYd")
		)
		(fp_line
			(start -0.951 -0.682)
			(end 0.949 -0.682)
			(stroke
				(width 0.15)
				(type solid)
			)
			(layer "F.Fab")
		)
		(fp_line
			(start -0.951 -0.677)
			(end -0.951 0.675)
			(stroke
				(width 0.15)
				(type solid)
			)
			(layer "F.Fab")
		)
		(fp_line
			(start -0.951 0.68)
			(end 0.949 0.68)
			(stroke
				(width 0.15)
				(type solid)
			)
			(layer "F.Fab")
		)
		(fp_line
			(start 0.949 -0.677)
			(end 0.949 0.675)
			(stroke
				(width 0.15)
				(type solid)
			)
			(layer "F.Fab")
		)
		(pad "1" smd roundrect
			(at -1.1 -0.001)
			(size 1 1.4)
			(layers "F.Cu" "F.Mask" "F.Paste")
			(roundrect_rratio 0.15)
			(net 588 "/Supply/1V0_REG")
			(pintype "passive")
		)
		(pad "2" smd roundrect
			(at 1.1 -0.001)
			(size 1 1.4)
			(layers "F.Cu" "F.Mask" "F.Paste")
			(roundrect_rratio 0.15)
			(net 465 "1V0_SYS")
			(pintype "passive")
		)
	)
	(footprint "antmicro-footprints:C_0603_1608Metric"
		(layer "F.Cu")
		(at 134.3 52.7 90)
		(descr "Capacitor SMD 0603")
		(tags "capacitor 0603")
		(property "Reference" "C196"
			(at 1 0.3 90)
			(layer "F.SilkS")
			(effects
				(font
					(size 0.7 0.7)
					(thickness 0.15)
				)
				(justify left bottom)
			)
		)
		(property "Value" "C_22u_0603"
			(at 0 1.6 90)
			(layer "F.Fab")
			(effects
				(font
					(size 0.7 0.7)
					(thickness 0.15)
				)
				(justify left bottom)
			)
		)
		(property "Description" " "
			(at 0 0 90)
			(layer "F.Fab")
			(hide yes)
			(effects
				(font
					(size 1.27 1.27)
					(thickness 0.15)
				)
			)
		)
		(property "Author" "Antmicro"
			(at 187 -81.6 0)
			(layer "F.Fab")
			(hide yes)
			(effects
				(font
					(size 1 1)
					(thickness 0.15)
				)
			)
		)
		(property "Dielectric" ""
			(at 187 -81.6 0)
			(layer "F.Fab")
			(hide yes)
			(effects
				(font
					(size 1 1)
					(thickness 0.15)
				)
			)
		)
		(property "License" "Apache-2.0"
			(at 187 -81.6 0)
			(layer "F.Fab")
			(hide yes)
			(effects
				(font
					(size 1 1)
					(thickness 0.15)
				)
			)
		)
		(property "MPN" "GRM188R60J226MEA0D"
			(at 187 -81.6 0)
			(layer "F.Fab")
			(hide yes)
			(effects
				(font
					(size 1 1)
					(thickness 0.15)
				)
			)
		)
		(property "Manufacturer" "Murata"
			(at 187 -81.6 0)
			(layer "F.Fab")
			(hide yes)
			(effects
				(font
					(size 1 1)
					(thickness 0.15)
				)
			)
		)
		(property "Val" "22u"
			(at 187 -81.6 0)
			(layer "F.Fab")
			(hide yes)
			(effects
				(font
					(size 1 1)
					(thickness 0.15)
				)
			)
		)
		(property "Voltage" ""
			(at 187 -81.6 0)
			(layer "F.Fab")
			(hide yes)
			(effects
				(font
					(size 1 1)
					(thickness 0.15)
				)
			)
		)
		(sheetname "Supply")
		(sheetfile "supply.kicad_sch")
		(attr exclude_from_pos_files exclude_from_bom dnp)
		(fp_line
			(start -0.3 -0.3)
			(end 0.3 -0.3)
			(stroke
				(width 0.15)
				(type solid)
			)
			(layer "F.SilkS")
		)
		(fp_line
			(start -0.3 0.3)
			(end 0.3 0.3)
			(stroke
				(width 0.15)
				(type solid)
			)
			(layer "F.SilkS")
		)
		(fp_rect
			(start -1.24 -0.7)
			(end 1.24 0.7)
			(stroke
				(width 0.05)
				(type solid)
			)
			(fill no)
			(layer "F.CrtYd")
		)
		(fp_rect
			(start -0.8 -0.4)
			(end 0.8 0.4)
			(stroke
				(width 0.15)
				(type solid)
			)
			(fill no)
			(layer "F.Fab")
		)
		(pad "1" smd roundrect
			(at -0.7 0 90)
			(size 0.6 0.8)
			(layers "F.Cu" "F.Mask" "F.Paste")
			(roundrect_rratio 0.2)
			(net 550 "VDD1V1")
			(pintype "passive")
		)
		(pad "2" smd roundrect
			(at 0.7 0 90)
			(size 0.6 0.8)
			(layers "F.Cu" "F.Mask" "F.Paste")
			(roundrect_rratio 0.2)
			(net 5 "GND")
			(pintype "passive")
		)
	)
	(footprint "antmicro-footprints:R_0402_1005Metric"
		(layer "F.Cu")
		(at 111.362806 90.974)
		(descr "Resistor SMD 0402")
		(tags "resistor SMD 0402")
		(property "Reference" "R136"
			(at -3.662806 0.326 0)
			(layer "F.SilkS")
			(effects
				(font
					(size 0.7 0.7)
					(thickness 0.15)
				)
				(justify left bottom)
			)
		)
		(property "Value" "R_31k6_0402"
			(at 0 1.4 0)
			(layer "F.Fab")
			(effects
				(font
					(size 0.7 0.7)
					(thickness 0.15)
				)
				(justify left bottom)
			)
		)
		(property "Description" "31k6 resistor in 0402 package with 1% tolerance"
			(at 0 0 0)
			(layer "F.Fab")
			(hide yes)
			(effects
				(font
					(size 1.27 1.27)
					(thickness 0.15)
				)
			)
		)
		(property "Author" "Antmicro"
			(at 0 0 0)
			(layer "F.Fab")
			(hide yes)
			(effects
				(font
					(size 1 1)
					(thickness 0.15)
				)
			)
		)
		(property "License" "Apache-2.0"
			(at 0 0 0)
			(layer "F.Fab")
			(hide yes)
			(effects
				(font
					(size 1 1)
					(thickness 0.15)
				)
			)
		)
		(property "MPN" "CR0402-FX-3162GLF"
			(at 0 0 0)
			(layer "F.Fab")
			(hide yes)
			(effects
				(font
					(size 1 1)
					(thickness 0.15)
				)
			)
		)
		(property "Manufacturer" "Bourns"
			(at 0 0 0)
			(layer "F.Fab")
			(hide yes)
			(effects
				(font
					(size 1 1)
					(thickness 0.15)
				)
			)
		)
		(property "Tolerance" "1%"
			(at 0 0 0)
			(layer "F.Fab")
			(hide yes)
			(effects
				(font
					(size 1 1)
					(thickness 0.15)
				)
			)
		)
		(property "Val" "31k6"
			(at 0 0 0)
			(layer "F.Fab")
			(hide yes)
			(effects
				(font
					(size 1 1)
					(thickness 0.15)
				)
			)
		)
		(sheetname "Supply")
		(sheetfile "supply.kicad_sch")
		(attr smd)
		(fp_rect
			(start -0.93 -0.47)
			(end 0.93 0.47)
			(stroke
				(width 0.05)
				(type solid)
			)
			(fill no)
			(layer "F.CrtYd")
		)
		(fp_rect
			(start -0.5 -0.25)
			(end 0.5 0.25)
			(stroke
				(width 0.15)
				(type solid)
			)
			(fill no)
			(layer "F.Fab")
		)
		(pad "1" smd roundrect
			(at -0.485 0)
			(size 0.59 0.64)
			(layers "F.Cu" "F.Mask" "F.Paste")
			(roundrect_rratio 0.25)
			(net 583 "/Supply/1V8_REG")
			(pintype "passive")
		)
		(pad "2" smd roundrect
			(at 0.485 0)
			(size 0.59 0.64)
			(layers "F.Cu" "F.Mask" "F.Paste")
			(roundrect_rratio 0.25)
			(net 600 "/Supply/1V8_FB")
			(pintype "passive")
		)
	)
	(footprint "antmicro-footprints:R_0402_1005Metric"
		(layer "F.Cu")
		(at 185.1 111.85 90)
		(descr "Resistor SMD 0402")
		(tags "resistor SMD 0402")
		(property "Reference" "R141"
			(at 0.75 0.4 90)
			(layer "F.SilkS")
			(effects
				(font
					(size 0.7 0.7)
					(thickness 0.15)
				)
				(justify left bottom)
			)
		)
		(property "Value" "R_10k_0402"
			(at 0 1.4 90)
			(layer "F.Fab")
			(effects
				(font
					(size 0.7 0.7)
					(thickness 0.15)
				)
				(justify left bottom)
			)
		)
		(property "Description" "10k resistor in 0402 package with 1% tolerance"
			(at 0 0 90)
			(layer "F.Fab")
			(hide yes)
			(effects
				(font
					(size 1.27 1.27)
					(thickness 0.15)
				)
			)
		)
		(property "Author" "Antmicro"
			(at 296.95 -73.25 0)
			(layer "F.Fab")
			(hide yes)
			(effects
				(font
					(size 1 1)
					(thickness 0.15)
				)
			)
		)
		(property "License" "Apache-2.0"
			(at 296.95 -73.25 0)
			(layer "F.Fab")
			(hide yes)
			(effects
				(font
					(size 1 1)
					(thickness 0.15)
				)
			)
		)
		(property "MPN" "CR0402-FX-1002GLF"
			(at 296.95 -73.25 0)
			(layer "F.Fab")
			(hide yes)
			(effects
				(font
					(size 1 1)
					(thickness 0.15)
				)
			)
		)
		(property "Manufacturer" "Bourns"
			(at 296.95 -73.25 0)
			(layer "F.Fab")
			(hide yes)
			(effects
				(font
					(size 1 1)
					(thickness 0.15)
				)
			)
		)
		(property "Tolerance" "1%"
			(at 296.95 -73.25 0)
			(layer "F.Fab")
			(hide yes)
			(effects
				(font
					(size 1 1)
					(thickness 0.15)
				)
			)
		)
		(property "Val" "10k"
			(at 296.95 -73.25 0)
			(layer "F.Fab")
			(hide yes)
			(effects
				(font
					(size 1 1)
					(thickness 0.15)
				)
			)
		)
		(sheetname "Supply")
		(sheetfile "supply.kicad_sch")
		(attr smd)
		(fp_rect
			(start -0.93 -0.47)
			(end 0.93 0.47)
			(stroke
				(width 0.05)
				(type solid)
			)
			(fill no)
			(layer "F.CrtYd")
		)
		(fp_rect
			(start -0.5 -0.25)
			(end 0.5 0.25)
			(stroke
				(width 0.15)
				(type solid)
			)
			(fill no)
			(layer "F.Fab")
		)
		(pad "1" smd roundrect
			(at -0.485 0 90)
			(size 0.59 0.64)
			(layers "F.Cu" "F.Mask" "F.Paste")
			(roundrect_rratio 0.25)
			(net 601 "/Supply/1V2_FB")
			(pintype "passive")
		)
		(pad "2" smd roundrect
			(at 0.485 0 90)
			(size 0.59 0.64)
			(layers "F.Cu" "F.Mask" "F.Paste")
			(roundrect_rratio 0.25)
			(net 5 "GND")
			(pintype "passive")
		)
	)
	(footprint "antmicro-footprints:C_0402_1005Metric"
		(layer "F.Cu")
		(at 111.725 95.249 180)
		(descr "Capacitor SMD 0402")
		(tags "capacitor SMD 0402")
		(property "Reference" "C177"
			(at 3.625 -0.351 180)
			(layer "F.SilkS")
			(effects
				(font
					(size 0.7 0.7)
					(thickness 0.15)
				)
				(justify left bottom)
			)
		)
		(property "Value" "C_1u_0402"
			(at 0 1.4 180)
			(layer "F.Fab")
			(effects
				(font
					(size 0.7 0.7)
					(thickness 0.15)
				)
				(justify left bottom)
			)
		)
		(property "Description" " "
			(at 0 0 180)
			(layer "F.Fab")
			(hide yes)
			(effects
				(font
					(size 1.27 1.27)
					(thickness 0.15)
				)
			)
		)
		(property "Author" "Antmicro"
			(at 223.45 190.498 0)
			(layer "F.Fab")
			(hide yes)
			(effects
				(font
					(size 1 1)
					(thickness 0.15)
				)
			)
		)
		(property "Dielectric" ""
			(at 223.45 190.498 0)
			(layer "F.Fab")
			(hide yes)
			(effects
				(font
					(size 1 1)
					(thickness 0.15)
				)
			)
		)
		(property "License" "Apache-2.0"
			(at 223.45 190.498 0)
			(layer "F.Fab")
			(hide yes)
			(effects
				(font
					(size 1 1)
					(thickness 0.15)
				)
			)
		)
		(property "MPN" "C1005X6S1A105K050BC"
			(at 223.45 190.498 0)
			(layer "F.Fab")
			(hide yes)
			(effects
				(font
					(size 1 1)
					(thickness 0.15)
				)
			)
		)
		(property "Manufacturer" "TDK"
			(at 223.45 190.498 0)
			(layer "F.Fab")
			(hide yes)
			(effects
				(font
					(size 1 1)
					(thickness 0.15)
				)
			)
		)
		(property "Val" "1u"
			(at 223.45 190.498 0)
			(layer "F.Fab")
			(hide yes)
			(effects
				(font
					(size 1 1)
					(thickness 0.15)
				)
			)
		)
		(property "Voltage" ""
			(at 223.45 190.498 0)
			(layer "F.Fab")
			(hide yes)
			(effects
				(font
					(size 1 1)
					(thickness 0.15)
				)
			)
		)
		(sheetname "Supply")
		(sheetfile "supply.kicad_sch")
		(attr smd)
		(fp_rect
			(start -0.94 -0.47)
			(end 0.94 0.47)
			(stroke
				(width 0.05)
				(type solid)
			)
			(fill no)
			(layer "F.CrtYd")
		)
		(fp_rect
			(start -0.499 -0.249)
			(end 0.499 0.249)
			(stroke
				(width 0.15)
				(type solid)
			)
			(fill no)
			(layer "F.Fab")
		)
		(pad "1" smd roundrect
			(at -0.484 0 180)
			(size 0.59 0.64)
			(layers "F.Cu" "F.Mask" "F.Paste")
			(roundrect_rratio 0.25)
			(net 576 "/Supply/3V3_REG")
			(pintype "passive")
		)
		(pad "2" smd roundrect
			(at 0.484 0 180)
			(size 0.59 0.64)
			(layers "F.Cu" "F.Mask" "F.Paste")
			(roundrect_rratio 0.25)
			(net 5 "GND")
			(pintype "passive")
		)
	)
	(footprint "antmicro-footprints:R_0805_2012Metric"
		(layer "F.Cu")
		(at 113.797806 82.274)
		(property "Reference" "R144"
			(at 0 -1 0)
			(layer "F.SilkS")
			(effects
				(font
					(size 0.7 0.7)
					(thickness 0.15)
				)
				(justify left bottom)
			)
		)
		(property "Value" "R_0R_0805"
			(at 0 1.8 0)
			(layer "F.Fab")
			(effects
				(font
					(size 0.7 0.7)
					(thickness 0.15)
				)
				(justify left bottom)
			)
		)
		(property "Description" "0R resistor in 0805 package with unspecified tolerance"
			(at 0 0 0)
			(layer "F.Fab")
			(hide yes)
			(effects
				(font
					(size 1.27 1.27)
					(thickness 0.15)
				)
			)
		)
		(property "Author" "Antmicro"
			(at 0 0 0)
			(layer "F.Fab")
			(hide yes)
			(effects
				(font
					(size 1 1)
					(thickness 0.15)
				)
			)
		)
		(property "Current" "2.5A"
			(at 0 0 0)
			(layer "F.Fab")
			(hide yes)
			(effects
				(font
					(size 1 1)
					(thickness 0.15)
				)
			)
		)
		(property "License" "Apache-2.0"
			(at 0 0 0)
			(layer "F.Fab")
			(hide yes)
			(effects
				(font
					(size 1 1)
					(thickness 0.15)
				)
			)
		)
		(property "MPN" "CRCW08050000Z0EA"
			(at 0 0 0)
			(layer "F.Fab")
			(hide yes)
			(effects
				(font
					(size 1 1)
					(thickness 0.15)
				)
			)
		)
		(property "Manufacturer" "Vishay"
			(at 0 0 0)
			(layer "F.Fab")
			(hide yes)
			(effects
				(font
					(size 1 1)
					(thickness 0.15)
				)
			)
		)
		(property "Tolerance" ""
			(at 0 0 0)
			(layer "F.Fab")
			(hide yes)
			(effects
				(font
					(size 1 1)
					(thickness 0.15)
				)
			)
		)
		(property "Val" "0R"
			(at 0 0 0)
			(layer "F.Fab")
			(hide yes)
			(effects
				(font
					(size 1 1)
					(thickness 0.15)
				)
			)
		)
		(sheetname "Supply")
		(sheetfile "supply.kicad_sch")
		(attr smd)
		(fp_line
			(start -0.32 0.699)
			(end 0.28 0.699)
			(stroke
				(width 0.15)
				(type solid)
			)
			(layer "F.SilkS")
		)
		(fp_line
			(start -0.3 -0.701)
			(end 0.298 -0.701)
			(stroke
				(width 0.15)
				(type solid)
			)
			(layer "F.SilkS")
		)
		(fp_rect
			(start -1.75 -0.85)
			(end 1.75 0.85)
			(stroke
				(width 0.05)
				(type solid)
			)
			(fill no)
			(layer "F.CrtYd")
		)
		(fp_line
			(start -0.951 -0.682)
			(end 0.949 -0.682)
			(stroke
				(width 0.15)
				(type solid)
			)
			(layer "F.Fab")
		)
		(fp_line
			(start -0.951 -0.677)
			(end -0.951 0.675)
			(stroke
				(width 0.15)
				(type solid)
			)
			(layer "F.Fab")
		)
		(fp_line
			(start -0.951 0.68)
			(end 0.949 0.68)
			(stroke
				(width 0.15)
				(type solid)
			)
			(layer "F.Fab")
		)
		(fp_line
			(start 0.949 -0.677)
			(end 0.949 0.675)
			(stroke
				(width 0.15)
				(type solid)
			)
			(layer "F.Fab")
		)
		(pad "1" smd roundrect
			(at -1.1 -0.001)
			(size 1 1.4)
			(layers "F.Cu" "F.Mask" "F.Paste")
			(roundrect_rratio 0.15)
			(net 583 "/Supply/1V8_REG")
			(pintype "passive")
		)
		(pad "2" smd roundrect
			(at 1.1 -0.001)
			(size 1 1.4)
			(layers "F.Cu" "F.Mask" "F.Paste")
			(roundrect_rratio 0.15)
			(net 460 "1V8_SYS")
			(pintype "passive")
		)
	)
	(footprint "antmicro-footprints:R_0402_1005Metric"
		(layer "F.Cu")
		(at 140.1825 89.599)
		(descr "Resistor SMD 0402")
		(tags "resistor SMD 0402")
		(property "Reference" "R101"
			(at -3.6825 -0.799 0)
			(layer "F.SilkS")
			(effects
				(font
					(size 0.7 0.7)
					(thickness 0.15)
				)
				(justify left bottom)
			)
		)
		(property "Value" "R_330R_0402"
			(at 0 1.4 0)
			(layer "F.Fab")
			(effects
				(font
					(size 0.7 0.7)
					(thickness 0.15)
				)
				(justify left bottom)
			)
		)
		(property "Description" "330R resistor in 0402 package with 1% tolerance"
			(at 0 0 0)
			(layer "F.Fab")
			(hide yes)
			(effects
				(font
					(size 1.27 1.27)
					(thickness 0.15)
				)
			)
		)
		(property "Author" "Antmicro"
			(at 0 0 0)
			(layer "F.Fab")
			(hide yes)
			(effects
				(font
					(size 1 1)
					(thickness 0.15)
				)
			)
		)
		(property "License" "Apache-2.0"
			(at 0 0 0)
			(layer "F.Fab")
			(hide yes)
			(effects
				(font
					(size 1 1)
					(thickness 0.15)
				)
			)
		)
		(property "MPN" "CR0402-FX-3300GLF"
			(at 0 0 0)
			(layer "F.Fab")
			(hide yes)
			(effects
				(font
					(size 1 1)
					(thickness 0.15)
				)
			)
		)
		(property "Manufacturer" "Bourns"
			(at 0 0 0)
			(layer "F.Fab")
			(hide yes)
			(effects
				(font
					(size 1 1)
					(thickness 0.15)
				)
			)
		)
		(property "Tolerance" "1%"
			(at 0 0 0)
			(layer "F.Fab")
			(hide yes)
			(effects
				(font
					(size 1 1)
					(thickness 0.15)
				)
			)
		)
		(property "Val" "330R"
			(at 0 0 0)
			(layer "F.Fab")
			(hide yes)
			(effects
				(font
					(size 1 1)
					(thickness 0.15)
				)
			)
		)
		(sheetname "Supply")
		(sheetfile "supply.kicad_sch")
		(attr smd)
		(fp_rect
			(start -0.93 -0.47)
			(end 0.93 0.47)
			(stroke
				(width 0.05)
				(type solid)
			)
			(fill no)
			(layer "F.CrtYd")
		)
		(fp_rect
			(start -0.5 -0.25)
			(end 0.5 0.25)
			(stroke
				(width 0.15)
				(type solid)
			)
			(fill no)
			(layer "F.Fab")
		)
		(pad "1" smd roundrect
			(at -0.485 0)
			(size 0.59 0.64)
			(layers "F.Cu" "F.Mask" "F.Paste")
			(roundrect_rratio 0.25)
			(net 553 "Net-(PWR2-Pad2)")
			(pintype "passive")
		)
		(pad "2" smd roundrect
			(at 0.485 0)
			(size 0.59 0.64)
			(layers "F.Cu" "F.Mask" "F.Paste")
			(roundrect_rratio 0.25)
			(net 234 "Net-(Q8-D)")
			(pintype "passive")
		)
	)
	(footprint "antmicro-footprints:R_0402_1005Metric"
		(layer "F.Cu")
		(at 137.1 64.7 180)
		(descr "Resistor SMD 0402")
		(tags "resistor SMD 0402")
		(property "Reference" "R154"
			(at 0.9 -2.3 180)
			(layer "F.SilkS")
			(effects
				(font
					(size 0.7 0.7)
					(thickness 0.15)
				)
				(justify left bottom)
			)
		)
		(property "Value" "R_10R_0402"
			(at 0 1.4 180)
			(layer "F.Fab")
			(effects
				(font
					(size 0.7 0.7)
					(thickness 0.15)
				)
				(justify left bottom)
			)
		)
		(property "Description" "10R resistor in 0402 package with 1% tolerance"
			(at 0 0 180)
			(layer "F.Fab")
			(hide yes)
			(effects
				(font
					(size 1.27 1.27)
					(thickness 0.15)
				)
			)
		)
		(property "Author" "Antmicro"
			(at 274.2 129.4 0)
			(layer "F.Fab")
			(hide yes)
			(effects
				(font
					(size 1 1)
					(thickness 0.15)
				)
			)
		)
		(property "License" "Apache-2.0"
			(at 274.2 129.4 0)
			(layer "F.Fab")
			(hide yes)
			(effects
				(font
					(size 1 1)
					(thickness 0.15)
				)
			)
		)
		(property "MPN" "CR0402-FX-10R0GLF"
			(at 274.2 129.4 0)
			(layer "F.Fab")
			(hide yes)
			(effects
				(font
					(size 1 1)
					(thickness 0.15)
				)
			)
		)
		(property "Manufacturer" "Bourns"
			(at 274.2 129.4 0)
			(layer "F.Fab")
			(hide yes)
			(effects
				(font
					(size 1 1)
					(thickness 0.15)
				)
			)
		)
		(property "Tolerance" "1%"
			(at 274.2 129.4 0)
			(layer "F.Fab")
			(hide yes)
			(effects
				(font
					(size 1 1)
					(thickness 0.15)
				)
			)
		)
		(property "Val" "10R"
			(at 274.2 129.4 0)
			(layer "F.Fab")
			(hide yes)
			(effects
				(font
					(size 1 1)
					(thickness 0.15)
				)
			)
		)
		(sheetname "Supply")
		(sheetfile "supply.kicad_sch")
		(attr smd)
		(fp_rect
			(start -0.93 -0.47)
			(end 0.93 0.47)
			(stroke
				(width 0.05)
				(type solid)
			)
			(fill no)
			(layer "F.CrtYd")
		)
		(fp_rect
			(start -0.5 -0.25)
			(end 0.5 0.25)
			(stroke
				(width 0.15)
				(type solid)
			)
			(fill no)
			(layer "F.Fab")
		)
		(pad "1" smd roundrect
			(at -0.485 0 180)
			(size 0.59 0.64)
			(layers "F.Cu" "F.Mask" "F.Paste")
			(roundrect_rratio 0.25)
			(net 633 "/Supply/0V6_REG")
			(pintype "passive")
		)
		(pad "2" smd roundrect
			(at 0.485 0 180)
			(size 0.59 0.64)
			(layers "F.Cu" "F.Mask" "F.Paste")
			(roundrect_rratio 0.25)
			(net 635 "/Supply/0V6_FB")
			(pintype "passive")
		)
	)
	(footprint "antmicro-footprints:C_0603_1608Metric"
		(layer "F.Cu")
		(at 128.6 66.8 180)
		(descr "Capacitor SMD 0603")
		(tags "capacitor 0603")
		(property "Reference" "C189"
			(at 3.9 -0.4 180)
			(layer "F.SilkS")
			(effects
				(font
					(size 0.7 0.7)
					(thickness 0.15)
				)
				(justify left bottom)
			)
		)
		(property "Value" "C_22u_0603"
			(at 0 1.6 180)
			(layer "F.Fab")
			(effects
				(font
					(size 0.7 0.7)
					(thickness 0.15)
				)
				(justify left bottom)
			)
		)
		(property "Description" " "
			(at 0 0 180)
			(layer "F.Fab")
			(hide yes)
			(effects
				(font
					(size 1.27 1.27)
					(thickness 0.15)
				)
			)
		)
		(property "Author" "Antmicro"
			(at 257.2 133.6 0)
			(layer "F.Fab")
			(hide yes)
			(effects
				(font
					(size 1 1)
					(thickness 0.15)
				)
			)
		)
		(property "Dielectric" ""
			(at 257.2 133.6 0)
			(layer "F.Fab")
			(hide yes)
			(effects
				(font
					(size 1 1)
					(thickness 0.15)
				)
			)
		)
		(property "License" "Apache-2.0"
			(at 257.2 133.6 0)
			(layer "F.Fab")
			(hide yes)
			(effects
				(font
					(size 1 1)
					(thickness 0.15)
				)
			)
		)
		(property "MPN" "GRM188R60J226MEA0D"
			(at 257.2 133.6 0)
			(layer "F.Fab")
			(hide yes)
			(effects
				(font
					(size 1 1)
					(thickness 0.15)
				)
			)
		)
		(property "Manufacturer" "Murata"
			(at 257.2 133.6 0)
			(layer "F.Fab")
			(hide yes)
			(effects
				(font
					(size 1 1)
					(thickness 0.15)
				)
			)
		)
		(property "Val" "22u"
			(at 257.2 133.6 0)
			(layer "F.Fab")
			(hide yes)
			(effects
				(font
					(size 1 1)
					(thickness 0.15)
				)
			)
		)
		(property "Voltage" ""
			(at 257.2 133.6 0)
			(layer "F.Fab")
			(hide yes)
			(effects
				(font
					(size 1 1)
					(thickness 0.15)
				)
			)
		)
		(sheetname "Supply")
		(sheetfile "supply.kicad_sch")
		(attr exclude_from_pos_files exclude_from_bom dnp)
		(fp_line
			(start -0.3 0.3)
			(end 0.3 0.3)
			(stroke
				(width 0.15)
				(type solid)
			)
			(layer "F.SilkS")
		)
		(fp_line
			(start -0.3 -0.3)
			(end 0.3 -0.3)
			(stroke
				(width 0.15)
				(type solid)
			)
			(layer "F.SilkS")
		)
		(fp_rect
			(start -1.24 -0.7)
			(end 1.24 0.7)
			(stroke
				(width 0.05)
				(type solid)
			)
			(fill no)
			(layer "F.CrtYd")
		)
		(fp_rect
			(start -0.8 -0.4)
			(end 0.8 0.4)
			(stroke
				(width 0.15)
				(type solid)
			)
			(fill no)
			(layer "F.Fab")
		)
		(pad "1" smd roundrect
			(at -0.7 0 180)
			(size 0.6 0.8)
			(layers "F.Cu" "F.Mask" "F.Paste")
			(roundrect_rratio 0.2)
			(net 551 "/Supply/VDD1V8")
			(pintype "passive")
		)
		(pad "2" smd roundrect
			(at 0.7 0 180)
			(size 0.6 0.8)
			(layers "F.Cu" "F.Mask" "F.Paste")
			(roundrect_rratio 0.2)
			(net 5 "GND")
			(pintype "passive")
		)
	)
	(footprint "antmicro-footprints:C_0603_1608Metric"
		(layer "F.Cu")
		(at 136.7 54.9)
		(descr "Capacitor SMD 0603")
		(tags "capacitor 0603")
		(property "Reference" "C198"
			(at 1 0.4 0)
			(layer "F.SilkS")
			(effects
				(font
					(size 0.7 0.7)
					(thickness 0.15)
				)
				(justify left bottom)
			)
		)
		(property "Value" "C_22u_0603"
			(at 0 1.6 0)
			(layer "F.Fab")
			(effects
				(font
					(size 0.7 0.7)
					(thickness 0.15)
				)
				(justify left bottom)
			)
		)
		(property "Description" " "
			(at 0 0 0)
			(layer "F.Fab")
			(hide yes)
			(effects
				(font
					(size 1.27 1.27)
					(thickness 0.15)
				)
			)
		)
		(property "Author" "Antmicro"
			(at 0 0 0)
			(layer "F.Fab")
			(hide yes)
			(effects
				(font
					(size 1 1)
					(thickness 0.15)
				)
			)
		)
		(property "Dielectric" ""
			(at 0 0 0)
			(layer "F.Fab")
			(hide yes)
			(effects
				(font
					(size 1 1)
					(thickness 0.15)
				)
			)
		)
		(property "License" "Apache-2.0"
			(at 0 0 0)
			(layer "F.Fab")
			(hide yes)
			(effects
				(font
					(size 1 1)
					(thickness 0.15)
				)
			)
		)
		(property "MPN" "GRM188R60J226MEA0D"
			(at 0 0 0)
			(layer "F.Fab")
			(hide yes)
			(effects
				(font
					(size 1 1)
					(thickness 0.15)
				)
			)
		)
		(property "Manufacturer" "Murata"
			(at 0 0 0)
			(layer "F.Fab")
			(hide yes)
			(effects
				(font
					(size 1 1)
					(thickness 0.15)
				)
			)
		)
		(property "Val" "22u"
			(at 0 0 0)
			(layer "F.Fab")
			(hide yes)
			(effects
				(font
					(size 1 1)
					(thickness 0.15)
				)
			)
		)
		(property "Voltage" ""
			(at 0 0 0)
			(layer "F.Fab")
			(hide yes)
			(effects
				(font
					(size 1 1)
					(thickness 0.15)
				)
			)
		)
		(sheetname "Supply")
		(sheetfile "supply.kicad_sch")
		(attr exclude_from_pos_files exclude_from_bom dnp)
		(fp_line
			(start -0.3 -0.3)
			(end 0.3 -0.3)
			(stroke
				(width 0.15)
				(type solid)
			)
			(layer "F.SilkS")
		)
		(fp_line
			(start -0.3 0.3)
			(end 0.3 0.3)
			(stroke
				(width 0.15)
				(type solid)
			)
			(layer "F.SilkS")
		)
		(fp_rect
			(start -1.24 -0.7)
			(end 1.24 0.7)
			(stroke
				(width 0.05)
				(type solid)
			)
			(fill no)
			(layer "F.CrtYd")
		)
		(fp_rect
			(start -0.8 -0.4)
			(end 0.8 0.4)
			(stroke
				(width 0.15)
				(type solid)
			)
			(fill no)
			(layer "F.Fab")
		)
		(pad "1" smd roundrect
			(at -0.7 0)
			(size 0.6 0.8)
			(layers "F.Cu" "F.Mask" "F.Paste")
			(roundrect_rratio 0.2)
			(net 550 "VDD1V1")
			(pintype "passive")
		)
		(pad "2" smd roundrect
			(at 0.7 0)
			(size 0.6 0.8)
			(layers "F.Cu" "F.Mask" "F.Paste")
			(roundrect_rratio 0.2)
			(net 5 "GND")
			(pintype "passive")
		)
	)
	(footprint "antmicro-footprints:C_0603_1608Metric"
		(layer "F.Cu")
		(at 128.925 52.725 90)
		(descr "Capacitor SMD 0603")
		(tags "capacitor 0603")
		(property "Reference" "C195"
			(at 1.025 0.275 90)
			(layer "F.SilkS")
			(effects
				(font
					(size 0.7 0.7)
					(thickness 0.15)
				)
				(justify left bottom)
			)
		)
		(property "Value" "C_22u_0603"
			(at 0 1.6 90)
			(layer "F.Fab")
			(effects
				(font
					(size 0.7 0.7)
					(thickness 0.15)
				)
				(justify left bottom)
			)
		)
		(property "Description" " "
			(at 0 0 90)
			(layer "F.Fab")
			(hide yes)
			(effects
				(font
					(size 1.27 1.27)
					(thickness 0.15)
				)
			)
		)
		(property "Author" "Antmicro"
			(at 181.65 -76.2 0)
			(layer "F.Fab")
			(hide yes)
			(effects
				(font
					(size 1 1)
					(thickness 0.15)
				)
			)
		)
		(property "Dielectric" ""
			(at 181.65 -76.2 0)
			(layer "F.Fab")
			(hide yes)
			(effects
				(font
					(size 1 1)
					(thickness 0.15)
				)
			)
		)
		(property "License" "Apache-2.0"
			(at 181.65 -76.2 0)
			(layer "F.Fab")
			(hide yes)
			(effects
				(font
					(size 1 1)
					(thickness 0.15)
				)
			)
		)
		(property "MPN" "GRM188R60J226MEA0D"
			(at 181.65 -76.2 0)
			(layer "F.Fab")
			(hide yes)
			(effects
				(font
					(size 1 1)
					(thickness 0.15)
				)
			)
		)
		(property "Manufacturer" "Murata"
			(at 181.65 -76.2 0)
			(layer "F.Fab")
			(hide yes)
			(effects
				(font
					(size 1 1)
					(thickness 0.15)
				)
			)
		)
		(property "Val" "22u"
			(at 181.65 -76.2 0)
			(layer "F.Fab")
			(hide yes)
			(effects
				(font
					(size 1 1)
					(thickness 0.15)
				)
			)
		)
		(property "Voltage" ""
			(at 181.65 -76.2 0)
			(layer "F.Fab")
			(hide yes)
			(effects
				(font
					(size 1 1)
					(thickness 0.15)
				)
			)
		)
		(sheetname "Supply")
		(sheetfile "supply.kicad_sch")
		(attr exclude_from_pos_files exclude_from_bom dnp)
		(fp_line
			(start -0.3 -0.3)
			(end 0.3 -0.3)
			(stroke
				(width 0.15)
				(type solid)
			)
			(layer "F.SilkS")
		)
		(fp_line
			(start -0.3 0.3)
			(end 0.3 0.3)
			(stroke
				(width 0.15)
				(type solid)
			)
			(layer "F.SilkS")
		)
		(fp_rect
			(start -1.24 -0.7)
			(end 1.24 0.7)
			(stroke
				(width 0.05)
				(type solid)
			)
			(fill no)
			(layer "F.CrtYd")
		)
		(fp_rect
			(start -0.8 -0.4)
			(end 0.8 0.4)
			(stroke
				(width 0.15)
				(type solid)
			)
			(fill no)
			(layer "F.Fab")
		)
		(pad "1" smd roundrect
			(at -0.7 0 90)
			(size 0.6 0.8)
			(layers "F.Cu" "F.Mask" "F.Paste")
			(roundrect_rratio 0.2)
			(net 550 "VDD1V1")
			(pintype "passive")
		)
		(pad "2" smd roundrect
			(at 0.7 0 90)
			(size 0.6 0.8)
			(layers "F.Cu" "F.Mask" "F.Paste")
			(roundrect_rratio 0.2)
			(net 5 "GND")
			(pintype "passive")
		)
	)
	(footprint "antmicro-footprints:C_0402_1005Metric"
		(layer "F.Cu")
		(at 111.147806 85.774 180)
		(descr "Capacitor SMD 0402")
		(tags "capacitor SMD 0402")
		(property "Reference" "C173"
			(at 3.647806 -0.326 180)
			(layer "F.SilkS")
			(effects
				(font
					(size 0.7 0.7)
					(thickness 0.15)
				)
				(justify left bottom)
			)
		)
		(property "Value" "C_22u_0402"
			(at 0 1.4 180)
			(layer "F.Fab")
			(effects
				(font
					(size 0.7 0.7)
					(thickness 0.15)
				)
				(justify left bottom)
			)
		)
		(property "Description" " "
			(at 0 0 180)
			(layer "F.Fab")
			(hide yes)
			(effects
				(font
					(size 1.27 1.27)
					(thickness 0.15)
				)
			)
		)
		(property "Author" "Antmicro"
			(at 222.295612 171.548 0)
			(layer "F.Fab")
			(hide yes)
			(effects
				(font
					(size 1 1)
					(thickness 0.15)
				)
			)
		)
		(property "Dielectric" ""
			(at 222.295612 171.548 0)
			(layer "F.Fab")
			(hide yes)
			(effects
				(font
					(size 1 1)
					(thickness 0.15)
				)
			)
		)
		(property "License" "Apache-2.0"
			(at 222.295612 171.548 0)
			(layer "F.Fab")
			(hide yes)
			(effects
				(font
					(size 1 1)
					(thickness 0.15)
				)
			)
		)
		(property "MPN" "04024W226MAT2A"
			(at 222.295612 171.548 0)
			(layer "F.Fab")
			(hide yes)
			(effects
				(font
					(size 1 1)
					(thickness 0.15)
				)
			)
		)
		(property "Manufacturer" "AVX"
			(at 222.295612 171.548 0)
			(layer "F.Fab")
			(hide yes)
			(effects
				(font
					(size 1 1)
					(thickness 0.15)
				)
			)
		)
		(property "Val" "22u"
			(at 222.295612 171.548 0)
			(layer "F.Fab")
			(hide yes)
			(effects
				(font
					(size 1 1)
					(thickness 0.15)
				)
			)
		)
		(property "Voltage" ""
			(at 222.295612 171.548 0)
			(layer "F.Fab")
			(hide yes)
			(effects
				(font
					(size 1 1)
					(thickness 0.15)
				)
			)
		)
		(sheetname "Supply")
		(sheetfile "supply.kicad_sch")
		(attr smd)
		(fp_rect
			(start -0.94 -0.47)
			(end 0.94 0.47)
			(stroke
				(width 0.05)
				(type solid)
			)
			(fill no)
			(layer "F.CrtYd")
		)
		(fp_rect
			(start -0.499 -0.249)
			(end 0.499 0.249)
			(stroke
				(width 0.15)
				(type solid)
			)
			(fill no)
			(layer "F.Fab")
		)
		(pad "1" smd roundrect
			(at -0.484 0 180)
			(size 0.59 0.64)
			(layers "F.Cu" "F.Mask" "F.Paste")
			(roundrect_rratio 0.25)
			(net 583 "/Supply/1V8_REG")
			(pintype "passive")
		)
		(pad "2" smd roundrect
			(at 0.484 0 180)
			(size 0.59 0.64)
			(layers "F.Cu" "F.Mask" "F.Paste")
			(roundrect_rratio 0.25)
			(net 5 "GND")
			(pintype "passive")
		)
	)
	(footprint "antmicro-footprints:R_0402_1005Metric"
		(layer "F.Cu")
		(at 118.275 100.549 180)
		(descr "Resistor SMD 0402")
		(tags "resistor SMD 0402")
		(property "Reference" "R128"
			(at 0.875 2.549 180)
			(layer "F.SilkS")
			(effects
				(font
					(size 0.7 0.7)
					(thickness 0.15)
				)
				(justify left bottom)
			)
		)
		(property "Value" "R_0R_0402"
			(at 0 1.4 180)
			(layer "F.Fab")
			(effects
				(font
					(size 0.7 0.7)
					(thickness 0.15)
				)
				(justify left bottom)
			)
		)
		(property "Description" "0R resistor in 0402 package with unspecified tolerance"
			(at 0 0 180)
			(layer "F.Fab")
			(hide yes)
			(effects
				(font
					(size 1.27 1.27)
					(thickness 0.15)
				)
			)
		)
		(property "Author" "Antmicro"
			(at 236.55 201.098 0)
			(layer "F.Fab")
			(hide yes)
			(effects
				(font
					(size 1 1)
					(thickness 0.15)
				)
			)
		)
		(property "Current" "1A"
			(at 236.55 201.098 0)
			(layer "F.Fab")
			(hide yes)
			(effects
				(font
					(size 1 1)
					(thickness 0.15)
				)
			)
		)
		(property "License" "Apache-2.0"
			(at 236.55 201.098 0)
			(layer "F.Fab")
			(hide yes)
			(effects
				(font
					(size 1 1)
					(thickness 0.15)
				)
			)
		)
		(property "MPN" "ERJ2GE0R00X"
			(at 236.55 201.098 0)
			(layer "F.Fab")
			(hide yes)
			(effects
				(font
					(size 1 1)
					(thickness 0.15)
				)
			)
		)
		(property "Manufacturer" "Panasonic"
			(at 236.55 201.098 0)
			(layer "F.Fab")
			(hide yes)
			(effects
				(font
					(size 1 1)
					(thickness 0.15)
				)
			)
		)
		(property "Tolerance" ""
			(at 236.55 201.098 0)
			(layer "F.Fab")
			(hide yes)
			(effects
				(font
					(size 1 1)
					(thickness 0.15)
				)
			)
		)
		(property "Val" "0R"
			(at 236.55 201.098 0)
			(layer "F.Fab")
			(hide yes)
			(effects
				(font
					(size 1 1)
					(thickness 0.15)
				)
			)
		)
		(sheetname "Supply")
		(sheetfile "supply.kicad_sch")
		(attr smd)
		(fp_rect
			(start -0.93 -0.47)
			(end 0.93 0.47)
			(stroke
				(width 0.05)
				(type solid)
			)
			(fill no)
			(layer "F.CrtYd")
		)
		(fp_rect
			(start -0.5 -0.25)
			(end 0.5 0.25)
			(stroke
				(width 0.15)
				(type solid)
			)
			(fill no)
			(layer "F.Fab")
		)
		(pad "1" smd roundrect
			(at -0.485 0 180)
			(size 0.59 0.64)
			(layers "F.Cu" "F.Mask" "F.Paste")
			(roundrect_rratio 0.25)
			(net 5 "GND")
			(pintype "passive")
		)
		(pad "2" smd roundrect
			(at 0.485 0 180)
			(size 0.59 0.64)
			(layers "F.Cu" "F.Mask" "F.Paste")
			(roundrect_rratio 0.25)
			(net 617 "/Supply/3V3_MODE")
			(pintype "passive")
		)
	)
	(footprint "antmicro-footprints:C_Pol_EIA-A"
		(layer "F.Cu")
		(at 151.84 84.21 180)
		(descr "Capacitor SMD KEMET_A")
		(tags "capacitor SMD KEMET_A")
		(property "Reference" "C86"
			(at 1.04 1.01 180)
			(layer "F.SilkS")
			(effects
				(font
					(size 0.7 0.7)
					(thickness 0.15)
				)
				(justify left bottom)
			)
		)
		(property "Value" "C_100u_KEMET_A"
			(at 0 2 180)
			(layer "F.Fab")
			(effects
				(font
					(size 0.7 0.7)
					(thickness 0.15)
				)
				(justify left bottom)
			)
		)
		(property "Description" " "
			(at 0 0 180)
			(layer "F.Fab")
			(hide yes)
			(effects
				(font
					(size 1.27 1.27)
					(thickness 0.15)
				)
			)
		)
		(property "Author" "Antmicro"
			(at 303.68 168.42 0)
			(layer "F.Fab")
			(hide yes)
			(effects
				(font
					(size 1 1)
					(thickness 0.15)
				)
			)
		)
		(property "Dielectric" ""
			(at 303.68 168.42 0)
			(layer "F.Fab")
			(hide yes)
			(effects
				(font
					(size 1 1)
					(thickness 0.15)
				)
			)
		)
		(property "License" "Apache-2.0"
			(at 303.68 168.42 0)
			(layer "F.Fab")
			(hide yes)
			(effects
				(font
					(size 1 1)
					(thickness 0.15)
				)
			)
		)
		(property "MPN" "298D107X06R3A2T"
			(at 303.68 168.42 0)
			(layer "F.Fab")
			(hide yes)
			(effects
				(font
					(size 1 1)
					(thickness 0.15)
				)
			)
		)
		(property "Manufacturer" "Vishay"
			(at 303.68 168.42 0)
			(layer "F.Fab")
			(hide yes)
			(effects
				(font
					(size 1 1)
					(thickness 0.15)
				)
			)
		)
		(property "Val" "100u"
			(at 303.68 168.42 0)
			(layer "F.Fab")
			(hide yes)
			(effects
				(font
					(size 1 1)
					(thickness 0.15)
				)
			)
		)
		(property "Voltage" ""
			(at 303.68 168.42 0)
			(layer "F.Fab")
			(hide yes)
			(effects
				(font
					(size 1 1)
					(thickness 0.15)
				)
			)
		)
		(sheetname "FPGA power")
		(sheetfile "fpga-power.kicad_sch")
		(attr smd)
		(fp_line
			(start 1.5 0.85)
			(end 1.2 0.85)
			(stroke
				(width 0.12)
				(type solid)
			)
			(layer "F.SilkS")
		)
		(fp_line
			(start 1.5 0.7)
			(end 1.5 0.85)
			(stroke
				(width 0.12)
				(type solid)
			)
			(layer "F.SilkS")
		)
		(fp_line
			(start 1.5 -0.7)
			(end 1.5 -0.85)
			(stroke
				(width 0.12)
				(type solid)
			)
			(layer "F.SilkS")
		)
		(fp_line
			(start 1.5 -0.85)
			(end 1.2 -0.85)
			(stroke
				(width 0.12)
				(type solid)
			)
			(layer "F.SilkS")
		)
		(fp_line
			(start -1.5 0.85)
			(end -1.2 0.85)
			(stroke
				(width 0.12)
				(type solid)
			)
			(layer "F.SilkS")
		)
		(fp_line
			(start -1.5 0.7)
			(end -1.5 0.85)
			(stroke
				(width 0.12)
				(type solid)
			)
			(layer "F.SilkS")
		)
		(fp_line
			(start -1.5 -0.7)
			(end -1.5 -0.85)
			(stroke
				(width 0.12)
				(type solid)
			)
			(layer "F.SilkS")
		)
		(fp_line
			(start -1.5 -0.85)
			(end -1.2 -0.85)
			(stroke
				(width 0.12)
				(type solid)
			)
			(layer "F.SilkS")
		)
		(fp_line
			(start -1.775 -0.975)
			(end -1.775 -0.675)
			(stroke
				(width 0.12)
				(type solid)
			)
			(layer "F.SilkS")
		)
		(fp_line
			(start -1.925 -0.825)
			(end -1.625 -0.825)
			(stroke
				(width 0.12)
				(type solid)
			)
			(layer "F.SilkS")
		)
		(fp_rect
			(start -1.9 -1.05)
			(end 1.9 1.05)
			(stroke
				(width 0.05)
				(type solid)
			)
			(fill no)
			(layer "F.CrtYd")
		)
		(fp_rect
			(start -1.601 -0.802)
			(end 1.6 0.8)
			(stroke
				(width 0.1)
				(type solid)
			)
			(fill no)
			(layer "F.Fab")
		)
		(pad "1" smd rect
			(at -1.2 0 180)
			(size 1.2 1.2)
			(layers "F.Cu" "F.Mask" "F.Paste")
			(net 465 "1V0_SYS")
			(pintype "passive")
		)
		(pad "2" smd rect
			(at 1.2 0 180)
			(size 1.2 1.2)
			(layers "F.Cu" "F.Mask" "F.Paste")
			(net 5 "GND")
			(pintype "passive")
		)
	)
	(footprint "antmicro-footprints:R_0402_1005Metric"
		(layer "F.Cu")
		(at 137.6 59.7)
		(descr "Resistor SMD 0402")
		(tags "resistor SMD 0402")
		(property "Reference" "R153"
			(at -0.9 -0.5 0)
			(layer "F.SilkS")
			(effects
				(font
					(size 0.7 0.7)
					(thickness 0.15)
				)
				(justify left bottom)
			)
		)
		(property "Value" "R_10k_0402"
			(at 0 1.4 0)
			(layer "F.Fab")
			(effects
				(font
					(size 0.7 0.7)
					(thickness 0.15)
				)
				(justify left bottom)
			)
		)
		(property "Description" "10k resistor in 0402 package with 1% tolerance"
			(at 0 0 0)
			(layer "F.Fab")
			(hide yes)
			(effects
				(font
					(size 1.27 1.27)
					(thickness 0.15)
				)
			)
		)
		(property "Author" "Antmicro"
			(at 0 0 0)
			(layer "F.Fab")
			(hide yes)
			(effects
				(font
					(size 1 1)
					(thickness 0.15)
				)
			)
		)
		(property "License" "Apache-2.0"
			(at 0 0 0)
			(layer "F.Fab")
			(hide yes)
			(effects
				(font
					(size 1 1)
					(thickness 0.15)
				)
			)
		)
		(property "MPN" "CR0402-FX-1002GLF"
			(at 0 0 0)
			(layer "F.Fab")
			(hide yes)
			(effects
				(font
					(size 1 1)
					(thickness 0.15)
				)
			)
		)
		(property "Manufacturer" "Bourns"
			(at 0 0 0)
			(layer "F.Fab")
			(hide yes)
			(effects
				(font
					(size 1 1)
					(thickness 0.15)
				)
			)
		)
		(property "Tolerance" "1%"
			(at 0 0 0)
			(layer "F.Fab")
			(hide yes)
			(effects
				(font
					(size 1 1)
					(thickness 0.15)
				)
			)
		)
		(property "Val" "10k"
			(at 0 0 0)
			(layer "F.Fab")
			(hide yes)
			(effects
				(font
					(size 1 1)
					(thickness 0.15)
				)
			)
		)
		(sheetname "Supply")
		(sheetfile "supply.kicad_sch")
		(attr smd)
		(fp_rect
			(start -0.93 -0.47)
			(end 0.93 0.47)
			(stroke
				(width 0.05)
				(type solid)
			)
			(fill no)
			(layer "F.CrtYd")
		)
		(fp_rect
			(start -0.5 -0.25)
			(end 0.5 0.25)
			(stroke
				(width 0.15)
				(type solid)
			)
			(fill no)
			(layer "F.Fab")
		)
		(pad "1" smd roundrect
			(at -0.485 0)
			(size 0.59 0.64)
			(layers "F.Cu" "F.Mask" "F.Paste")
			(roundrect_rratio 0.25)
			(net 636 "/Supply/0V6_EN")
			(pintype "passive")
		)
		(pad "2" smd roundrect
			(at 0.485 0)
			(size 0.59 0.64)
			(layers "F.Cu" "F.Mask" "F.Paste")
			(roundrect_rratio 0.25)
			(net 5 "GND")
			(pintype "passive")
		)
	)
	(footprint "antmicro-footprints:R_0402_1005Metric"
		(layer "F.Cu")
		(at 186.1 111.85 -90)
		(descr "Resistor SMD 0402")
		(tags "resistor SMD 0402")
		(property "Reference" "R152"
			(at -0.75 -0.4 270)
			(layer "F.SilkS")
			(effects
				(font
					(size 0.7 0.7)
					(thickness 0.15)
				)
				(justify left bottom)
			)
		)
		(property "Value" "R_0R_0402"
			(at 0 1.4 270)
			(layer "F.Fab")
			(effects
				(font
					(size 0.7 0.7)
					(thickness 0.15)
				)
				(justify left bottom)
			)
		)
		(property "Description" "0R resistor in 0402 package with unspecified tolerance"
			(at 0 0 270)
			(layer "F.Fab")
			(hide yes)
			(effects
				(font
					(size 1.27 1.27)
					(thickness 0.15)
				)
			)
		)
		(property "Author" "Antmicro"
			(at 74.25 297.95 0)
			(layer "F.Fab")
			(hide yes)
			(effects
				(font
					(size 1 1)
					(thickness 0.15)
				)
			)
		)
		(property "Current" "1A"
			(at 74.25 297.95 0)
			(layer "F.Fab")
			(hide yes)
			(effects
				(font
					(size 1 1)
					(thickness 0.15)
				)
			)
		)
		(property "License" "Apache-2.0"
			(at 74.25 297.95 0)
			(layer "F.Fab")
			(hide yes)
			(effects
				(font
					(size 1 1)
					(thickness 0.15)
				)
			)
		)
		(property "MPN" "ERJ2GE0R00X"
			(at 74.25 297.95 0)
			(layer "F.Fab")
			(hide yes)
			(effects
				(font
					(size 1 1)
					(thickness 0.15)
				)
			)
		)
		(property "Manufacturer" "Panasonic"
			(at 74.25 297.95 0)
			(layer "F.Fab")
			(hide yes)
			(effects
				(font
					(size 1 1)
					(thickness 0.15)
				)
			)
		)
		(property "Tolerance" ""
			(at 74.25 297.95 0)
			(layer "F.Fab")
			(hide yes)
			(effects
				(font
					(size 1 1)
					(thickness 0.15)
				)
			)
		)
		(property "Val" "0R"
			(at 74.25 297.95 0)
			(layer "F.Fab")
			(hide yes)
			(effects
				(font
					(size 1 1)
					(thickness 0.15)
				)
			)
		)
		(sheetname "Supply")
		(sheetfile "supply.kicad_sch")
		(attr smd)
		(fp_rect
			(start -0.93 -0.47)
			(end 0.93 0.47)
			(stroke
				(width 0.05)
				(type solid)
			)
			(fill no)
			(layer "F.CrtYd")
		)
		(fp_rect
			(start -0.5 -0.25)
			(end 0.5 0.25)
			(stroke
				(width 0.15)
				(type solid)
			)
			(fill no)
			(layer "F.Fab")
		)
		(pad "1" smd roundrect
			(at -0.485 0 270)
			(size 0.59 0.64)
			(layers "F.Cu" "F.Mask" "F.Paste")
			(roundrect_rratio 0.25)
			(net 5 "GND")
			(pintype "passive")
		)
		(pad "2" smd roundrect
			(at 0.485 0 270)
			(size 0.59 0.64)
			(layers "F.Cu" "F.Mask" "F.Paste")
			(roundrect_rratio 0.25)
			(net 624 "/Supply/1V2_SS{slash}TR")
			(pintype "passive")
		)
	)
	(footprint "antmicro-footprints:SOT-523"
		(layer "F.Cu")
		(at 142.3825 89.599 90)
		(property "Reference" "Q8"
			(at 0.599 -1.9825 0)
			(layer "F.SilkS")
			(effects
				(font
					(size 0.7 0.7)
					(thickness 0.15)
				)
				(justify left bottom)
			)
		)
		(property "Value" "DMG1012T-7"
			(at 0.1 1.824 90)
			(layer "F.Fab")
			(effects
				(font
					(size 0.7 0.7)
					(thickness 0.15)
				)
				(justify left bottom)
			)
		)
		(property "Author" "Antmicro"
			(at 231.9815 -52.7835 0)
			(layer "F.Fab")
			(hide yes)
			(effects
				(font
					(size 1 1)
					(thickness 0.15)
				)
			)
		)
		(property "License" "Apache-2.0"
			(at 231.9815 -52.7835 0)
			(layer "F.Fab")
			(hide yes)
			(effects
				(font
					(size 1 1)
					(thickness 0.15)
				)
			)
		)
		(property "MPN" "DMG1012T-7"
			(at 231.9815 -52.7835 0)
			(layer "F.Fab")
			(hide yes)
			(effects
				(font
					(size 1 1)
					(thickness 0.15)
				)
			)
		)
		(property "Manufacturer" "Diodes Incorporated"
			(at 231.9815 -52.7835 0)
			(layer "F.Fab")
			(hide yes)
			(effects
				(font
					(size 1 1)
					(thickness 0.15)
				)
			)
		)
		(sheetname "Supply")
		(sheetfile "supply.kicad_sch")
		(attr smd)
		(fp_line
			(start -0.277 -0.551)
			(end -0.277 -0.75)
			(stroke
				(width 0.15)
				(type solid)
			)
			(layer "F.SilkS")
		)
		(fp_line
			(start -0.725 -0.551)
			(end -0.277 -0.551)
			(stroke
				(width 0.15)
				(type solid)
			)
			(layer "F.SilkS")
		)
		(fp_line
			(start -0.927 -0.351)
			(end -0.725 -0.551)
			(stroke
				(width 0.15)
				(type solid)
			)
			(layer "F.SilkS")
		)
		(fp_line
			(start -0.927 -0.051)
			(end -0.927 -0.351)
			(stroke
				(width 0.15)
				(type solid)
			)
			(layer "F.SilkS")
		)
		(fp_circle
			(center -0.9652 0.9652)
			(end -0.9152 0.9652)
			(stroke
				(width 0.15)
				(type solid)
			)
			(fill yes)
			(layer "F.SilkS")
		)
		(fp_line
			(start 1.1 -1.16)
			(end 1.1 1.15)
			(stroke
				(width 0.05)
				(type solid)
			)
			(layer "F.CrtYd")
		)
		(fp_line
			(start -1.12 -1.16)
			(end 1.1 -1.16)
			(stroke
				(width 0.05)
				(type solid)
			)
			(layer "F.CrtYd")
		)
		(fp_line
			(start -1.12 -1.16)
			(end -1.12 1.15)
			(stroke
				(width 0.05)
				(type solid)
			)
			(layer "F.CrtYd")
		)
		(fp_line
			(start -1.12 1.15)
			(end 1.1 1.15)
			(stroke
				(width 0.05)
				(type solid)
			)
			(layer "F.CrtYd")
		)
		(fp_line
			(start 0.8 -0.425)
			(end -0.652 -0.425)
			(stroke
				(width 0.15)
				(type solid)
			)
			(layer "F.Fab")
		)
		(fp_line
			(start 0.8 -0.425)
			(end 0.8 0.424)
			(stroke
				(width 0.15)
				(type solid)
			)
			(layer "F.Fab")
		)
		(fp_line
			(start -0.652 -0.425)
			(end -0.802 -0.276)
			(stroke
				(width 0.15)
				(type solid)
			)
			(layer "F.Fab")
		)
		(fp_line
			(start -0.802 -0.276)
			(end -0.802 0.424)
			(stroke
				(width 0.15)
				(type solid)
			)
			(layer "F.Fab")
		)
		(fp_line
			(start 0.8 0.424)
			(end -0.802 0.424)
			(stroke
				(width 0.15)
				(type solid)
			)
			(layer "F.Fab")
		)
		(fp_circle
			(center -0.9652 0.9652)
			(end -0.9144 0.9652)
			(stroke
				(width 0.15)
				(type solid)
			)
			(fill no)
			(layer "F.Fab")
		)
		(pad "1" smd rect
			(at -0.5 0.65 90)
			(size 0.4 0.51)
			(layers "F.Cu" "F.Mask" "F.Paste")
			(net 602 "1V2_SYS")
			(pinfunction "G")
			(pintype "bidirectional")
		)
		(pad "2" smd rect
			(at 0.498 0.65 90)
			(size 0.4 0.51)
			(layers "F.Cu" "F.Mask" "F.Paste")
			(net 5 "GND")
			(pinfunction "S")
			(pintype "bidirectional")
		)
		(pad "3" smd rect
			(at 0 -0.652 90)
			(size 0.4 0.51)
			(layers "F.Cu" "F.Mask" "F.Paste")
			(net 234 "Net-(Q8-D)")
			(pinfunction "D")
			(pintype "bidirectional")
		)
	)
	(footprint "antmicro-footprints:WSON-8_6x8x0.5mm_P1.27mm"
		(layer "F.Cu")
		(at 174.475 117.625)
		(property "Reference" "U5"
			(at -4.275 -3.425 0)
			(layer "F.SilkS")
			(effects
				(font
					(size 0.7 0.7)
					(thickness 0.15)
				)
				(justify left bottom)
			)
		)
		(property "Value" "S25FL128LAGNFA010"
			(at 0 4.3 0)
			(layer "F.Fab")
			(effects
				(font
					(size 0.7 0.7)
					(thickness 0.15)
				)
				(justify left bottom)
			)
		)
		(property "Description" "FLASH - NOR Memory IC 128Mb (16M x 8) SPI - Quad I/O, QPI 133 MHz 8-WSON (5x6)"
			(at 0 0 0)
			(layer "F.Fab")
			(hide yes)
			(effects
				(font
					(size 1.27 1.27)
					(thickness 0.15)
				)
			)
		)
		(property "Author" "Antmicro"
			(at 0 0 0)
			(layer "F.Fab")
			(hide yes)
			(effects
				(font
					(size 1 1)
					(thickness 0.15)
				)
			)
		)
		(property "License" "Apache-2.0"
			(at 0 0 0)
			(layer "F.Fab")
			(hide yes)
			(effects
				(font
					(size 1 1)
					(thickness 0.15)
				)
			)
		)
		(property "MPN" "S25FL128LAGNFA010"
			(at 0 0 0)
			(layer "F.Fab")
			(hide yes)
			(effects
				(font
					(size 1 1)
					(thickness 0.15)
				)
			)
		)
		(property "Manufacturer" "Cypress Semiconductor"
			(at 0 0 0)
			(layer "F.Fab")
			(hide yes)
			(effects
				(font
					(size 1 1)
					(thickness 0.15)
				)
			)
		)
		(sheetname "Config SPI flash")
		(sheetfile "config-spi.kicad_sch")
		(attr smd)
		(fp_line
			(start 4 -3.2)
			(end -3.975 -3.2)
			(stroke
				(width 0.15)
				(type solid)
			)
			(layer "F.SilkS")
		)
		(fp_line
			(start 4.0005 3.2)
			(end -3.9995 3.2)
			(stroke
				(width 0.15)
				(type solid)
			)
			(layer "F.SilkS")
		)
		(fp_circle
			(center -4.2 -2.4)
			(end -4.149 -2.4)
			(stroke
				(width 0.15)
				(type solid)
			)
			(fill yes)
			(layer "F.SilkS")
		)
		(fp_rect
			(start -4.7 -3.25)
			(end 4.7 3.25)
			(stroke
				(width 0.05)
				(type solid)
			)
			(fill no)
			(layer "F.CrtYd")
		)
		(fp_line
			(start -3.9995 3.0005)
			(end -3.9995 -1.9995)
			(stroke
				(width 0.15)
				(type solid)
			)
			(layer "F.Fab")
		)
		(fp_line
			(start -3.0015 -2.9995)
			(end -3.9995 -1.9995)
			(stroke
				(width 0.15)
				(type solid)
			)
			(layer "F.Fab")
		)
		(fp_line
			(start -3.0015 -2.9995)
			(end 3.9995 -2.9995)
			(stroke
				(width 0.15)
				(type solid)
			)
			(layer "F.Fab")
		)
		(fp_line
			(start 3.9995 -2.9995)
			(end 3.9995 3.0005)
			(stroke
				(width 0.15)
				(type solid)
			)
			(layer "F.Fab")
		)
		(fp_line
			(start 3.9995 3.0005)
			(end -3.9995 3.0005)
			(stroke
				(width 0.15)
				(type solid)
			)
			(layer "F.Fab")
		)
		(pad "1" smd roundrect
			(at -3.9995 -1.9045 270)
			(size 0.4 1.3)
			(layers "F.Cu" "F.Mask" "F.Paste")
			(roundrect_rratio 0.25)
			(net 255 "Net-(U5-*CS)")
			(pinfunction "*CS")
			(pintype "input")
		)
		(pad "2" smd roundrect
			(at -3.9995 -0.6355 270)
			(size 0.4 1.3)
			(layers "F.Cu" "F.Mask" "F.Paste")
			(roundrect_rratio 0.25)
			(net 260 "Net-(U5-SO{slash}IO1)")
			(pinfunction "SO/IO1")
			(pintype "bidirectional")
		)
		(pad "3" smd roundrect
			(at -3.9995 0.6345 270)
			(size 0.4 1.3)
			(layers "F.Cu" "F.Mask" "F.Paste")
			(roundrect_rratio 0.25)
			(net 258 "Net-(U5-*WP{slash}IO2)")
			(pinfunction "*WP/IO2")
			(pintype "bidirectional")
		)
		(pad "4" smd roundrect
			(at -3.9995 1.9045 270)
			(size 0.4 1.3)
			(layers "F.Cu" "F.Mask" "F.Paste")
			(roundrect_rratio 0.25)
			(net 5 "GND")
			(pinfunction "VSS")
			(pintype "power_in")
		)
		(pad "5" smd roundrect
			(at 3.9995 1.8755 270)
			(size 0.4 1.3)
			(layers "F.Cu" "F.Mask" "F.Paste")
			(roundrect_rratio 0.25)
			(net 259 "Net-(U5-SI{slash}IO0)")
			(pinfunction "SI/IO0")
			(pintype "bidirectional")
		)
		(pad "6" smd roundrect
			(at 3.9995 0.6035 270)
			(size 0.4 1.3)
			(layers "F.Cu" "F.Mask" "F.Paste")
			(roundrect_rratio 0.25)
			(net 256 "Net-(U5-SCK)")
			(pinfunction "SCK")
			(pintype "input")
		)
		(pad "7" smd roundrect
			(at 3.9995 -0.6655 270)
			(size 0.4 1.3)
			(layers "F.Cu" "F.Mask" "F.Paste")
			(roundrect_rratio 0.25)
			(net 257 "Net-(U5-*HOLD{slash}IO3)")
			(pinfunction "*HOLD/IO3")
			(pintype "bidirectional")
		)
		(pad "8" smd roundrect
			(at 3.9995 -1.9355 270)
			(size 0.4 1.3)
			(layers "F.Cu" "F.Mask" "F.Paste")
			(roundrect_rratio 0.25)
			(net 459 "3V3_SYS")
			(pinfunction "VCC")
			(pintype "power_in")
		)
		(pad "9" smd roundrect
			(at -0.0005 -0.0005)
			(size 4.8 4.65)
			(layers "F.Cu" "F.Mask" "F.Paste")
			(roundrect_rratio 0.05)
			(chamfer_ratio 0.1)
			(chamfer top_left)
			(net 637 "unconnected-(U5-EP-Pad9)")
			(pinfunction "EP")
			(pintype "unspecified+no_connect")
		)
	)
	(footprint "antmicro-footprints:C_0402_1005Metric"
		(layer "F.Cu")
		(at 123.14 84.724 180)
		(descr "Capacitor SMD 0402")
		(tags "capacitor SMD 0402")
		(property "Reference" "C169"
			(at 1.94 2.524 180)
			(layer "F.SilkS")
			(effects
				(font
					(size 0.7 0.7)
					(thickness 0.15)
				)
				(justify left bottom)
			)
		)
		(property "Value" "C_22u_0402"
			(at 0 1.4 180)
			(layer "F.Fab")
			(effects
				(font
					(size 0.7 0.7)
					(thickness 0.15)
				)
				(justify left bottom)
			)
		)
		(property "Description" " "
			(at 0 0 180)
			(layer "F.Fab")
			(hide yes)
			(effects
				(font
					(size 1.27 1.27)
					(thickness 0.15)
				)
			)
		)
		(property "Author" "Antmicro"
			(at 246.28 169.448 0)
			(layer "F.Fab")
			(hide yes)
			(effects
				(font
					(size 1 1)
					(thickness 0.15)
				)
			)
		)
		(property "Dielectric" ""
			(at 246.28 169.448 0)
			(layer "F.Fab")
			(hide yes)
			(effects
				(font
					(size 1 1)
					(thickness 0.15)
				)
			)
		)
		(property "License" "Apache-2.0"
			(at 246.28 169.448 0)
			(layer "F.Fab")
			(hide yes)
			(effects
				(font
					(size 1 1)
					(thickness 0.15)
				)
			)
		)
		(property "MPN" "04024W226MAT2A"
			(at 246.28 169.448 0)
			(layer "F.Fab")
			(hide yes)
			(effects
				(font
					(size 1 1)
					(thickness 0.15)
				)
			)
		)
		(property "Manufacturer" "AVX"
			(at 246.28 169.448 0)
			(layer "F.Fab")
			(hide yes)
			(effects
				(font
					(size 1 1)
					(thickness 0.15)
				)
			)
		)
		(property "Val" "22u"
			(at 246.28 169.448 0)
			(layer "F.Fab")
			(hide yes)
			(effects
				(font
					(size 1 1)
					(thickness 0.15)
				)
			)
		)
		(property "Voltage" ""
			(at 246.28 169.448 0)
			(layer "F.Fab")
			(hide yes)
			(effects
				(font
					(size 1 1)
					(thickness 0.15)
				)
			)
		)
		(sheetname "Supply")
		(sheetfile "supply.kicad_sch")
		(attr smd)
		(fp_rect
			(start -0.94 -0.47)
			(end 0.94 0.47)
			(stroke
				(width 0.05)
				(type solid)
			)
			(fill no)
			(layer "F.CrtYd")
		)
		(fp_rect
			(start -0.499 -0.249)
			(end 0.499 0.249)
			(stroke
				(width 0.15)
				(type solid)
			)
			(fill no)
			(layer "F.Fab")
		)
		(pad "1" smd roundrect
			(at -0.484 0 180)
			(size 0.59 0.64)
			(layers "F.Cu" "F.Mask" "F.Paste")
			(roundrect_rratio 0.25)
			(net 587 "/Supply/1V1_REG")
			(pintype "passive")
		)
		(pad "2" smd roundrect
			(at 0.484 0 180)
			(size 0.59 0.64)
			(layers "F.Cu" "F.Mask" "F.Paste")
			(roundrect_rratio 0.25)
			(net 5 "GND")
			(pintype "passive")
		)
	)
	(footprint "antmicro-footprints:C_0603_1608Metric"
		(layer "F.Cu")
		(at 122.3 56.35 -90)
		(descr "Capacitor SMD 0603")
		(tags "capacitor 0603")
		(property "Reference" "C185"
			(at 1.45 0.6 270)
			(layer "F.SilkS")
			(effects
				(font
					(size 0.7 0.7)
					(thickness 0.15)
				)
				(justify left bottom)
			)
		)
		(property "Value" "C_10u_25V_0603"
			(at 0 1.6 270)
			(layer "F.Fab")
			(effects
				(font
					(size 0.7 0.7)
					(thickness 0.15)
				)
				(justify left bottom)
			)
		)
		(property "Description" " "
			(at 0 0 270)
			(layer "F.Fab")
			(hide yes)
			(effects
				(font
					(size 1.27 1.27)
					(thickness 0.15)
				)
			)
		)
		(property "Author" "Antmicro"
			(at 65.95 178.65 0)
			(layer "F.Fab")
			(hide yes)
			(effects
				(font
					(size 1 1)
					(thickness 0.15)
				)
			)
		)
		(property "Dielectric" ""
			(at 65.95 178.65 0)
			(layer "F.Fab")
			(hide yes)
			(effects
				(font
					(size 1 1)
					(thickness 0.15)
				)
			)
		)
		(property "License" "Apache-2.0"
			(at 65.95 178.65 0)
			(layer "F.Fab")
			(hide yes)
			(effects
				(font
					(size 1 1)
					(thickness 0.15)
				)
			)
		)
		(property "MPN" "C1608X5R1E106M080AC"
			(at 65.95 178.65 0)
			(layer "F.Fab")
			(hide yes)
			(effects
				(font
					(size 1 1)
					(thickness 0.15)
				)
			)
		)
		(property "Manufacturer" "TDK"
			(at 65.95 178.65 0)
			(layer "F.Fab")
			(hide yes)
			(effects
				(font
					(size 1 1)
					(thickness 0.15)
				)
			)
		)
		(property "Val" "10u/25V"
			(at 65.95 178.65 0)
			(layer "F.Fab")
			(hide yes)
			(effects
				(font
					(size 1 1)
					(thickness 0.15)
				)
			)
		)
		(property "Voltage" ""
			(at 65.95 178.65 0)
			(layer "F.Fab")
			(hide yes)
			(effects
				(font
					(size 1 1)
					(thickness 0.15)
				)
			)
		)
		(sheetname "Supply")
		(sheetfile "supply.kicad_sch")
		(attr exclude_from_pos_files exclude_from_bom dnp)
		(fp_line
			(start -0.3 0.3)
			(end 0.3 0.3)
			(stroke
				(width 0.15)
				(type solid)
			)
			(layer "F.SilkS")
		)
		(fp_line
			(start -0.3 -0.3)
			(end 0.3 -0.3)
			(stroke
				(width 0.15)
				(type solid)
			)
			(layer "F.SilkS")
		)
		(fp_rect
			(start -1.24 -0.7)
			(end 1.24 0.7)
			(stroke
				(width 0.05)
				(type solid)
			)
			(fill no)
			(layer "F.CrtYd")
		)
		(fp_rect
			(start -0.8 -0.4)
			(end 0.8 0.4)
			(stroke
				(width 0.15)
				(type solid)
			)
			(fill no)
			(layer "F.Fab")
		)
		(pad "1" smd roundrect
			(at -0.7 0 270)
			(size 0.6 0.8)
			(layers "F.Cu" "F.Mask" "F.Paste")
			(roundrect_rratio 0.2)
			(net 224 "VIN")
			(pintype "passive")
		)
		(pad "2" smd roundrect
			(at 0.7 0 270)
			(size 0.6 0.8)
			(layers "F.Cu" "F.Mask" "F.Paste")
			(roundrect_rratio 0.2)
			(net 5 "GND")
			(pintype "passive")
		)
	)
	(footprint "antmicro-footprints:TP_SMD_1mm"
		(layer "F.Cu")
		(at 144.7 87.599)
		(property "Reference" "TP16"
			(at -1.4 -5.861996 0)
			(layer "F.SilkS")
			(effects
				(font
					(size 0.7 0.7)
					(thickness 0.15)
				)
				(justify left bottom)
			)
		)
		(property "Value" "TP_1mm_SMD"
			(at 0 1.4 0)
			(layer "F.Fab")
			(effects
				(font
					(size 0.7 0.7)
					(thickness 0.15)
				)
				(justify left bottom)
			)
		)
		(property "Description" "Test Point 1mm"
			(at 0 0 0)
			(layer "F.Fab")
			(hide yes)
			(effects
				(font
					(size 1.27 1.27)
					(thickness 0.15)
				)
			)
		)
		(property "Author" "Antmicro"
			(at 0 0 0)
			(layer "F.Fab")
			(hide yes)
			(effects
				(font
					(size 1 1)
					(thickness 0.15)
				)
			)
		)
		(property "License" "Apache-2.0"
			(at 0 0 0)
			(layer "F.Fab")
			(hide yes)
			(effects
				(font
					(size 1 1)
					(thickness 0.15)
				)
			)
		)
		(property "MPN" ""
			(at 0 0 0)
			(layer "F.Fab")
			(hide yes)
			(effects
				(font
					(size 1 1)
					(thickness 0.15)
				)
			)
		)
		(property "Manufacturer" ""
			(at 0 0 0)
			(layer "F.Fab")
			(hide yes)
			(effects
				(font
					(size 1 1)
					(thickness 0.15)
				)
			)
		)
		(sheetname "Supply")
		(sheetfile "supply.kicad_sch")
		(attr exclude_from_pos_files)
		(pad "1" smd circle
			(at 0 0)
			(size 1 1)
			(layers "F.Cu" "F.Mask")
			(net 461 "1V1_SYS")
			(pinfunction "1")
			(pintype "passive")
		)
	)
	(footprint "antmicro-footprints:VQFN-18_3x3x1mm_P0.5mm"
		(layer "F.Cu")
		(at 125.526157 56.419672 -90)
		(property "Reference" "U13"
			(at -1.047672 1.828157 270)
			(layer "F.SilkS")
			(effects
				(font
					(size 0.7 0.7)
					(thickness 0.15)
				)
				(justify left bottom)
			)
		)
		(property "Value" "TPS65296"
			(at -2.1 3 270)
			(layer "F.Fab")
			(effects
				(font
					(size 0.7 0.7)
					(thickness 0.15)
				)
				(justify left bottom)
			)
		)
		(property "Description" "DC/DC switching voltage regulator"
			(at 0 0 270)
			(layer "F.Fab")
			(hide yes)
			(effects
				(font
					(size 1.27 1.27)
					(thickness 0.15)
				)
			)
		)
		(property "Author" "Antmicro"
			(at 69.106485 181.945829 0)
			(layer "F.Fab")
			(hide yes)
			(effects
				(font
					(size 1 1)
					(thickness 0.15)
				)
			)
		)
		(property "License" "Apache-2.0"
			(at 69.106485 181.945829 0)
			(layer "F.Fab")
			(hide yes)
			(effects
				(font
					(size 1 1)
					(thickness 0.15)
				)
			)
		)
		(property "MPN" "TPS65296RJER"
			(at 69.106485 181.945829 0)
			(layer "F.Fab")
			(hide yes)
			(effects
				(font
					(size 1 1)
					(thickness 0.15)
				)
			)
		)
		(property "Manufacturer" "Texas Instruments"
			(at 69.106485 181.945829 0)
			(layer "F.Fab")
			(hide yes)
			(effects
				(font
					(size 1 1)
					(thickness 0.15)
				)
			)
		)
		(sheetname "Supply")
		(sheetfile "supply.kicad_sch")
		(attr exclude_from_pos_files exclude_from_bom dnp)
		(fp_line
			(start -1.932 1.929)
			(end -1.621 1.929)
			(stroke
				(width 0.15)
				(type solid)
			)
			(layer "F.SilkS")
		)
		(fp_line
			(start 1.618 1.929)
			(end 1.929 1.929)
			(stroke
				(width 0.15)
				(type solid)
			)
			(layer "F.SilkS")
		)
		(fp_line
			(start 1.929 1.929)
			(end 1.929 1.596)
			(stroke
				(width 0.15)
				(type solid)
			)
			(layer "F.SilkS")
		)
		(fp_line
			(start -1.932 1.596)
			(end -1.932 1.929)
			(stroke
				(width 0.15)
				(type solid)
			)
			(layer "F.SilkS")
		)
		(fp_line
			(start 1.929 -1.597)
			(end 1.929 -1.932)
			(stroke
				(width 0.15)
				(type solid)
			)
			(layer "F.SilkS")
		)
		(fp_line
			(start -1.932 -1.932)
			(end -1.932 -1.597)
			(stroke
				(width 0.15)
				(type solid)
			)
			(layer "F.SilkS")
		)
		(fp_line
			(start -1.621 -1.932)
			(end -1.932 -1.932)
			(stroke
				(width 0.15)
				(type solid)
			)
			(layer "F.SilkS")
		)
		(fp_line
			(start 1.929 -1.932)
			(end 1.618 -1.932)
			(stroke
				(width 0.15)
				(type solid)
			)
			(layer "F.SilkS")
		)
		(fp_circle
			(center -2.246 -1.258)
			(end -2.196 -1.258)
			(stroke
				(width 0.15)
				(type solid)
			)
			(fill no)
			(layer "F.SilkS")
		)
		(fp_poly
			(pts
				(xy -0.352 1.703) (xy -0.551 1.703) (xy -0.551 0.685) (xy -0.352 0.685)
			)
			(stroke
				(width 0.001)
				(type solid)
			)
			(fill yes)
			(layer "F.Paste")
		)
		(fp_poly
			(pts
				(xy 0.548 1.703) (xy 0.349 1.703) (xy 0.349 0.685) (xy 0.548 0.685)
			)
			(stroke
				(width 0.001)
				(type solid)
			)
			(fill yes)
			(layer "F.Paste")
		)
		(fp_poly
			(pts
				(xy 0.099 0.535) (xy -0.1 0.535) (xy -0.1 -0.485) (xy 0.099 -0.485)
			)
			(stroke
				(width 0.001)
				(type solid)
			)
			(fill yes)
			(layer "F.Paste")
		)
		(fp_poly
			(pts
				(xy -0.352 0.484) (xy -0.551 0.484) (xy -0.551 -0.535) (xy -0.352 -0.535)
			)
			(stroke
				(width 0.001)
				(type solid)
			)
			(fill yes)
			(layer "F.Paste")
		)
		(fp_poly
			(pts
				(xy 0.548 0.484) (xy 0.349 0.484) (xy 0.349 -0.535) (xy 0.548 -0.535)
			)
			(stroke
				(width 0.001)
				(type solid)
			)
			(fill yes)
			(layer "F.Paste")
		)
		(fp_poly
			(pts
				(xy 0.099 -0.687) (xy -0.1 -0.687) (xy -0.1 -1.706) (xy 0.099 -1.706)
			)
			(stroke
				(width 0.001)
				(type solid)
			)
			(fill yes)
			(layer "F.Paste")
		)
		(fp_poly
			(pts
				(xy -1.101 1.705) (xy -1.355 1.703) (xy -1.355 1.348) (xy -1.7 1.35) (xy -1.7 1.124) (xy -1.101 1.124)
			)
			(stroke
				(width 0.001)
				(type solid)
			)
			(fill yes)
			(layer "F.Paste")
		)
		(fp_poly
			(pts
				(xy 1.1 1.705) (xy 1.352 1.703) (xy 1.352 1.348) (xy 1.699 1.35) (xy 1.699 1.124) (xy 1.1 1.124)
			)
			(stroke
				(width 0.001)
				(type solid)
			)
			(fill yes)
			(layer "F.Paste")
		)
		(fp_poly
			(pts
				(xy -1.103 -1.706) (xy -1.355 -1.706) (xy -1.355 -1.351) (xy -1.702 -1.351) (xy -1.702 -1.127) (xy -1.103 -1.127)
			)
			(stroke
				(width 0.001)
				(type solid)
			)
			(fill yes)
			(layer "F.Paste")
		)
		(fp_poly
			(pts
				(xy 1.1 -1.706) (xy 1.352 -1.706) (xy 1.352 -1.351) (xy 1.699 -1.351) (xy 1.699 -1.125) (xy 1.1 -1.125)
			)
			(stroke
				(width 0.001)
				(type solid)
			)
			(fill yes)
			(layer "F.Paste")
		)
		(fp_rect
			(start -2 -2)
			(end 2 2)
			(stroke
				(width 0.05)
				(type solid)
			)
			(fill no)
			(layer "F.CrtYd")
		)
		(fp_line
			(start -1.551 1.548)
			(end 1.548 1.548)
			(stroke
				(width 0.15)
				(type solid)
			)
			(layer "F.Fab")
		)
		(fp_line
			(start 1.548 1.548)
			(end 1.548 -1.551)
			(stroke
				(width 0.15)
				(type solid)
			)
			(layer "F.Fab")
		)
		(fp_line
			(start -1.551 -0.802)
			(end -1.551 1.548)
			(stroke
				(width 0.15)
				(type solid)
			)
			(layer "F.Fab")
		)
		(fp_line
			(start -1.551 -0.802)
			(end -0.802 -1.551)
			(stroke
				(width 0.15)
				(type solid)
			)
			(layer "F.Fab")
		)
		(fp_line
			(start 1.548 -1.551)
			(end -0.802 -1.551)
			(stroke
				(width 0.15)
				(type solid)
			)
			(layer "F.Fab")
		)
		(pad "1" smd custom
			(at -1.401 -1.25)
			(size 0.25 0.6)
			(layers "F.Cu" "F.Mask")
			(net 550 "VDD1V1")
			(pinfunction "VLDOIN")
			(pintype "input")
			(options
				(clearance outline)
				(anchor rect)
			)
			(primitives
				(gr_poly
					(pts
						(xy 0.4548 0.3) (xy 0.454997 0.016207) (xy 0.124997 0.016207) (xy 0.125 -0.3) (xy -0.125 -0.3)
						(xy -0.125 0.3)
					)
					(width 0.001)
					(fill yes)
				)
				(gr_poly
					(pts
						(xy 0.4548 0.3) (xy 0.454997 0.016207) (xy 0.124997 0.016207) (xy 0.125 -0.3) (xy -0.125 -0.3)
						(xy -0.125 0.3)
					)
					(width 0.001)
					(fill yes)
				)
			)
		)
		(pad "2" smd rect
			(at -1.401 -0.751)
			(size 0.25 0.6)
			(layers "F.Cu" "F.Mask" "F.Paste")
			(net 627 "/Supply/VDDQ_0V6")
			(pinfunction "VDDQ")
			(pintype "input")
		)
		(pad "3" smd rect
			(at -1.401 -0.25)
			(size 0.25 0.6)
			(layers "F.Cu" "F.Mask" "F.Paste")
			(net 5 "GND")
			(pinfunction "AGND")
			(pintype "input")
		)
		(pad "4" smd rect
			(at -1.401 0.248)
			(size 0.25 0.6)
			(layers "F.Cu" "F.Mask" "F.Paste")
			(net 631 "/Supply/VDDQ_SNS")
			(pinfunction "VDDQSNS")
			(pintype "input")
		)
		(pad "5" smd rect
			(at -1.401 0.749)
			(size 0.25 0.6)
			(layers "F.Cu" "F.Mask" "F.Paste")
			(net 550 "VDD1V1")
			(pinfunction "VDD2SNS")
			(pintype "input")
		)
		(pad "6" smd custom
			(at -1.401 1.249)
			(size 0.25 0.6)
			(layers "F.Cu" "F.Mask" "F.Paste")
			(net 626 "/Supply/VDDQ_REF")
			(pinfunction "VDDQREF")
			(pintype "input")
			(options
				(clearance outline)
				(anchor rect)
			)
			(primitives
				(gr_poly
					(pts
						(xy -0.4548 0.3) (xy -0.454997 0.016207) (xy -0.124997 0.016207) (xy -0.125 -0.3) (xy 0.125 -0.3)
						(xy 0.125 0.3)
					)
					(width 0.001)
					(fill yes)
				)
				(gr_poly
					(pts
						(xy -0.4548 0.3) (xy -0.454997 0.016207) (xy -0.124997 0.016207) (xy -0.125 -0.3) (xy 0.125 -0.3)
						(xy 0.125 0.3)
					)
					(width 0.001)
					(fill yes)
				)
			)
		)
		(pad "7" smd rect
			(at -0.452 0.583 270)
			(size 0.2 2.238)
			(layers "F.Cu" "F.Mask")
			(net 224 "VIN")
			(pinfunction "PVIN")
			(pintype "input")
		)
		(pad "8" smd rect
			(at 0 1.354 270)
			(size 0.2 0.7)
			(layers "F.Cu" "F.Mask" "F.Paste")
			(net 630 "/Supply/LPDDR4_PGOOD")
			(pinfunction "PGOOD")
			(pintype "input")
		)
		(pad "9" smd rect
			(at 0.45 0.583 270)
			(size 0.2 2.238)
			(layers "F.Cu" "F.Mask")
			(net 5 "GND")
			(pinfunction "PGND")
			(pintype "input")
		)
		(pad "10" smd custom
			(at 1.398 1.249 180)
			(size 0.25 0.6)
			(layers "F.Cu" "F.Mask")
			(net 636 "/Supply/0V6_EN")
			(pinfunction "VDDQEN")
			(pintype "input")
			(options
				(clearance outline)
				(anchor rect)
			)
			(primitives
				(gr_poly
					(pts
						(xy 0.4548 0.3) (xy 0.454997 0.016207) (xy 0.124997 0.016207) (xy 0.125 -0.3) (xy -0.125 -0.3)
						(xy -0.125 0.3)
					)
					(width 0.001)
					(fill yes)
				)
				(gr_poly
					(pts
						(xy 0.4548 0.3) (xy 0.454997 0.016207) (xy 0.124997 0.016207) (xy 0.125 -0.3) (xy -0.125 -0.3)
						(xy -0.125 0.3)
					)
					(width 0.001)
					(fill yes)
				)
			)
		)
		(pad "11" smd rect
			(at 1.398 0.749)
			(size 0.25 0.6096)
			(layers "F.Cu" "F.Mask" "F.Paste")
			(net 594 "/Supply/1V8_EN")
			(pinfunction "VDDEN")
			(pintype "input")
		)
		(pad "12" smd rect
			(at 1.398 0.248)
			(size 0.25 0.6096)
			(layers "F.Cu" "F.Mask" "F.Paste")
			(net 551 "/Supply/VDD1V8")
			(pinfunction "VDD1SNS")
			(pintype "input")
		)
		(pad "13" smd rect
			(at 1.398 -0.25)
			(size 0.25 0.6096)
			(layers "F.Cu" "F.Mask" "F.Paste")
			(net 463 "VCC5V0_INT")
			(pinfunction "VCC_5V")
			(pintype "input")
		)
		(pad "14" smd rect
			(at 1.398 -0.751)
			(size 0.25 0.6)
			(layers "F.Cu" "F.Mask" "F.Paste")
			(net 463 "VCC5V0_INT")
			(pinfunction "PIN_VDD1")
			(pintype "input")
		)
		(pad "15" smd custom
			(at 1.398 -1.25 180)
			(size 0.25 0.6)
			(layers "F.Cu" "F.Mask")
			(net 628 "/Supply/VDD1_SW")
			(pinfunction "SW_VDD1")
			(pintype "input")
			(options
				(clearance outline)
				(anchor rect)
			)
			(primitives
				(gr_poly
					(pts
						(xy -0.4548 0.3) (xy -0.454997 0.016207) (xy -0.124997 0.016207) (xy -0.125 -0.3) (xy 0.125 -0.3)
						(xy 0.125 0.3)
					)
					(width 0.001)
					(fill yes)
				)
				(gr_poly
					(pts
						(xy -0.4548 0.3) (xy -0.454997 0.016207) (xy -0.124997 0.016207) (xy -0.125 -0.3) (xy 0.125 -0.3)
						(xy 0.125 0.3)
					)
					(width 0.001)
					(fill yes)
				)
			)
		)
		(pad "16" smd rect
			(at 0.65 -1.401 270)
			(size 0.2 0.6096)
			(layers "F.Cu" "F.Mask" "F.Paste")
			(net 5 "GND")
			(pinfunction "PGND_VDD1")
			(pintype "input")
		)
		(pad "17" smd rect
			(at 0 -0.585 270)
			(size 0.2 2.243)
			(layers "F.Cu" "F.Mask")
			(net 625 "/Supply/VDD2_SW")
			(pinfunction "SW")
			(pintype "input")
		)
		(pad "18" smd rect
			(at -0.652 -1.401 270)
			(size 0.2 0.6096)
			(layers "F.Cu" "F.Mask" "F.Paste")
			(net 629 "/Supply/VDD2_BST")
			(pinfunction "BST")
			(pintype "input")
		)
	)
	(footprint "antmicro-footprints:LED_0603_1608Metric_G"
		(layer "F.Cu")
		(at 115.1492 106.4 180)
		(descr "LED SMD 0603 Green")
		(tags "LED SMD 0603 Green")
		(property "Reference" "PWR6"
			(at 1.4492 -1.4 180)
			(layer "F.SilkS")
			(effects
				(font
					(size 0.7 0.7)
					(thickness 0.15)
				)
				(justify left bottom)
			)
		)
		(property "Value" "LED_G_0603_KP-1608CGCK"
			(at 0 1.6 180)
			(layer "F.Fab")
			(effects
				(font
					(size 0.7 0.7)
					(thickness 0.15)
				)
				(justify left bottom)
			)
		)
		(property "Author" "Antmicro"
			(at 230.2984 212.8 0)
			(layer "F.Fab")
			(hide yes)
			(effects
				(font
					(size 1 1)
					(thickness 0.15)
				)
			)
		)
		(property "License" "Apache-2.0"
			(at 230.2984 212.8 0)
			(layer "F.Fab")
			(hide yes)
			(effects
				(font
					(size 1 1)
					(thickness 0.15)
				)
			)
		)
		(property "MPN" "KP-1608CGCK"
			(at 230.2984 212.8 0)
			(layer "F.Fab")
			(hide yes)
			(effects
				(font
					(size 1 1)
					(thickness 0.15)
				)
			)
		)
		(property "Manufacturer" "Kingbright"
			(at 230.2984 212.8 0)
			(layer "F.Fab")
			(hide yes)
			(effects
				(font
					(size 1 1)
					(thickness 0.15)
				)
			)
		)
		(sheetname "Supply")
		(sheetfile "supply.kicad_sch")
		(attr smd)
		(fp_line
			(start 1.25 0.32)
			(end 1.25 -0.32)
			(stroke
				(width 0.15)
				(type solid)
			)
			(layer "F.SilkS")
		)
		(fp_line
			(start 0.093672 -8e-06)
			(end 0.293672 -8e-06)
			(stroke
				(width 0.1)
				(type solid)
			)
			(layer "F.SilkS")
		)
		(fp_line
			(start 0.093672 -8e-06)
			(end -0.106328 0.199992)
			(stroke
				(width 0.1)
				(type solid)
			)
			(layer "F.SilkS")
		)
		(fp_line
			(start 0.093672 -0.200008)
			(end 0.093672 0.199992)
			(stroke
				(width 0.1)
				(type solid)
			)
			(layer "F.SilkS")
		)
		(fp_line
			(start -0.106328 -8e-06)
			(end -0.29 0)
			(stroke
				(width 0.1)
				(type solid)
			)
			(layer "F.SilkS")
		)
		(fp_line
			(start -0.106328 -0.200008)
			(end 0.093672 -8e-06)
			(stroke
				(width 0.1)
				(type solid)
			)
			(layer "F.SilkS")
		)
		(fp_line
			(start -0.106328 -0.200008)
			(end -0.106328 0.199992)
			(stroke
				(width 0.1)
				(type solid)
			)
			(layer "F.SilkS")
		)
		(fp_line
			(start -0.27 0.351)
			(end 0.27 0.351)
			(stroke
				(width 0.15)
				(type solid)
			)
			(layer "F.SilkS")
		)
		(fp_line
			(start -0.27 -0.35)
			(end 0.27 -0.35)
			(stroke
				(width 0.15)
				(type solid)
			)
			(layer "F.SilkS")
		)
		(fp_rect
			(start 1.26 0.65)
			(end -1.26 -0.65)
			(stroke
				(width 0.05)
				(type solid)
			)
			(fill no)
			(layer "F.CrtYd")
		)
		(fp_line
			(start 0.199 0.202)
			(end 0.199 -0.1)
			(stroke
				(width 0.15)
				(type solid)
			)
			(layer "F.Fab")
		)
		(fp_line
			(start 0.199 0)
			(end 0.597 0)
			(stroke
				(width 0.15)
				(type solid)
			)
			(layer "F.Fab")
		)
		(fp_line
			(start 0.199 -0.2)
			(end 0.199 -0.1)
			(stroke
				(width 0.15)
				(type solid)
			)
			(layer "F.Fab")
		)
		(fp_line
			(start 0.101 0)
			(end -0.201 -0.2)
			(stroke
				(width 0.15)
				(type solid)
			)
			(layer "F.Fab")
		)
		(fp_line
			(start -0.201 0.202)
			(end 0.101 0)
			(stroke
				(width 0.15)
				(type solid)
			)
			(layer "F.Fab")
		)
		(fp_line
			(start -0.201 0)
			(end -0.201 0.202)
			(stroke
				(width 0.15)
				(type solid)
			)
			(layer "F.Fab")
		)
		(fp_line
			(start -0.201 -0.2)
			(end -0.201 0)
			(stroke
				(width 0.15)
				(type solid)
			)
			(layer "F.Fab")
		)
		(fp_line
			(start -0.599 0)
			(end -0.201 0)
			(stroke
				(width 0.15)
				(type solid)
			)
			(layer "F.Fab")
		)
		(fp_rect
			(start -0.848 -0.4)
			(end 0.85 0.402)
			(stroke
				(width 0.15)
				(type solid)
			)
			(fill no)
			(layer "F.Fab")
		)
		(pad "1" smd rect
			(at -0.75 0)
			(size 0.8 0.8)
			(layers "F.Cu" "F.Mask" "F.Paste")
			(net 463 "VCC5V0_INT")
			(pinfunction "1")
			(pintype "passive")
		)
		(pad "2" smd rect
			(at 0.75 0)
			(size 0.8 0.8)
			(layers "F.Cu" "F.Mask" "F.Paste")
			(net 632 "Net-(PWR6-Pad2)")
			(pinfunction "2")
			(pintype "passive")
		)
	)
	(footprint "antmicro-footprints:L_1210_3225Metric"
		(layer "F.Cu")
		(at 131.55 55.85 90)
		(property "Reference" "L8"
			(at 2.25 -0.65 180)
			(layer "F.SilkS")
			(effects
				(font
					(size 0.7 0.7)
					(thickness 0.15)
				)
				(justify left bottom)
			)
		)
		(property "Value" "L_680n_6.1A_1210"
			(at 0 2.4 90)
			(layer "F.Fab")
			(effects
				(font
					(size 0.7 0.7)
					(thickness 0.15)
				)
				(justify left bottom)
			)
		)
		(property "Author" "Antmicro"
			(at 187.4 -75.7 0)
			(layer "F.Fab")
			(hide yes)
			(effects
				(font
					(size 1 1)
					(thickness 0.15)
				)
			)
		)
		(property "IMax" ""
			(at 187.4 -75.7 0)
			(layer "F.Fab")
			(hide yes)
			(effects
				(font
					(size 1 1)
					(thickness 0.15)
				)
			)
		)
		(property "ISat" ""
			(at 187.4 -75.7 0)
			(layer "F.Fab")
			(hide yes)
			(effects
				(font
					(size 1 1)
					(thickness 0.15)
				)
			)
		)
		(property "License" "Apache-2.0"
			(at 187.4 -75.7 0)
			(layer "F.Fab")
			(hide yes)
			(effects
				(font
					(size 1 1)
					(thickness 0.15)
				)
			)
		)
		(property "MPN" "DFE322512F-R68M=P2"
			(at 187.4 -75.7 0)
			(layer "F.Fab")
			(hide yes)
			(effects
				(font
					(size 1 1)
					(thickness 0.15)
				)
			)
		)
		(property "Manufacturer" "Murata"
			(at 187.4 -75.7 0)
			(layer "F.Fab")
			(hide yes)
			(effects
				(font
					(size 1 1)
					(thickness 0.15)
				)
			)
		)
		(property "Size" "3.2x2.5"
			(at 187.4 -75.7 0)
			(layer "F.Fab")
			(hide yes)
			(effects
				(font
					(size 1 1)
					(thickness 0.15)
				)
			)
		)
		(property "Val" "680n/6.1A"
			(at 187.4 -75.7 0)
			(layer "F.Fab")
			(hide yes)
			(effects
				(font
					(size 1 1)
					(thickness 0.15)
				)
			)
		)
		(sheetname "Supply")
		(sheetfile "supply.kicad_sch")
		(attr exclude_from_pos_files exclude_from_bom dnp)
		(fp_line
			(start -0.7 -1.4)
			(end 0.7 -1.4)
			(stroke
				(width 0.15)
				(type solid)
			)
			(layer "F.SilkS")
		)
		(fp_line
			(start -0.7 1.4)
			(end 0.7 1.4)
			(stroke
				(width 0.15)
				(type solid)
			)
			(layer "F.SilkS")
		)
		(fp_rect
			(start -2.1 -1.5)
			(end 2.09 1.5)
			(stroke
				(width 0.05)
				(type solid)
			)
			(fill no)
			(layer "F.CrtYd")
		)
		(fp_line
			(start 1.7 -1.351)
			(end -1.701 -1.351)
			(stroke
				(width 0.15)
				(type solid)
			)
			(layer "F.Fab")
		)
		(fp_line
			(start 1.7 1.35)
			(end 1.7 -1.351)
			(stroke
				(width 0.15)
				(type solid)
			)
			(layer "F.Fab")
		)
		(fp_line
			(start 1.7 1.35)
			(end -1.701 1.35)
			(stroke
				(width 0.15)
				(type solid)
			)
			(layer "F.Fab")
		)
		(fp_line
			(start -1.701 1.35)
			(end -1.701 -1.351)
			(stroke
				(width 0.15)
				(type solid)
			)
			(layer "F.Fab")
		)
		(pad "1" smd rect
			(at -1.439 0 90)
			(size 1.24 2.72)
			(layers "F.Cu" "F.Mask" "F.Paste")
			(net 625 "/Supply/VDD2_SW")
			(pintype "passive")
		)
		(pad "2" smd rect
			(at 1.439 0 90)
			(size 1.24 2.72)
			(layers "F.Cu" "F.Mask" "F.Paste")
			(net 550 "VDD1V1")
			(pintype "passive")
		)
	)
	(footprint "antmicro-footprints:L_WE-MAIA-2512"
		(layer "F.Cu")
		(at 126.1825 96.249 180)
		(property "Reference" "L6"
			(at -1.5 -1.4 180)
			(layer "F.SilkS")
			(effects
				(font
					(size 0.7 0.7)
					(thickness 0.15)
				)
				(justify left bottom)
			)
		)
		(property "Value" "784383240047"
			(at 0 2.3 180)
			(layer "F.Fab")
			(effects
				(font
					(size 0.7 0.7)
					(thickness 0.15)
				)
				(justify left bottom)
			)
		)
		(property "Description" "Power Inductor (SMT), AEC-Q200, 470 nH, 3.4 A, Shielded, 6.25 A, WE-MAIA"
			(at 0 0 180)
			(layer "F.Fab")
			(hide yes)
			(effects
				(font
					(size 1.27 1.27)
					(thickness 0.15)
				)
			)
		)
		(property "Author" "Antmicro"
			(at 252.365 192.498 0)
			(layer "F.Fab")
			(hide yes)
			(effects
				(font
					(size 1 1)
					(thickness 0.15)
				)
			)
		)
		(property "IMax" "3.4 A"
			(at 252.365 192.498 0)
			(layer "F.Fab")
			(hide yes)
			(effects
				(font
					(size 1 1)
					(thickness 0.15)
				)
			)
		)
		(property "ISat" "6.25 A"
			(at 252.365 192.498 0)
			(layer "F.Fab")
			(hide yes)
			(effects
				(font
					(size 1 1)
					(thickness 0.15)
				)
			)
		)
		(property "License" "Apache-2.0"
			(at 252.365 192.498 0)
			(layer "F.Fab")
			(hide yes)
			(effects
				(font
					(size 1 1)
					(thickness 0.15)
				)
			)
		)
		(property "MPN" "784383240047"
			(at 252.365 192.498 0)
			(layer "F.Fab")
			(hide yes)
			(effects
				(font
					(size 1 1)
					(thickness 0.15)
				)
			)
		)
		(property "Manufacturer" "Würth Elektronik"
			(at 252.365 192.498 0)
			(layer "F.Fab")
			(hide yes)
			(effects
				(font
					(size 1 1)
					(thickness 0.15)
				)
			)
		)
		(property "Size" "2x2.5"
			(at 252.365 192.498 0)
			(layer "F.Fab")
			(hide yes)
			(effects
				(font
					(size 1 1)
					(thickness 0.15)
				)
			)
		)
		(property "Val" "470n/3.4A"
			(at 252.365 192.498 0)
			(layer "F.Fab")
			(hide yes)
			(effects
				(font
					(size 1 1)
					(thickness 0.15)
				)
			)
		)
		(sheetname "Supply")
		(sheetfile "supply.kicad_sch")
		(attr smd)
		(fp_line
			(start -0.325 1.125)
			(end 0.325 1.125)
			(stroke
				(width 0.15)
				(type solid)
			)
			(layer "F.SilkS")
		)
		(fp_line
			(start -0.325 -1.125)
			(end 0.325 -1.125)
			(stroke
				(width 0.15)
				(type solid)
			)
			(layer "F.SilkS")
		)
		(fp_rect
			(start -1.65 -1.4)
			(end 1.65 1.4)
			(stroke
				(width 0.05)
				(type solid)
			)
			(fill no)
			(layer "F.CrtYd")
		)
		(fp_rect
			(start -1.25 -1)
			(end 1.25 1)
			(stroke
				(width 0.15)
				(type solid)
			)
			(fill no)
			(layer "F.Fab")
		)
		(pad "1" smd roundrect
			(at -0.975 0 180)
			(size 0.85 2.3)
			(layers "F.Cu" "F.Mask" "F.Paste")
			(roundrect_rratio 0.1)
			(net 582 "/Supply/1V0_SW")
			(pintype "passive")
		)
		(pad "2" smd roundrect
			(at 0.975 0 180)
			(size 0.85 2.3)
			(layers "F.Cu" "F.Mask" "F.Paste")
			(roundrect_rratio 0.1)
			(net 588 "/Supply/1V0_REG")
			(pintype "passive")
		)
	)
	(footprint "antmicro-footprints:C_0603_1608Metric"
		(layer "F.Cu")
		(at 127.425 52.725 90)
		(descr "Capacitor SMD 0603")
		(tags "capacitor 0603")
		(property "Reference" "C190"
			(at 1.025 0.775 90)
			(layer "F.SilkS")
			(effects
				(font
					(size 0.7 0.7)
					(thickness 0.15)
				)
				(justify left bottom)
			)
		)
		(property "Value" "C_10u_0603"
			(at 0 1.6 90)
			(layer "F.Fab")
			(effects
				(font
					(size 0.7 0.7)
					(thickness 0.15)
				)
				(justify left bottom)
			)
		)
		(property "Description" " "
			(at 0 0 90)
			(layer "F.Fab")
			(hide yes)
			(effects
				(font
					(size 1.27 1.27)
					(thickness 0.15)
				)
			)
		)
		(property "Author" "Antmicro"
			(at 180.15 -74.7 0)
			(layer "F.Fab")
			(hide yes)
			(effects
				(font
					(size 1 1)
					(thickness 0.15)
				)
			)
		)
		(property "License" "Apache-2.0"
			(at 180.15 -74.7 0)
			(layer "F.Fab")
			(hide yes)
			(effects
				(font
					(size 1 1)
					(thickness 0.15)
				)
			)
		)
		(property "MPN" "GRM188R61A106KE69D"
			(at 180.15 -74.7 0)
			(layer "F.Fab")
			(hide yes)
			(effects
				(font
					(size 1 1)
					(thickness 0.15)
				)
			)
		)
		(property "Manufacturer" "Murata"
			(at 180.15 -74.7 0)
			(layer "F.Fab")
			(hide yes)
			(effects
				(font
					(size 1 1)
					(thickness 0.15)
				)
			)
		)
		(property "Val" "10u"
			(at 180.15 -74.7 0)
			(layer "F.Fab")
			(hide yes)
			(effects
				(font
					(size 1 1)
					(thickness 0.15)
				)
			)
		)
		(property "Voltage" ""
			(at 180.15 -74.7 0)
			(layer "F.Fab")
			(hide yes)
			(effects
				(font
					(size 1 1)
					(thickness 0.15)
				)
			)
		)
		(sheetname "Supply")
		(sheetfile "supply.kicad_sch")
		(attr exclude_from_pos_files exclude_from_bom dnp)
		(fp_line
			(start -0.3 -0.3)
			(end 0.3 -0.3)
			(stroke
				(width 0.15)
				(type solid)
			)
			(layer "F.SilkS")
		)
		(fp_line
			(start -0.3 0.3)
			(end 0.3 0.3)
			(stroke
				(width 0.15)
				(type solid)
			)
			(layer "F.SilkS")
		)
		(fp_rect
			(start -1.24 -0.7)
			(end 1.24 0.7)
			(stroke
				(width 0.05)
				(type solid)
			)
			(fill no)
			(layer "F.CrtYd")
		)
		(fp_rect
			(start -0.8 -0.4)
			(end 0.8 0.4)
			(stroke
				(width 0.15)
				(type solid)
			)
			(fill no)
			(layer "F.Fab")
		)
		(pad "1" smd roundrect
			(at -0.7 0 90)
			(size 0.6 0.8)
			(layers "F.Cu" "F.Mask" "F.Paste")
			(roundrect_rratio 0.2)
			(net 550 "VDD1V1")
			(pintype "passive")
		)
		(pad "2" smd roundrect
			(at 0.7 0 90)
			(size 0.6 0.8)
			(layers "F.Cu" "F.Mask" "F.Paste")
			(roundrect_rratio 0.2)
			(net 5 "GND")
			(pintype "passive")
		)
	)
	(footprint "antmicro-footprints:R_0402_1005Metric"
		(layer "F.Cu")
		(at 137.1 65.7)
		(descr "Resistor SMD 0402")
		(tags "resistor SMD 0402")
		(property "Reference" "R155"
			(at -0.9 2.3 0)
			(layer "F.SilkS")
			(effects
				(font
					(size 0.7 0.7)
					(thickness 0.15)
				)
				(justify left bottom)
			)
		)
		(property "Value" "R_49R9_0402"
			(at 0 1.4 0)
			(layer "F.Fab")
			(effects
				(font
					(size 0.7 0.7)
					(thickness 0.15)
				)
				(justify left bottom)
			)
		)
		(property "Description" "49R9 resistor in 0402 package with 1% tolerance"
			(at 0 0 0)
			(layer "F.Fab")
			(hide yes)
			(effects
				(font
					(size 1.27 1.27)
					(thickness 0.15)
				)
			)
		)
		(property "Author" "Antmicro"
			(at 0 0 0)
			(layer "F.Fab")
			(hide yes)
			(effects
				(font
					(size 1 1)
					(thickness 0.15)
				)
			)
		)
		(property "License" "Apache-2.0"
			(at 0 0 0)
			(layer "F.Fab")
			(hide yes)
			(effects
				(font
					(size 1 1)
					(thickness 0.15)
				)
			)
		)
		(property "MPN" "CR0402-FX-49R9GLF"
			(at 0 0 0)
			(layer "F.Fab")
			(hide yes)
			(effects
				(font
					(size 1 1)
					(thickness 0.15)
				)
			)
		)
		(property "Manufacturer" "Bourns"
			(at 0 0 0)
			(layer "F.Fab")
			(hide yes)
			(effects
				(font
					(size 1 1)
					(thickness 0.15)
				)
			)
		)
		(property "Tolerance" "1%"
			(at 0 0 0)
			(layer "F.Fab")
			(hide yes)
			(effects
				(font
					(size 1 1)
					(thickness 0.15)
				)
			)
		)
		(property "Val" "49R9"
			(at 0 0 0)
			(layer "F.Fab")
			(hide yes)
			(effects
				(font
					(size 1 1)
					(thickness 0.15)
				)
			)
		)
		(sheetname "Supply")
		(sheetfile "supply.kicad_sch")
		(attr smd)
		(fp_rect
			(start -0.93 -0.47)
			(end 0.93 0.47)
			(stroke
				(width 0.05)
				(type solid)
			)
			(fill no)
			(layer "F.CrtYd")
		)
		(fp_rect
			(start -0.5 -0.25)
			(end 0.5 0.25)
			(stroke
				(width 0.15)
				(type solid)
			)
			(fill no)
			(layer "F.Fab")
		)
		(pad "1" smd roundrect
			(at -0.485 0)
			(size 0.59 0.64)
			(layers "F.Cu" "F.Mask" "F.Paste")
			(roundrect_rratio 0.25)
			(net 635 "/Supply/0V6_FB")
			(pintype "passive")
		)
		(pad "2" smd roundrect
			(at 0.485 0)
			(size 0.59 0.64)
			(layers "F.Cu" "F.Mask" "F.Paste")
			(roundrect_rratio 0.25)
			(net 5 "GND")
			(pintype "passive")
		)
	)
	(footprint "antmicro-footprints:R_0402_1005Metric"
		(layer "F.Cu")
		(at 129.9825 100.549 180)
		(descr "Resistor SMD 0402")
		(tags "resistor SMD 0402")
		(property "Reference" "R125"
			(at -0.7175 -0.451 180)
			(layer "F.SilkS")
			(effects
				(font
					(size 0.7 0.7)
					(thickness 0.15)
				)
				(justify left bottom)
			)
		)
		(property "Value" "R_0R_0402"
			(at 0 1.4 180)
			(layer "F.Fab")
			(effects
				(font
					(size 0.7 0.7)
					(thickness 0.15)
				)
				(justify left bottom)
			)
		)
		(property "Description" "0R resistor in 0402 package with unspecified tolerance"
			(at 0 0 180)
			(layer "F.Fab")
			(hide yes)
			(effects
				(font
					(size 1.27 1.27)
					(thickness 0.15)
				)
			)
		)
		(property "Author" "Antmicro"
			(at 259.965 201.098 0)
			(layer "F.Fab")
			(hide yes)
			(effects
				(font
					(size 1 1)
					(thickness 0.15)
				)
			)
		)
		(property "Current" "1A"
			(at 259.965 201.098 0)
			(layer "F.Fab")
			(hide yes)
			(effects
				(font
					(size 1 1)
					(thickness 0.15)
				)
			)
		)
		(property "License" "Apache-2.0"
			(at 259.965 201.098 0)
			(layer "F.Fab")
			(hide yes)
			(effects
				(font
					(size 1 1)
					(thickness 0.15)
				)
			)
		)
		(property "MPN" "ERJ2GE0R00X"
			(at 259.965 201.098 0)
			(layer "F.Fab")
			(hide yes)
			(effects
				(font
					(size 1 1)
					(thickness 0.15)
				)
			)
		)
		(property "Manufacturer" "Panasonic"
			(at 259.965 201.098 0)
			(layer "F.Fab")
			(hide yes)
			(effects
				(font
					(size 1 1)
					(thickness 0.15)
				)
			)
		)
		(property "Tolerance" ""
			(at 259.965 201.098 0)
			(layer "F.Fab")
			(hide yes)
			(effects
				(font
					(size 1 1)
					(thickness 0.15)
				)
			)
		)
		(property "Val" "0R"
			(at 259.965 201.098 0)
			(layer "F.Fab")
			(hide yes)
			(effects
				(font
					(size 1 1)
					(thickness 0.15)
				)
			)
		)
		(sheetname "Supply")
		(sheetfile "supply.kicad_sch")
		(attr smd)
		(fp_rect
			(start -0.93 -0.47)
			(end 0.93 0.47)
			(stroke
				(width 0.05)
				(type solid)
			)
			(fill no)
			(layer "F.CrtYd")
		)
		(fp_rect
			(start -0.5 -0.25)
			(end 0.5 0.25)
			(stroke
				(width 0.15)
				(type solid)
			)
			(fill no)
			(layer "F.Fab")
		)
		(pad "1" smd roundrect
			(at -0.485 0 180)
			(size 0.59 0.64)
			(layers "F.Cu" "F.Mask" "F.Paste")
			(roundrect_rratio 0.25)
			(net 5 "GND")
			(pintype "passive")
		)
		(pad "2" smd roundrect
			(at 0.485 0 180)
			(size 0.59 0.64)
			(layers "F.Cu" "F.Mask" "F.Paste")
			(roundrect_rratio 0.25)
			(net 612 "/Supply/1V0_MODE")
			(pintype "passive")
		)
	)
	(footprint "antmicro-footprints:R_0402_1005Metric"
		(layer "F.Cu")
		(at 111.362806 89.974 180)
		(descr "Resistor SMD 0402")
		(tags "resistor SMD 0402")
		(property "Reference" "R137"
			(at 3.662806 -0.326 180)
			(layer "F.SilkS")
			(effects
				(font
					(size 0.7 0.7)
					(thickness 0.15)
				)
				(justify left bottom)
			)
		)
		(property "Value" "R_10k_0402"
			(at 0 1.4 180)
			(layer "F.Fab")
			(effects
				(font
					(size 0.7 0.7)
					(thickness 0.15)
				)
				(justify left bottom)
			)
		)
		(property "Description" "10k resistor in 0402 package with 1% tolerance"
			(at 0 0 180)
			(layer "F.Fab")
			(hide yes)
			(effects
				(font
					(size 1.27 1.27)
					(thickness 0.15)
				)
			)
		)
		(property "Author" "Antmicro"
			(at 222.725612 179.948 0)
			(layer "F.Fab")
			(hide yes)
			(effects
				(font
					(size 1 1)
					(thickness 0.15)
				)
			)
		)
		(property "License" "Apache-2.0"
			(at 222.725612 179.948 0)
			(layer "F.Fab")
			(hide yes)
			(effects
				(font
					(size 1 1)
					(thickness 0.15)
				)
			)
		)
		(property "MPN" "CR0402-FX-1002GLF"
			(at 222.725612 179.948 0)
			(layer "F.Fab")
			(hide yes)
			(effects
				(font
					(size 1 1)
					(thickness 0.15)
				)
			)
		)
		(property "Manufacturer" "Bourns"
			(at 222.725612 179.948 0)
			(layer "F.Fab")
			(hide yes)
			(effects
				(font
					(size 1 1)
					(thickness 0.15)
				)
			)
		)
		(property "Tolerance" "1%"
			(at 222.725612 179.948 0)
			(layer "F.Fab")
			(hide yes)
			(effects
				(font
					(size 1 1)
					(thickness 0.15)
				)
			)
		)
		(property "Val" "10k"
			(at 222.725612 179.948 0)
			(layer "F.Fab")
			(hide yes)
			(effects
				(font
					(size 1 1)
					(thickness 0.15)
				)
			)
		)
		(sheetname "Supply")
		(sheetfile "supply.kicad_sch")
		(attr smd)
		(fp_rect
			(start -0.93 -0.47)
			(end 0.93 0.47)
			(stroke
				(width 0.05)
				(type solid)
			)
			(fill no)
			(layer "F.CrtYd")
		)
		(fp_rect
			(start -0.5 -0.25)
			(end 0.5 0.25)
			(stroke
				(width 0.15)
				(type solid)
			)
			(fill no)
			(layer "F.Fab")
		)
		(pad "1" smd roundrect
			(at -0.485 0 180)
			(size 0.59 0.64)
			(layers "F.Cu" "F.Mask" "F.Paste")
			(roundrect_rratio 0.25)
			(net 600 "/Supply/1V8_FB")
			(pintype "passive")
		)
		(pad "2" smd roundrect
			(at 0.485 0 180)
			(size 0.59 0.64)
			(layers "F.Cu" "F.Mask" "F.Paste")
			(roundrect_rratio 0.25)
			(net 5 "GND")
			(pintype "passive")
		)
	)
	(footprint "antmicro-footprints:R_0402_1005Metric"
		(layer "F.Cu")
		(at 140.1825 92.099)
		(descr "Resistor SMD 0402")
		(tags "resistor SMD 0402")
		(property "Reference" "R102"
			(at -3.6825 -0.899 0)
			(layer "F.SilkS")
			(effects
				(font
					(size 0.7 0.7)
					(thickness 0.15)
				)
				(justify left bottom)
			)
		)
		(property "Value" "R_330R_0402"
			(at 0 1.4 0)
			(layer "F.Fab")
			(effects
				(font
					(size 0.7 0.7)
					(thickness 0.15)
				)
				(justify left bottom)
			)
		)
		(property "Description" "330R resistor in 0402 package with 1% tolerance"
			(at 0 0 0)
			(layer "F.Fab")
			(hide yes)
			(effects
				(font
					(size 1.27 1.27)
					(thickness 0.15)
				)
			)
		)
		(property "Author" "Antmicro"
			(at 0 0 0)
			(layer "F.Fab")
			(hide yes)
			(effects
				(font
					(size 1 1)
					(thickness 0.15)
				)
			)
		)
		(property "License" "Apache-2.0"
			(at 0 0 0)
			(layer "F.Fab")
			(hide yes)
			(effects
				(font
					(size 1 1)
					(thickness 0.15)
				)
			)
		)
		(property "MPN" "CR0402-FX-3300GLF"
			(at 0 0 0)
			(layer "F.Fab")
			(hide yes)
			(effects
				(font
					(size 1 1)
					(thickness 0.15)
				)
			)
		)
		(property "Manufacturer" "Bourns"
			(at 0 0 0)
			(layer "F.Fab")
			(hide yes)
			(effects
				(font
					(size 1 1)
					(thickness 0.15)
				)
			)
		)
		(property "Tolerance" "1%"
			(at 0 0 0)
			(layer "F.Fab")
			(hide yes)
			(effects
				(font
					(size 1 1)
					(thickness 0.15)
				)
			)
		)
		(property "Val" "330R"
			(at 0 0 0)
			(layer "F.Fab")
			(hide yes)
			(effects
				(font
					(size 1 1)
					(thickness 0.15)
				)
			)
		)
		(sheetname "Supply")
		(sheetfile "supply.kicad_sch")
		(attr smd)
		(fp_rect
			(start -0.93 -0.47)
			(end 0.93 0.47)
			(stroke
				(width 0.05)
				(type solid)
			)
			(fill no)
			(layer "F.CrtYd")
		)
		(fp_rect
			(start -0.5 -0.25)
			(end 0.5 0.25)
			(stroke
				(width 0.15)
				(type solid)
			)
			(fill no)
			(layer "F.Fab")
		)
		(pad "1" smd roundrect
			(at -0.485 0)
			(size 0.59 0.64)
			(layers "F.Cu" "F.Mask" "F.Paste")
			(roundrect_rratio 0.25)
			(net 555 "Net-(PWR3-Pad2)")
			(pintype "passive")
		)
		(pad "2" smd roundrect
			(at 0.485 0)
			(size 0.59 0.64)
			(layers "F.Cu" "F.Mask" "F.Paste")
			(roundrect_rratio 0.25)
			(net 235 "Net-(Q9-D)")
			(pintype "passive")
		)
	)
	(footprint "antmicro-footprints:R_0402_1005Metric"
		(layer "F.Cu")
		(at 117.697806 89.074 180)
		(descr "Resistor SMD 0402")
		(tags "resistor SMD 0402")
		(property "Reference" "R131"
			(at 0.897806 3.574 180)
			(layer "F.SilkS")
			(effects
				(font
					(size 0.7 0.7)
					(thickness 0.15)
				)
				(justify left bottom)
			)
		)
		(property "Value" "R_0R_0402"
			(at 0 1.4 180)
			(layer "F.Fab")
			(effects
				(font
					(size 0.7 0.7)
					(thickness 0.15)
				)
				(justify left bottom)
			)
		)
		(property "Description" "0R resistor in 0402 package with unspecified tolerance"
			(at 0 0 180)
			(layer "F.Fab")
			(hide yes)
			(effects
				(font
					(size 1.27 1.27)
					(thickness 0.15)
				)
			)
		)
		(property "Author" "Antmicro"
			(at 235.395612 178.148 0)
			(layer "F.Fab")
			(hide yes)
			(effects
				(font
					(size 1 1)
					(thickness 0.15)
				)
			)
		)
		(property "Current" "1A"
			(at 235.395612 178.148 0)
			(layer "F.Fab")
			(hide yes)
			(effects
				(font
					(size 1 1)
					(thickness 0.15)
				)
			)
		)
		(property "License" "Apache-2.0"
			(at 235.395612 178.148 0)
			(layer "F.Fab")
			(hide yes)
			(effects
				(font
					(size 1 1)
					(thickness 0.15)
				)
			)
		)
		(property "MPN" "ERJ2GE0R00X"
			(at 235.395612 178.148 0)
			(layer "F.Fab")
			(hide yes)
			(effects
				(font
					(size 1 1)
					(thickness 0.15)
				)
			)
		)
		(property "Manufacturer" "Panasonic"
			(at 235.395612 178.148 0)
			(layer "F.Fab")
			(hide yes)
			(effects
				(font
					(size 1 1)
					(thickness 0.15)
				)
			)
		)
		(property "Tolerance" ""
			(at 235.395612 178.148 0)
			(layer "F.Fab")
			(hide yes)
			(effects
				(font
					(size 1 1)
					(thickness 0.15)
				)
			)
		)
		(property "Val" "0R"
			(at 235.395612 178.148 0)
			(layer "F.Fab")
			(hide yes)
			(effects
				(font
					(size 1 1)
					(thickness 0.15)
				)
			)
		)
		(sheetname "Supply")
		(sheetfile "supply.kicad_sch")
		(attr smd)
		(fp_rect
			(start -0.93 -0.47)
			(end 0.93 0.47)
			(stroke
				(width 0.05)
				(type solid)
			)
			(fill no)
			(layer "F.CrtYd")
		)
		(fp_rect
			(start -0.5 -0.25)
			(end 0.5 0.25)
			(stroke
				(width 0.15)
				(type solid)
			)
			(fill no)
			(layer "F.Fab")
		)
		(pad "1" smd roundrect
			(at -0.485 0 180)
			(size 0.59 0.64)
			(layers "F.Cu" "F.Mask" "F.Paste")
			(roundrect_rratio 0.25)
			(net 5 "GND")
			(pintype "passive")
		)
		(pad "2" smd roundrect
			(at 0.485 0 180)
			(size 0.59 0.64)
			(layers "F.Cu" "F.Mask" "F.Paste")
			(roundrect_rratio 0.25)
			(net 619 "/Supply/1V8_MODE")
			(pintype "passive")
		)
	)
	(footprint "antmicro-footprints:R_0402_1005Metric"
		(layer "F.Cu")
		(at 111.362806 88.974)
		(descr "Resistor SMD 0402")
		(tags "resistor SMD 0402")
		(property "Reference" "R132"
			(at -3.662806 0.326 0)
			(layer "F.SilkS")
			(effects
				(font
					(size 0.7 0.7)
					(thickness 0.15)
				)
				(justify left bottom)
			)
		)
		(property "Value" "R_0R_0402"
			(at 0 1.4 0)
			(layer "F.Fab")
			(effects
				(font
					(size 0.7 0.7)
					(thickness 0.15)
				)
				(justify left bottom)
			)
		)
		(property "Description" "0R resistor in 0402 package with unspecified tolerance"
			(at 0 0 0)
			(layer "F.Fab")
			(hide yes)
			(effects
				(font
					(size 1.27 1.27)
					(thickness 0.15)
				)
			)
		)
		(property "Author" "Antmicro"
			(at 0 0 0)
			(layer "F.Fab")
			(hide yes)
			(effects
				(font
					(size 1 1)
					(thickness 0.15)
				)
			)
		)
		(property "Current" "1A"
			(at 0 0 0)
			(layer "F.Fab")
			(hide yes)
			(effects
				(font
					(size 1 1)
					(thickness 0.15)
				)
			)
		)
		(property "License" "Apache-2.0"
			(at 0 0 0)
			(layer "F.Fab")
			(hide yes)
			(effects
				(font
					(size 1 1)
					(thickness 0.15)
				)
			)
		)
		(property "MPN" "ERJ2GE0R00X"
			(at 0 0 0)
			(layer "F.Fab")
			(hide yes)
			(effects
				(font
					(size 1 1)
					(thickness 0.15)
				)
			)
		)
		(property "Manufacturer" "Panasonic"
			(at 0 0 0)
			(layer "F.Fab")
			(hide yes)
			(effects
				(font
					(size 1 1)
					(thickness 0.15)
				)
			)
		)
		(property "Tolerance" ""
			(at 0 0 0)
			(layer "F.Fab")
			(hide yes)
			(effects
				(font
					(size 1 1)
					(thickness 0.15)
				)
			)
		)
		(property "Val" "0R"
			(at 0 0 0)
			(layer "F.Fab")
			(hide yes)
			(effects
				(font
					(size 1 1)
					(thickness 0.15)
				)
			)
		)
		(sheetname "Supply")
		(sheetfile "supply.kicad_sch")
		(attr smd)
		(fp_rect
			(start -0.93 -0.47)
			(end 0.93 0.47)
			(stroke
				(width 0.05)
				(type solid)
			)
			(fill no)
			(layer "F.CrtYd")
		)
		(fp_rect
			(start -0.5 -0.25)
			(end 0.5 0.25)
			(stroke
				(width 0.15)
				(type solid)
			)
			(fill no)
			(layer "F.Fab")
		)
		(pad "1" smd roundrect
			(at -0.485 0)
			(size 0.59 0.64)
			(layers "F.Cu" "F.Mask" "F.Paste")
			(roundrect_rratio 0.25)
			(net 5 "GND")
			(pintype "passive")
		)
		(pad "2" smd roundrect
			(at 0.485 0)
			(size 0.59 0.64)
			(layers "F.Cu" "F.Mask" "F.Paste")
			(roundrect_rratio 0.25)
			(net 620 "/Supply/1V8_SS{slash}TR")
			(pintype "passive")
		)
	)
	(footprint "antmicro-footprints:R_0402_1005Metric"
		(layer "F.Cu")
		(at 187 118.185 90)
		(descr "Resistor SMD 0402")
		(tags "resistor SMD 0402")
		(property "Reference" "R123"
			(at -3.615 0.436828 90)
			(layer "F.SilkS")
			(effects
				(font
					(size 0.7 0.7)
					(thickness 0.15)
				)
				(justify left bottom)
			)
		)
		(property "Value" "R_0R_0402"
			(at 0 1.4 90)
			(layer "F.Fab")
			(effects
				(font
					(size 0.7 0.7)
					(thickness 0.15)
				)
				(justify left bottom)
			)
		)
		(property "Description" "0R resistor in 0402 package with unspecified tolerance"
			(at 0 0 90)
			(layer "F.Fab")
			(hide yes)
			(effects
				(font
					(size 1.27 1.27)
					(thickness 0.15)
				)
			)
		)
		(property "Author" "Antmicro"
			(at 305.185 -68.815 0)
			(layer "F.Fab")
			(hide yes)
			(effects
				(font
					(size 1 1)
					(thickness 0.15)
				)
			)
		)
		(property "Current" "1A"
			(at 305.185 -68.815 0)
			(layer "F.Fab")
			(hide yes)
			(effects
				(font
					(size 1 1)
					(thickness 0.15)
				)
			)
		)
		(property "License" "Apache-2.0"
			(at 305.185 -68.815 0)
			(layer "F.Fab")
			(hide yes)
			(effects
				(font
					(size 1 1)
					(thickness 0.15)
				)
			)
		)
		(property "MPN" "ERJ2GE0R00X"
			(at 305.185 -68.815 0)
			(layer "F.Fab")
			(hide yes)
			(effects
				(font
					(size 1 1)
					(thickness 0.15)
				)
			)
		)
		(property "Manufacturer" "Panasonic"
			(at 305.185 -68.815 0)
			(layer "F.Fab")
			(hide yes)
			(effects
				(font
					(size 1 1)
					(thickness 0.15)
				)
			)
		)
		(property "Tolerance" ""
			(at 305.185 -68.815 0)
			(layer "F.Fab")
			(hide yes)
			(effects
				(font
					(size 1 1)
					(thickness 0.15)
				)
			)
		)
		(property "Val" "0R"
			(at 305.185 -68.815 0)
			(layer "F.Fab")
			(hide yes)
			(effects
				(font
					(size 1 1)
					(thickness 0.15)
				)
			)
		)
		(sheetname "Supply")
		(sheetfile "supply.kicad_sch")
		(attr smd)
		(fp_rect
			(start -0.93 -0.47)
			(end 0.93 0.47)
			(stroke
				(width 0.05)
				(type solid)
			)
			(fill no)
			(layer "F.CrtYd")
		)
		(fp_rect
			(start -0.5 -0.25)
			(end 0.5 0.25)
			(stroke
				(width 0.15)
				(type solid)
			)
			(fill no)
			(layer "F.Fab")
		)
		(pad "1" smd roundrect
			(at -0.485 0 90)
			(size 0.59 0.64)
			(layers "F.Cu" "F.Mask" "F.Paste")
			(roundrect_rratio 0.25)
			(net 597 "/Supply/1V2_VCC_INT")
			(pintype "passive")
		)
		(pad "2" smd roundrect
			(at 0.485 0 90)
			(size 0.59 0.64)
			(layers "F.Cu" "F.Mask" "F.Paste")
			(roundrect_rratio 0.25)
			(net 616 "/Supply/1V2_FSEL")
			(pintype "passive")
		)
	)
	(footprint "antmicro-footprints:R_0805_2012Metric"
		(layer "F.Cu")
		(at 192.8 111.5 90)
		(property "Reference" "R145"
			(at -1.5 1.7 90)
			(layer "F.SilkS")
			(effects
				(font
					(size 0.7 0.7)
					(thickness 0.15)
				)
				(justify left bottom)
			)
		)
		(property "Value" "R_0R_0805"
			(at 0 1.8 90)
			(layer "F.Fab")
			(effects
				(font
					(size 0.7 0.7)
					(thickness 0.15)
				)
				(justify left bottom)
			)
		)
		(property "Description" "0R resistor in 0805 package with unspecified tolerance"
			(at 0 0 90)
			(layer "F.Fab")
			(hide yes)
			(effects
				(font
					(size 1.27 1.27)
					(thickness 0.15)
				)
			)
		)
		(property "Author" "Antmicro"
			(at 304.3 -81.3 0)
			(layer "F.Fab")
			(hide yes)
			(effects
				(font
					(size 1 1)
					(thickness 0.15)
				)
			)
		)
		(property "Current" "2.5A"
			(at 304.3 -81.3 0)
			(layer "F.Fab")
			(hide yes)
			(effects
				(font
					(size 1 1)
					(thickness 0.15)
				)
			)
		)
		(property "License" "Apache-2.0"
			(at 304.3 -81.3 0)
			(layer "F.Fab")
			(hide yes)
			(effects
				(font
					(size 1 1)
					(thickness 0.15)
				)
			)
		)
		(property "MPN" "CRCW08050000Z0EA"
			(at 304.3 -81.3 0)
			(layer "F.Fab")
			(hide yes)
			(effects
				(font
					(size 1 1)
					(thickness 0.15)
				)
			)
		)
		(property "Manufacturer" "Vishay"
			(at 304.3 -81.3 0)
			(layer "F.Fab")
			(hide yes)
			(effects
				(font
					(size 1 1)
					(thickness 0.15)
				)
			)
		)
		(property "Tolerance" ""
			(at 304.3 -81.3 0)
			(layer "F.Fab")
			(hide yes)
			(effects
				(font
					(size 1 1)
					(thickness 0.15)
				)
			)
		)
		(property "Val" "0R"
			(at 304.3 -81.3 0)
			(layer "F.Fab")
			(hide yes)
			(effects
				(font
					(size 1 1)
					(thickness 0.15)
				)
			)
		)
		(sheetname "Supply")
		(sheetfile "supply.kicad_sch")
		(attr smd)
		(fp_line
			(start -0.3 -0.701)
			(end 0.298 -0.701)
			(stroke
				(width 0.15)
				(type solid)
			)
			(layer "F.SilkS")
		)
		(fp_line
			(start -0.32 0.699)
			(end 0.28 0.699)
			(stroke
				(width 0.15)
				(type solid)
			)
			(layer "F.SilkS")
		)
		(fp_rect
			(start -1.75 -0.85)
			(end 1.75 0.85)
			(stroke
				(width 0.05)
				(type solid)
			)
			(fill no)
			(layer "F.CrtYd")
		)
		(fp_line
			(start -0.951 -0.682)
			(end 0.949 -0.682)
			(stroke
				(width 0.15)
				(type solid)
			)
			(layer "F.Fab")
		)
		(fp_line
			(start 0.949 -0.677)
			(end 0.949 0.675)
			(stroke
				(width 0.15)
				(type solid)
			)
			(layer "F.Fab")
		)
		(fp_line
			(start -0.951 -0.677)
			(end -0.951 0.675)
			(stroke
				(width 0.15)
				(type solid)
			)
			(layer "F.Fab")
		)
		(fp_line
			(start -0.951 0.68)
			(end 0.949 0.68)
			(stroke
				(width 0.15)
				(type solid)
			)
			(layer "F.Fab")
		)
		(pad "1" smd roundrect
			(at -1.1 -0.001 90)
			(size 1 1.4)
			(layers "F.Cu" "F.Mask" "F.Paste")
			(roundrect_rratio 0.15)
			(net 589 "/Supply/1V2_REG")
			(pintype "passive")
		)
		(pad "2" smd roundrect
			(at 1.1 -0.001 90)
			(size 1 1.4)
			(layers "F.Cu" "F.Mask" "F.Paste")
			(roundrect_rratio 0.15)
			(net 602 "1V2_SYS")
			(pintype "passive")
		)
	)
	(footprint "antmicro-footprints:V-QFN2030-12"
		(layer "F.Cu")
		(at 126.896172 100.378992 180)
		(property "Reference" "U12"
			(at -0.903828 -2.521008 180)
			(layer "F.SilkS")
			(effects
				(font
					(size 0.7 0.7)
					(thickness 0.15)
				)
				(justify left bottom)
			)
		)
		(property "Value" "AP62600SJ-7"
			(at -4 2.2 180)
			(layer "F.Fab")
			(effects
				(font
					(size 0.7 0.7)
					(thickness 0.15)
				)
				(justify left bottom)
			)
		)
		(property "Description" "Buck Switching Regulator IC Positive Fixed 0.6V 1 Output 6A 12-VFQFN"
			(at 0 0 180)
			(layer "F.Fab")
			(hide yes)
			(effects
				(font
					(size 1.27 1.27)
					(thickness 0.15)
				)
			)
		)
		(property "Author" "Antmicro"
			(at 253.792344 200.757984 0)
			(layer "F.Fab")
			(hide yes)
			(effects
				(font
					(size 1 1)
					(thickness 0.15)
				)
			)
		)
		(property "License" "Apache-2.0"
			(at 253.792344 200.757984 0)
			(layer "F.Fab")
			(hide yes)
			(effects
				(font
					(size 1 1)
					(thickness 0.15)
				)
			)
		)
		(property "MPN" "AP62600SJ-7"
			(at 253.792344 200.757984 0)
			(layer "F.Fab")
			(hide yes)
			(effects
				(font
					(size 1 1)
					(thickness 0.15)
				)
			)
		)
		(property "Manufacturer" "Diodes Incorporated"
			(at 253.792344 200.757984 0)
			(layer "F.Fab")
			(hide yes)
			(effects
				(font
					(size 1 1)
					(thickness 0.15)
				)
			)
		)
		(sheetname "Supply")
		(sheetfile "supply.kicad_sch")
		(attr smd)
		(fp_line
			(start 1.8 1.199)
			(end 0.8 1.199)
			(stroke
				(width 0.15)
				(type solid)
			)
			(layer "F.SilkS")
		)
		(fp_line
			(start 1.8 0.998)
			(end 1.8 1.199)
			(stroke
				(width 0.15)
				(type solid)
			)
			(layer "F.SilkS")
		)
		(fp_line
			(start 1.8 -1.276)
			(end 1.8 -1.025)
			(stroke
				(width 0.15)
				(type solid)
			)
			(layer "F.SilkS")
		)
		(fp_line
			(start -0.802 1.199)
			(end -1.801 1.199)
			(stroke
				(width 0.15)
				(type solid)
			)
			(layer "F.SilkS")
		)
		(fp_line
			(start -1.801 1.199)
			(end -1.801 0.998)
			(stroke
				(width 0.15)
				(type solid)
			)
			(layer "F.SilkS")
		)
		(fp_line
			(start -1.801 -1)
			(end -1.801 -1.2)
			(stroke
				(width 0.15)
				(type solid)
			)
			(layer "F.SilkS")
		)
		(fp_line
			(start -1.801 -1.2)
			(end -0.802 -1.2)
			(stroke
				(width 0.15)
				(type solid)
			)
			(layer "F.SilkS")
		)
		(fp_circle
			(center 0.497 -1.7)
			(end 0.548 -1.7)
			(stroke
				(width 0.15)
				(type solid)
			)
			(fill yes)
			(layer "F.SilkS")
		)
		(fp_rect
			(start -2.026 -1.525)
			(end 2.023 1.524)
			(stroke
				(width 0.05)
				(type solid)
			)
			(fill no)
			(layer "F.CrtYd")
		)
		(fp_line
			(start 1.3 -1)
			(end 1.5 -0.8)
			(stroke
				(width 0.15)
				(type solid)
			)
			(layer "F.Fab")
		)
		(fp_rect
			(start -1.526 -1.025)
			(end 1.523 1.024)
			(stroke
				(width 0.15)
				(type solid)
			)
			(fill no)
			(layer "F.Fab")
		)
		(pad "1" smd rect
			(at 0.498 -0.552 90)
			(size 1.6 0.35)
			(layers "F.Cu" "F.Mask" "F.Paste")
			(net 5 "GND")
			(pinfunction "PGND")
			(pintype "passive")
		)
		(pad "2" smd rect
			(at -0.5 -0.552 90)
			(size 1.6 0.35)
			(layers "F.Cu" "F.Mask" "F.Paste")
			(net 463 "VCC5V0_INT")
			(pinfunction "VIN")
			(pintype "power_in")
		)
		(pad "3" smd rect
			(at -1.45 -0.75 90)
			(size 0.35 0.8)
			(layers "F.Cu" "F.Mask" "F.Paste")
			(net 592 "/Supply/1V0_EN")
			(pinfunction "EN")
			(pintype "input")
		)
		(pad "4" smd rect
			(at -1.45 -0.25 90)
			(size 0.35 0.8)
			(layers "F.Cu" "F.Mask" "F.Paste")
			(net 612 "/Supply/1V0_MODE")
			(pinfunction "MODE")
			(pintype "input")
		)
		(pad "5" smd rect
			(at -1.45 0.248 90)
			(size 0.35 0.8)
			(layers "F.Cu" "F.Mask" "F.Paste")
			(net 611 "/Supply/1V0_FSEL")
			(pinfunction "FSEL")
			(pintype "input")
		)
		(pad "6" smd rect
			(at -1.45 0.748 90)
			(size 0.35 0.8)
			(layers "F.Cu" "F.Mask" "F.Paste")
			(net 658 "unconnected-(U12-PG-Pad6)")
			(pinfunction "PG")
			(pintype "open_collector+no_connect")
		)
		(pad "7" smd rect
			(at -0.5 0.949 180)
			(size 0.35 0.8)
			(layers "F.Cu" "F.Mask" "F.Paste")
			(net 581 "/Supply/1V0_BST")
			(pinfunction "BST")
			(pintype "input")
		)
		(pad "8" smd rect
			(at 0 0.55 90)
			(size 1.6 0.35)
			(layers "F.Cu" "F.Mask" "F.Paste")
			(net 582 "/Supply/1V0_SW")
			(pinfunction "SW")
			(pintype "output")
		)
		(pad "9" smd rect
			(at 1.449 0.748 270)
			(size 0.35 0.8)
			(layers "F.Cu" "F.Mask" "F.Paste")
			(net 593 "/Supply/1V0_VCC_INT")
			(pinfunction "VCC")
			(pintype "input")
		)
		(pad "10" smd rect
			(at 1.449 0.248 270)
			(size 0.35 0.8)
			(layers "F.Cu" "F.Mask" "F.Paste")
			(net 613 "/Supply/1V0_SS{slash}TR")
			(pinfunction "SS/TR")
			(pintype "input")
		)
		(pad "11" smd rect
			(at 1.449 -0.25 270)
			(size 0.35 0.8)
			(layers "F.Cu" "F.Mask" "F.Paste")
			(net 5 "GND")
			(pinfunction "GND")
			(pintype "passive")
		)
		(pad "12" smd rect
			(at 1.449 -0.75 270)
			(size 0.35 0.8)
			(layers "F.Cu" "F.Mask" "F.Paste")
			(net 599 "/Supply/1V0_FB")
			(pinfunction "FB")
			(pintype "input")
		)
	)
	(footprint "antmicro-footprints:R_0402_1005Metric"
		(layer "F.Cu")
		(at 184.1 111.85 -90)
		(descr "Resistor SMD 0402")
		(tags "resistor SMD 0402")
		(property "Reference" "R140"
			(at -0.75 -0.4 270)
			(layer "F.SilkS")
			(effects
				(font
					(size 0.7 0.7)
					(thickness 0.15)
				)
				(justify left bottom)
			)
		)
		(property "Value" "R_31k6_0402"
			(at 0 1.4 270)
			(layer "F.Fab")
			(effects
				(font
					(size 0.7 0.7)
					(thickness 0.15)
				)
				(justify left bottom)
			)
		)
		(property "Description" "31k6 resistor in 0402 package with 1% tolerance"
			(at 0 0 270)
			(layer "F.Fab")
			(hide yes)
			(effects
				(font
					(size 1.27 1.27)
					(thickness 0.15)
				)
			)
		)
		(property "Author" "Antmicro"
			(at 72.25 295.95 0)
			(layer "F.Fab")
			(hide yes)
			(effects
				(font
					(size 1 1)
					(thickness 0.15)
				)
			)
		)
		(property "License" "Apache-2.0"
			(at 72.25 295.95 0)
			(layer "F.Fab")
			(hide yes)
			(effects
				(font
					(size 1 1)
					(thickness 0.15)
				)
			)
		)
		(property "MPN" "CR0402-FX-3162GLF"
			(at 72.25 295.95 0)
			(layer "F.Fab")
			(hide yes)
			(effects
				(font
					(size 1 1)
					(thickness 0.15)
				)
			)
		)
		(property "Manufacturer" "Bourns"
			(at 72.25 295.95 0)
			(layer "F.Fab")
			(hide yes)
			(effects
				(font
					(size 1 1)
					(thickness 0.15)
				)
			)
		)
		(property "Tolerance" "1%"
			(at 72.25 295.95 0)
			(layer "F.Fab")
			(hide yes)
			(effects
				(font
					(size 1 1)
					(thickness 0.15)
				)
			)
		)
		(property "Val" "31k6"
			(at 72.25 295.95 0)
			(layer "F.Fab")
			(hide yes)
			(effects
				(font
					(size 1 1)
					(thickness 0.15)
				)
			)
		)
		(sheetname "Supply")
		(sheetfile "supply.kicad_sch")
		(attr smd)
		(fp_rect
			(start -0.93 -0.47)
			(end 0.93 0.47)
			(stroke
				(width 0.05)
				(type solid)
			)
			(fill no)
			(layer "F.CrtYd")
		)
		(fp_rect
			(start -0.5 -0.25)
			(end 0.5 0.25)
			(stroke
				(width 0.15)
				(type solid)
			)
			(fill no)
			(layer "F.Fab")
		)
		(pad "1" smd roundrect
			(at -0.485 0 270)
			(size 0.59 0.64)
			(layers "F.Cu" "F.Mask" "F.Paste")
			(roundrect_rratio 0.25)
			(net 589 "/Supply/1V2_REG")
			(pintype "passive")
		)
		(pad "2" smd roundrect
			(at 0.485 0 270)
			(size 0.59 0.64)
			(layers "F.Cu" "F.Mask" "F.Paste")
			(roundrect_rratio 0.25)
			(net 601 "/Supply/1V2_FB")
			(pintype "passive")
		)
	)
	(footprint "antmicro-footprints:C_0402_1005Metric"
		(layer "F.Cu")
		(at 190.3 111.635 90)
		(descr "Capacitor SMD 0402")
		(tags "capacitor SMD 0402")
		(property "Reference" "C180"
			(at 0.735 0.4 90)
			(layer "F.SilkS")
			(effects
				(font
					(size 0.7 0.7)
					(thickness 0.15)
				)
				(justify left bottom)
			)
		)
		(property "Value" "C_1u_0402"
			(at 0 1.4 90)
			(layer "F.Fab")
			(effects
				(font
					(size 0.7 0.7)
					(thickness 0.15)
				)
				(justify left bottom)
			)
		)
		(property "Description" " "
			(at 0 0 90)
			(layer "F.Fab")
			(hide yes)
			(effects
				(font
					(size 1.27 1.27)
					(thickness 0.15)
				)
			)
		)
		(property "Author" "Antmicro"
			(at 301.935 -78.665 0)
			(layer "F.Fab")
			(hide yes)
			(effects
				(font
					(size 1 1)
					(thickness 0.15)
				)
			)
		)
		(property "Dielectric" ""
			(at 301.935 -78.665 0)
			(layer "F.Fab")
			(hide yes)
			(effects
				(font
					(size 1 1)
					(thickness 0.15)
				)
			)
		)
		(property "License" "Apache-2.0"
			(at 301.935 -78.665 0)
			(layer "F.Fab")
			(hide yes)
			(effects
				(font
					(size 1 1)
					(thickness 0.15)
				)
			)
		)
		(property "MPN" "C1005X6S1A105K050BC"
			(at 301.935 -78.665 0)
			(layer "F.Fab")
			(hide yes)
			(effects
				(font
					(size 1 1)
					(thickness 0.15)
				)
			)
		)
		(property "Manufacturer" "TDK"
			(at 301.935 -78.665 0)
			(layer "F.Fab")
			(hide yes)
			(effects
				(font
					(size 1 1)
					(thickness 0.15)
				)
			)
		)
		(property "Val" "1u"
			(at 301.935 -78.665 0)
			(layer "F.Fab")
			(hide yes)
			(effects
				(font
					(size 1 1)
					(thickness 0.15)
				)
			)
		)
		(property "Voltage" ""
			(at 301.935 -78.665 0)
			(layer "F.Fab")
			(hide yes)
			(effects
				(font
					(size 1 1)
					(thickness 0.15)
				)
			)
		)
		(sheetname "Supply")
		(sheetfile "supply.kicad_sch")
		(attr smd)
		(fp_rect
			(start -0.94 -0.47)
			(end 0.94 0.47)
			(stroke
				(width 0.05)
				(type solid)
			)
			(fill no)
			(layer "F.CrtYd")
		)
		(fp_rect
			(start -0.499 -0.249)
			(end 0.499 0.249)
			(stroke
				(width 0.15)
				(type solid)
			)
			(fill no)
			(layer "F.Fab")
		)
		(pad "1" smd roundrect
			(at -0.484 0 90)
			(size 0.59 0.64)
			(layers "F.Cu" "F.Mask" "F.Paste")
			(roundrect_rratio 0.25)
			(net 589 "/Supply/1V2_REG")
			(pintype "passive")
		)
		(pad "2" smd roundrect
			(at 0.484 0 90)
			(size 0.59 0.64)
			(layers "F.Cu" "F.Mask" "F.Paste")
			(roundrect_rratio 0.25)
			(net 5 "GND")
			(pintype "passive")
		)
	)
	(footprint "antmicro-footprints:R_0805_2012Metric"
		(layer "F.Cu")
		(at 134.4 56.1 -90)
		(property "Reference" "R97"
			(at 1.7 -1.8 270)
			(layer "F.SilkS")
			(effects
				(font
					(size 0.7 0.7)
					(thickness 0.15)
				)
				(justify left bottom)
			)
		)
		(property "Value" "R_0R_0805"
			(at 0 1.8 270)
			(layer "F.Fab")
			(effects
				(font
					(size 0.7 0.7)
					(thickness 0.15)
				)
				(justify left bottom)
			)
		)
		(property "Description" "0R resistor in 0805 package with unspecified tolerance"
			(at 0 0 270)
			(layer "F.Fab")
			(hide yes)
			(effects
				(font
					(size 1.27 1.27)
					(thickness 0.15)
				)
			)
		)
		(property "Author" "Antmicro"
			(at 78.3 190.5 0)
			(layer "F.Fab")
			(hide yes)
			(effects
				(font
					(size 1 1)
					(thickness 0.15)
				)
			)
		)
		(property "Current" "2.5A"
			(at 78.3 190.5 0)
			(layer "F.Fab")
			(hide yes)
			(effects
				(font
					(size 1 1)
					(thickness 0.15)
				)
			)
		)
		(property "License" "Apache-2.0"
			(at 78.3 190.5 0)
			(layer "F.Fab")
			(hide yes)
			(effects
				(font
					(size 1 1)
					(thickness 0.15)
				)
			)
		)
		(property "MPN" "CRCW08050000Z0EA"
			(at 78.3 190.5 0)
			(layer "F.Fab")
			(hide yes)
			(effects
				(font
					(size 1 1)
					(thickness 0.15)
				)
			)
		)
		(property "Manufacturer" "Vishay"
			(at 78.3 190.5 0)
			(layer "F.Fab")
			(hide yes)
			(effects
				(font
					(size 1 1)
					(thickness 0.15)
				)
			)
		)
		(property "Tolerance" ""
			(at 78.3 190.5 0)
			(layer "F.Fab")
			(hide yes)
			(effects
				(font
					(size 1 1)
					(thickness 0.15)
				)
			)
		)
		(property "Val" "0R"
			(at 78.3 190.5 0)
			(layer "F.Fab")
			(hide yes)
			(effects
				(font
					(size 1 1)
					(thickness 0.15)
				)
			)
		)
		(sheetname "Supply")
		(sheetfile "supply.kicad_sch")
		(attr exclude_from_pos_files exclude_from_bom dnp)
		(fp_line
			(start -0.32 0.699)
			(end 0.28 0.699)
			(stroke
				(width 0.15)
				(type solid)
			)
			(layer "F.SilkS")
		)
		(fp_line
			(start -0.3 -0.701)
			(end 0.298 -0.701)
			(stroke
				(width 0.15)
				(type solid)
			)
			(layer "F.SilkS")
		)
		(fp_rect
			(start -1.75 -0.85)
			(end 1.75 0.85)
			(stroke
				(width 0.05)
				(type solid)
			)
			(fill no)
			(layer "F.CrtYd")
		)
		(fp_line
			(start -0.951 0.68)
			(end 0.949 0.68)
			(stroke
				(width 0.15)
				(type solid)
			)
			(layer "F.Fab")
		)
		(fp_line
			(start -0.951 -0.677)
			(end -0.951 0.675)
			(stroke
				(width 0.15)
				(type solid)
			)
			(layer "F.Fab")
		)
		(fp_line
			(start 0.949 -0.677)
			(end 0.949 0.675)
			(stroke
				(width 0.15)
				(type solid)
			)
			(layer "F.Fab")
		)
		(fp_line
			(start -0.951 -0.682)
			(end 0.949 -0.682)
			(stroke
				(width 0.15)
				(type solid)
			)
			(layer "F.Fab")
		)
		(pad "1" smd roundrect
			(at -1.1 -0.001 270)
			(size 1 1.4)
			(layers "F.Cu" "F.Mask" "F.Paste")
			(roundrect_rratio 0.15)
			(net 550 "VDD1V1")
			(pintype "passive")
		)
		(pad "2" smd roundrect
			(at 1.1 -0.001 270)
			(size 1 1.4)
			(layers "F.Cu" "F.Mask" "F.Paste")
			(roundrect_rratio 0.15)
			(net 461 "1V1_SYS")
			(pintype "passive")
		)
	)
	(footprint "antmicro-footprints:C_0603_1608Metric"
		(layer "F.Cu")
		(at 139.1 63.5 90)
		(descr "Capacitor SMD 0603")
		(tags "capacitor 0603")
		(property "Reference" "C140"
			(at -3.9 0.9 90)
			(layer "F.SilkS")
			(effects
				(font
					(size 0.7 0.7)
					(thickness 0.15)
				)
				(justify left bottom)
			)
		)
		(property "Value" "C_47u_0603"
			(at 0 1.6 90)
			(layer "F.Fab")
			(effects
				(font
					(size 0.7 0.7)
					(thickness 0.15)
				)
				(justify left bottom)
			)
		)
		(property "Description" " "
			(at 0 0 90)
			(layer "F.Fab")
			(hide yes)
			(effects
				(font
					(size 1.27 1.27)
					(thickness 0.15)
				)
			)
		)
		(property "Author" "Antmicro"
			(at 202.6 -75.6 0)
			(layer "F.Fab")
			(hide yes)
			(effects
				(font
					(size 1 1)
					(thickness 0.15)
				)
			)
		)
		(property "Dielectric" ""
			(at 202.6 -75.6 0)
			(layer "F.Fab")
			(hide yes)
			(effects
				(font
					(size 1 1)
					(thickness 0.15)
				)
			)
		)
		(property "License" "Apache-2.0"
			(at 202.6 -75.6 0)
			(layer "F.Fab")
			(hide yes)
			(effects
				(font
					(size 1 1)
					(thickness 0.15)
				)
			)
		)
		(property "MPN" "GRM188R60J476ME15D"
			(at 202.6 -75.6 0)
			(layer "F.Fab")
			(hide yes)
			(effects
				(font
					(size 1 1)
					(thickness 0.15)
				)
			)
		)
		(property "Manufacturer" "Murata"
			(at 202.6 -75.6 0)
			(layer "F.Fab")
			(hide yes)
			(effects
				(font
					(size 1 1)
					(thickness 0.15)
				)
			)
		)
		(property "Val" "47u"
			(at 202.6 -75.6 0)
			(layer "F.Fab")
			(hide yes)
			(effects
				(font
					(size 1 1)
					(thickness 0.15)
				)
			)
		)
		(property "Voltage" ""
			(at 202.6 -75.6 0)
			(layer "F.Fab")
			(hide yes)
			(effects
				(font
					(size 1 1)
					(thickness 0.15)
				)
			)
		)
		(sheetname "Supply")
		(sheetfile "supply.kicad_sch")
		(attr smd)
		(fp_line
			(start -0.3 -0.3)
			(end 0.3 -0.3)
			(stroke
				(width 0.15)
				(type solid)
			)
			(layer "F.SilkS")
		)
		(fp_line
			(start -0.3 0.3)
			(end 0.3 0.3)
			(stroke
				(width 0.15)
				(type solid)
			)
			(layer "F.SilkS")
		)
		(fp_rect
			(start -1.24 -0.7)
			(end 1.24 0.7)
			(stroke
				(width 0.05)
				(type solid)
			)
			(fill no)
			(layer "F.CrtYd")
		)
		(fp_rect
			(start -0.8 -0.4)
			(end 0.8 0.4)
			(stroke
				(width 0.15)
				(type solid)
			)
			(fill no)
			(layer "F.Fab")
		)
		(pad "1" smd roundrect
			(at -0.7 0 90)
			(size 0.6 0.8)
			(layers "F.Cu" "F.Mask" "F.Paste")
			(roundrect_rratio 0.2)
			(net 633 "/Supply/0V6_REG")
			(pintype "passive")
		)
		(pad "2" smd roundrect
			(at 0.7 0 90)
			(size 0.6 0.8)
			(layers "F.Cu" "F.Mask" "F.Paste")
			(roundrect_rratio 0.2)
			(net 5 "GND")
			(pintype "passive")
		)
	)
	(footprint "antmicro-footprints:C_0603_1608Metric"
		(layer "F.Cu")
		(at 179.6 57.1 90)
		(descr "Capacitor SMD 0603")
		(tags "capacitor 0603")
		(property "Reference" "C138"
			(at -1.5 1.3 90)
			(layer "F.SilkS")
			(effects
				(font
					(size 0.7 0.7)
					(thickness 0.15)
				)
				(justify left bottom)
			)
		)
		(property "Value" "C_10n_0603"
			(at 0 1.6 90)
			(layer "F.Fab")
			(effects
				(font
					(size 0.7 0.7)
					(thickness 0.15)
				)
				(justify left bottom)
			)
		)
		(property "Description" " "
			(at 0 0 90)
			(layer "F.Fab")
			(hide yes)
			(effects
				(font
					(size 1.27 1.27)
					(thickness 0.15)
				)
			)
		)
		(property "Author" "Antmicro"
			(at 236.7 -122.5 0)
			(layer "F.Fab")
			(hide yes)
			(effects
				(font
					(size 1 1)
					(thickness 0.15)
				)
			)
		)
		(property "Dielectric" ""
			(at 236.7 -122.5 0)
			(layer "F.Fab")
			(hide yes)
			(effects
				(font
					(size 1 1)
					(thickness 0.15)
				)
			)
		)
		(property "License" "Apache-2.0"
			(at 236.7 -122.5 0)
			(layer "F.Fab")
			(hide yes)
			(effects
				(font
					(size 1 1)
					(thickness 0.15)
				)
			)
		)
		(property "MPN" "06031C103JAT2A"
			(at 236.7 -122.5 0)
			(layer "F.Fab")
			(hide yes)
			(effects
				(font
					(size 1 1)
					(thickness 0.15)
				)
			)
		)
		(property "Manufacturer" "AVX"
			(at 236.7 -122.5 0)
			(layer "F.Fab")
			(hide yes)
			(effects
				(font
					(size 1 1)
					(thickness 0.15)
				)
			)
		)
		(property "Val" "10n"
			(at 236.7 -122.5 0)
			(layer "F.Fab")
			(hide yes)
			(effects
				(font
					(size 1 1)
					(thickness 0.15)
				)
			)
		)
		(property "Voltage" ""
			(at 236.7 -122.5 0)
			(layer "F.Fab")
			(hide yes)
			(effects
				(font
					(size 1 1)
					(thickness 0.15)
				)
			)
		)
		(sheetname "Supply")
		(sheetfile "supply.kicad_sch")
		(attr smd)
		(fp_line
			(start -0.3 -0.3)
			(end 0.3 -0.3)
			(stroke
				(width 0.15)
				(type solid)
			)
			(layer "F.SilkS")
		)
		(fp_line
			(start -0.3 0.3)
			(end 0.3 0.3)
			(stroke
				(width 0.15)
				(type solid)
			)
			(layer "F.SilkS")
		)
		(fp_rect
			(start -1.24 -0.7)
			(end 1.24 0.7)
			(stroke
				(width 0.05)
				(type solid)
			)
			(fill no)
			(layer "F.CrtYd")
		)
		(fp_rect
			(start -0.8 -0.4)
			(end 0.8 0.4)
			(stroke
				(width 0.15)
				(type solid)
			)
			(fill no)
			(layer "F.Fab")
		)
		(pad "1" smd roundrect
			(at -0.7 0 90)
			(size 0.6 0.8)
			(layers "F.Cu" "F.Mask" "F.Paste")
			(roundrect_rratio 0.2)
			(net 66 "VDDQ")
			(pintype "passive")
		)
		(pad "2" smd roundrect
			(at 0.7 0 90)
			(size 0.6 0.8)
			(layers "F.Cu" "F.Mask" "F.Paste")
			(roundrect_rratio 0.2)
			(net 5 "GND")
			(pintype "passive")
		)
	)
	(footprint "antmicro-footprints:C_0805_2012Metric"
		(layer "F.Cu")
		(at 110.8492 112.05 90)
		(descr "Capacitor SMD 0805")
		(tags "capacitor SMD 0805")
		(property "Reference" "C127"
			(at 1.65 0.3508 90)
			(layer "F.SilkS")
			(effects
				(font
					(size 0.7 0.7)
					(thickness 0.15)
				)
				(justify left bottom)
			)
		)
		(property "Value" "C_22u_0805_16V"
			(at 0 1.947 90)
			(layer "F.Fab")
			(effects
				(font
					(size 0.7 0.7)
					(thickness 0.15)
				)
				(justify left bottom)
			)
		)
		(property "Description" " "
			(at 0 0 90)
			(layer "F.Fab")
			(hide yes)
			(effects
				(font
					(size 1.27 1.27)
					(thickness 0.15)
				)
			)
		)
		(property "Author" "Antmicro"
			(at 222.8992 1.2008 0)
			(layer "F.Fab")
			(hide yes)
			(effects
				(font
					(size 1 1)
					(thickness 0.15)
				)
			)
		)
		(property "Dielectric" ""
			(at 222.8992 1.2008 0)
			(layer "F.Fab")
			(hide yes)
			(effects
				(font
					(size 1 1)
					(thickness 0.15)
				)
			)
		)
		(property "License" "Apache-2.0"
			(at 222.8992 1.2008 0)
			(layer "F.Fab")
			(hide yes)
			(effects
				(font
					(size 1 1)
					(thickness 0.15)
				)
			)
		)
		(property "MPN" "GRT21BR61C226ME13L"
			(at 222.8992 1.2008 0)
			(layer "F.Fab")
			(hide yes)
			(effects
				(font
					(size 1 1)
					(thickness 0.15)
				)
			)
		)
		(property "Manufacturer" "Murata"
			(at 222.8992 1.2008 0)
			(layer "F.Fab")
			(hide yes)
			(effects
				(font
					(size 1 1)
					(thickness 0.15)
				)
			)
		)
		(property "Val" "22u/16V"
			(at 222.8992 1.2008 0)
			(layer "F.Fab")
			(hide yes)
			(effects
				(font
					(size 1 1)
					(thickness 0.15)
				)
			)
		)
		(property "Voltage" ""
			(at 222.8992 1.2008 0)
			(layer "F.Fab")
			(hide yes)
			(effects
				(font
					(size 1 1)
					(thickness 0.15)
				)
			)
		)
		(sheetname "Supply")
		(sheetfile "supply.kicad_sch")
		(attr smd)
		(fp_line
			(start -0.3 -0.8)
			(end 0.3 -0.8)
			(stroke
				(width 0.15)
				(type solid)
			)
			(layer "F.SilkS")
		)
		(fp_line
			(start -0.3 0.8)
			(end 0.3 0.8)
			(stroke
				(width 0.15)
				(type solid)
			)
			(layer "F.SilkS")
		)
		(fp_rect
			(start -1.9 -0.93)
			(end 1.9 0.93)
			(stroke
				(width 0.05)
				(type solid)
			)
			(fill no)
			(layer "F.CrtYd")
		)
		(fp_rect
			(start -0.95 -0.675)
			(end 0.95 0.675)
			(stroke
				(width 0.15)
				(type solid)
			)
			(fill no)
			(layer "F.Fab")
		)
		(pad "1" smd rect
			(at -1.05 0 90)
			(size 1.2 1.2)
			(layers "F.Cu" "F.Mask" "F.Paste")
			(net 224 "VIN")
			(pintype "passive")
		)
		(pad "2" smd rect
			(at 1.05 0 90)
			(size 1.2 1.2)
			(layers "F.Cu" "F.Mask" "F.Paste")
			(net 5 "GND")
			(pintype "passive")
		)
	)
	(footprint "antmicro-footprints:R_0402_1005Metric"
		(layer "F.Cu")
		(at 129.95 90.074 180)
		(descr "Resistor SMD 0402")
		(tags "resistor SMD 0402")
		(property "Reference" "R122"
			(at 1.285328 2.474 180)
			(layer "F.SilkS")
			(effects
				(font
					(size 0.7 0.7)
					(thickness 0.15)
				)
				(justify left bottom)
			)
		)
		(property "Value" "R_100k_0402"
			(at 0 1.4 180)
			(layer "F.Fab")
			(effects
				(font
					(size 0.7 0.7)
					(thickness 0.15)
				)
				(justify left bottom)
			)
		)
		(property "Description" "100k resistor in 0402 package with 1% tolerance"
			(at 0 0 180)
			(layer "F.Fab")
			(hide yes)
			(effects
				(font
					(size 1.27 1.27)
					(thickness 0.15)
				)
			)
		)
		(property "Author" "Antmicro"
			(at 259.9 180.148 0)
			(layer "F.Fab")
			(hide yes)
			(effects
				(font
					(size 1 1)
					(thickness 0.15)
				)
			)
		)
		(property "License" "Apache-2.0"
			(at 259.9 180.148 0)
			(layer "F.Fab")
			(hide yes)
			(effects
				(font
					(size 1 1)
					(thickness 0.15)
				)
			)
		)
		(property "MPN" "CR0402-FX-1003GLF"
			(at 259.9 180.148 0)
			(layer "F.Fab")
			(hide yes)
			(effects
				(font
					(size 1 1)
					(thickness 0.15)
				)
			)
		)
		(property "Manufacturer" "Bourns"
			(at 259.9 180.148 0)
			(layer "F.Fab")
			(hide yes)
			(effects
				(font
					(size 1 1)
					(thickness 0.15)
				)
			)
		)
		(property "Tolerance" "1%"
			(at 259.9 180.148 0)
			(layer "F.Fab")
			(hide yes)
			(effects
				(font
					(size 1 1)
					(thickness 0.15)
				)
			)
		)
		(property "Val" "100k"
			(at 259.9 180.148 0)
			(layer "F.Fab")
			(hide yes)
			(effects
				(font
					(size 1 1)
					(thickness 0.15)
				)
			)
		)
		(sheetname "Supply")
		(sheetfile "supply.kicad_sch")
		(attr smd)
		(fp_rect
			(start -0.93 -0.47)
			(end 0.93 0.47)
			(stroke
				(width 0.05)
				(type solid)
			)
			(fill no)
			(layer "F.CrtYd")
		)
		(fp_rect
			(start -0.5 -0.25)
			(end 0.5 0.25)
			(stroke
				(width 0.15)
				(type solid)
			)
			(fill no)
			(layer "F.Fab")
		)
		(pad "1" smd roundrect
			(at -0.485 0 180)
			(size 0.59 0.64)
			(layers "F.Cu" "F.Mask" "F.Paste")
			(roundrect_rratio 0.25)
			(net 605 "/Supply/1V8_PG")
			(pintype "passive")
		)
		(pad "2" smd roundrect
			(at 0.485 0 180)
			(size 0.59 0.64)
			(layers "F.Cu" "F.Mask" "F.Paste")
			(roundrect_rratio 0.25)
			(net 590 "/Supply/1V1_EN")
			(pintype "passive")
		)
	)
	(footprint "antmicro-footprints:R_0402_1005Metric"
		(layer "F.Cu")
		(at 140.1825 84.699)
		(descr "Resistor SMD 0402")
		(tags "resistor SMD 0402")
		(property "Reference" "R113"
			(at -3.6825 -0.699 0)
			(layer "F.SilkS")
			(effects
				(font
					(size 0.7 0.7)
					(thickness 0.15)
				)
				(justify left bottom)
			)
		)
		(property "Value" "R_330R_0402"
			(at 0 1.4 0)
			(layer "F.Fab")
			(effects
				(font
					(size 0.7 0.7)
					(thickness 0.15)
				)
				(justify left bottom)
			)
		)
		(property "Description" "330R resistor in 0402 package with 1% tolerance"
			(at 0 0 0)
			(layer "F.Fab")
			(hide yes)
			(effects
				(font
					(size 1.27 1.27)
					(thickness 0.15)
				)
			)
		)
		(property "Author" "Antmicro"
			(at 0 0 0)
			(layer "F.Fab")
			(hide yes)
			(effects
				(font
					(size 1 1)
					(thickness 0.15)
				)
			)
		)
		(property "License" "Apache-2.0"
			(at 0 0 0)
			(layer "F.Fab")
			(hide yes)
			(effects
				(font
					(size 1 1)
					(thickness 0.15)
				)
			)
		)
		(property "MPN" "CR0402-FX-3300GLF"
			(at 0 0 0)
			(layer "F.Fab")
			(hide yes)
			(effects
				(font
					(size 1 1)
					(thickness 0.15)
				)
			)
		)
		(property "Manufacturer" "Bourns"
			(at 0 0 0)
			(layer "F.Fab")
			(hide yes)
			(effects
				(font
					(size 1 1)
					(thickness 0.15)
				)
			)
		)
		(property "Tolerance" "1%"
			(at 0 0 0)
			(layer "F.Fab")
			(hide yes)
			(effects
				(font
					(size 1 1)
					(thickness 0.15)
				)
			)
		)
		(property "Val" "330R"
			(at 0 0 0)
			(layer "F.Fab")
			(hide yes)
			(effects
				(font
					(size 1 1)
					(thickness 0.15)
				)
			)
		)
		(sheetname "Supply")
		(sheetfile "supply.kicad_sch")
		(attr smd)
		(fp_rect
			(start -0.93 -0.47)
			(end 0.93 0.47)
			(stroke
				(width 0.05)
				(type solid)
			)
			(fill no)
			(layer "F.CrtYd")
		)
		(fp_rect
			(start -0.5 -0.25)
			(end 0.5 0.25)
			(stroke
				(width 0.15)
				(type solid)
			)
			(fill no)
			(layer "F.Fab")
		)
		(pad "1" smd roundrect
			(at -0.485 0)
			(size 0.59 0.64)
			(layers "F.Cu" "F.Mask" "F.Paste")
			(roundrect_rratio 0.25)
			(net 557 "Net-(PWR5-Pad2)")
			(pintype "passive")
		)
		(pad "2" smd roundrect
			(at 0.485 0)
			(size 0.59 0.64)
			(layers "F.Cu" "F.Mask" "F.Paste")
			(roundrect_rratio 0.25)
			(net 237 "Net-(Q11-D)")
			(pintype "passive")
		)
	)
	(footprint "antmicro-footprints:C_0402_1005Metric"
		(layer "F.Cu")
		(at 111.94 99.449 180)
		(descr "Capacitor SMD 0402")
		(tags "capacitor SMD 0402")
		(property "Reference" "C162"
			(at 3.64 -0.351 180)
			(layer "F.SilkS")
			(effects
				(font
					(size 0.7 0.7)
					(thickness 0.15)
				)
				(justify left bottom)
			)
		)
		(property "Value" "C_1u_0402"
			(at 0 1.4 180)
			(layer "F.Fab")
			(effects
				(font
					(size 0.7 0.7)
					(thickness 0.15)
				)
				(justify left bottom)
			)
		)
		(property "Description" " "
			(at 0 0 180)
			(layer "F.Fab")
			(hide yes)
			(effects
				(font
					(size 1.27 1.27)
					(thickness 0.15)
				)
			)
		)
		(property "Author" "Antmicro"
			(at 223.88 198.898 0)
			(layer "F.Fab")
			(hide yes)
			(effects
				(font
					(size 1 1)
					(thickness 0.15)
				)
			)
		)
		(property "Dielectric" ""
			(at 223.88 198.898 0)
			(layer "F.Fab")
			(hide yes)
			(effects
				(font
					(size 1 1)
					(thickness 0.15)
				)
			)
		)
		(property "License" "Apache-2.0"
			(at 223.88 198.898 0)
			(layer "F.Fab")
			(hide yes)
			(effects
				(font
					(size 1 1)
					(thickness 0.15)
				)
			)
		)
		(property "MPN" "C1005X6S1A105K050BC"
			(at 223.88 198.898 0)
			(layer "F.Fab")
			(hide yes)
			(effects
				(font
					(size 1 1)
					(thickness 0.15)
				)
			)
		)
		(property "Manufacturer" "TDK"
			(at 223.88 198.898 0)
			(layer "F.Fab")
			(hide yes)
			(effects
				(font
					(size 1 1)
					(thickness 0.15)
				)
			)
		)
		(property "Val" "1u"
			(at 223.88 198.898 0)
			(layer "F.Fab")
			(hide yes)
			(effects
				(font
					(size 1 1)
					(thickness 0.15)
				)
			)
		)
		(property "Voltage" ""
			(at 223.88 198.898 0)
			(layer "F.Fab")
			(hide yes)
			(effects
				(font
					(size 1 1)
					(thickness 0.15)
				)
			)
		)
		(sheetname "Supply")
		(sheetfile "supply.kicad_sch")
		(attr smd)
		(fp_rect
			(start -0.94 -0.47)
			(end 0.94 0.47)
			(stroke
				(width 0.05)
				(type solid)
			)
			(fill no)
			(layer "F.CrtYd")
		)
		(fp_rect
			(start -0.499 -0.249)
			(end 0.499 0.249)
			(stroke
				(width 0.15)
				(type solid)
			)
			(fill no)
			(layer "F.Fab")
		)
		(pad "1" smd roundrect
			(at -0.484 0 180)
			(size 0.59 0.64)
			(layers "F.Cu" "F.Mask" "F.Paste")
			(roundrect_rratio 0.25)
			(net 609 "/Supply/3V3_VCC_INT")
			(pintype "passive")
		)
		(pad "2" smd roundrect
			(at 0.484 0 180)
			(size 0.59 0.64)
			(layers "F.Cu" "F.Mask" "F.Paste")
			(roundrect_rratio 0.25)
			(net 5 "GND")
			(pintype "passive")
		)
	)
	(footprint "antmicro-footprints:C_0603_1608Metric"
		(layer "F.Cu")
		(at 125.3 59.85 180)
		(descr "Capacitor SMD 0603")
		(tags "capacitor 0603")
		(property "Reference" "C183"
			(at 3.9 -0.35 180)
			(layer "F.SilkS")
			(effects
				(font
					(size 0.7 0.7)
					(thickness 0.15)
				)
				(justify left bottom)
			)
		)
		(property "Value" "C_100n_0603"
			(at 0 1.6 180)
			(layer "F.Fab")
			(effects
				(font
					(size 0.7 0.7)
					(thickness 0.15)
				)
				(justify left bottom)
			)
		)
		(property "Description" " "
			(at 0 0 180)
			(layer "F.Fab")
			(hide yes)
			(effects
				(font
					(size 1.27 1.27)
					(thickness 0.15)
				)
			)
		)
		(property "Author" "Antmicro"
			(at 250.6 119.7 0)
			(layer "F.Fab")
			(hide yes)
			(effects
				(font
					(size 1 1)
					(thickness 0.15)
				)
			)
		)
		(property "Dielectric" ""
			(at 250.6 119.7 0)
			(layer "F.Fab")
			(hide yes)
			(effects
				(font
					(size 1 1)
					(thickness 0.15)
				)
			)
		)
		(property "License" "Apache-2.0"
			(at 250.6 119.7 0)
			(layer "F.Fab")
			(hide yes)
			(effects
				(font
					(size 1 1)
					(thickness 0.15)
				)
			)
		)
		(property "MPN" "0603YC104KAZ2A"
			(at 250.6 119.7 0)
			(layer "F.Fab")
			(hide yes)
			(effects
				(font
					(size 1 1)
					(thickness 0.15)
				)
			)
		)
		(property "Manufacturer" "AVX"
			(at 250.6 119.7 0)
			(layer "F.Fab")
			(hide yes)
			(effects
				(font
					(size 1 1)
					(thickness 0.15)
				)
			)
		)
		(property "Val" "100n"
			(at 250.6 119.7 0)
			(layer "F.Fab")
			(hide yes)
			(effects
				(font
					(size 1 1)
					(thickness 0.15)
				)
			)
		)
		(property "Voltage" ""
			(at 250.6 119.7 0)
			(layer "F.Fab")
			(hide yes)
			(effects
				(font
					(size 1 1)
					(thickness 0.15)
				)
			)
		)
		(sheetname "Supply")
		(sheetfile "supply.kicad_sch")
		(attr exclude_from_pos_files exclude_from_bom dnp)
		(fp_line
			(start -0.3 0.3)
			(end 0.3 0.3)
			(stroke
				(width 0.15)
				(type solid)
			)
			(layer "F.SilkS")
		)
		(fp_line
			(start -0.3 -0.3)
			(end 0.3 -0.3)
			(stroke
				(width 0.15)
				(type solid)
			)
			(layer "F.SilkS")
		)
		(fp_rect
			(start -1.24 -0.7)
			(end 1.24 0.7)
			(stroke
				(width 0.05)
				(type solid)
			)
			(fill no)
			(layer "F.CrtYd")
		)
		(fp_rect
			(start -0.8 -0.4)
			(end 0.8 0.4)
			(stroke
				(width 0.15)
				(type solid)
			)
			(fill no)
			(layer "F.Fab")
		)
		(pad "1" smd roundrect
			(at -0.7 0 180)
			(size 0.6 0.8)
			(layers "F.Cu" "F.Mask" "F.Paste")
			(roundrect_rratio 0.2)
			(net 463 "VCC5V0_INT")
			(pintype "passive")
		)
		(pad "2" smd roundrect
			(at 0.7 0 180)
			(size 0.6 0.8)
			(layers "F.Cu" "F.Mask" "F.Paste")
			(roundrect_rratio 0.2)
			(net 5 "GND")
			(pintype "passive")
		)
	)
	(footprint "antmicro-footprints:C_0603_1608Metric"
		(layer "F.Cu")
		(at 128.6 68.3 180)
		(descr "Capacitor SMD 0603")
		(tags "capacitor 0603")
		(property "Reference" "C193"
			(at 3.9 -0.4 180)
			(layer "F.SilkS")
			(effects
				(font
					(size 0.7 0.7)
					(thickness 0.15)
				)
				(justify left bottom)
			)
		)
		(property "Value" "C_22u_0603"
			(at 0 1.6 180)
			(layer "F.Fab")
			(effects
				(font
					(size 0.7 0.7)
					(thickness 0.15)
				)
				(justify left bottom)
			)
		)
		(property "Description" " "
			(at 0 0 180)
			(layer "F.Fab")
			(hide yes)
			(effects
				(font
					(size 1.27 1.27)
					(thickness 0.15)
				)
			)
		)
		(property "Author" "Antmicro"
			(at 257.2 136.6 0)
			(layer "F.Fab")
			(hide yes)
			(effects
				(font
					(size 1 1)
					(thickness 0.15)
				)
			)
		)
		(property "Dielectric" ""
			(at 257.2 136.6 0)
			(layer "F.Fab")
			(hide yes)
			(effects
				(font
					(size 1 1)
					(thickness 0.15)
				)
			)
		)
		(property "License" "Apache-2.0"
			(at 257.2 136.6 0)
			(layer "F.Fab")
			(hide yes)
			(effects
				(font
					(size 1 1)
					(thickness 0.15)
				)
			)
		)
		(property "MPN" "GRM188R60J226MEA0D"
			(at 257.2 136.6 0)
			(layer "F.Fab")
			(hide yes)
			(effects
				(font
					(size 1 1)
					(thickness 0.15)
				)
			)
		)
		(property "Manufacturer" "Murata"
			(at 257.2 136.6 0)
			(layer "F.Fab")
			(hide yes)
			(effects
				(font
					(size 1 1)
					(thickness 0.15)
				)
			)
		)
		(property "Val" "22u"
			(at 257.2 136.6 0)
			(layer "F.Fab")
			(hide yes)
			(effects
				(font
					(size 1 1)
					(thickness 0.15)
				)
			)
		)
		(property "Voltage" ""
			(at 257.2 136.6 0)
			(layer "F.Fab")
			(hide yes)
			(effects
				(font
					(size 1 1)
					(thickness 0.15)
				)
			)
		)
		(sheetname "Supply")
		(sheetfile "supply.kicad_sch")
		(attr exclude_from_pos_files exclude_from_bom dnp)
		(fp_line
			(start -0.3 0.3)
			(end 0.3 0.3)
			(stroke
				(width 0.15)
				(type solid)
			)
			(layer "F.SilkS")
		)
		(fp_line
			(start -0.3 -0.3)
			(end 0.3 -0.3)
			(stroke
				(width 0.15)
				(type solid)
			)
			(layer "F.SilkS")
		)
		(fp_rect
			(start -1.24 -0.7)
			(end 1.24 0.7)
			(stroke
				(width 0.05)
				(type solid)
			)
			(fill no)
			(layer "F.CrtYd")
		)
		(fp_rect
			(start -0.8 -0.4)
			(end 0.8 0.4)
			(stroke
				(width 0.15)
				(type solid)
			)
			(fill no)
			(layer "F.Fab")
		)
		(pad "1" smd roundrect
			(at -0.7 0 180)
			(size 0.6 0.8)
			(layers "F.Cu" "F.Mask" "F.Paste")
			(roundrect_rratio 0.2)
			(net 551 "/Supply/VDD1V8")
			(pintype "passive")
		)
		(pad "2" smd roundrect
			(at 0.7 0 180)
			(size 0.6 0.8)
			(layers "F.Cu" "F.Mask" "F.Paste")
			(roundrect_rratio 0.2)
			(net 5 "GND")
			(pintype "passive")
		)
	)
	(footprint "antmicro-footprints:L_2020_5252Metric"
		(layer "F.Cu")
		(at 130.3 62.475 -90)
		(property "Reference" "L7"
			(at -3.275 -1.6 0)
			(layer "F.SilkS")
			(effects
				(font
					(size 0.7 0.7)
					(thickness 0.15)
				)
				(justify left bottom)
			)
		)
		(property "Value" "L_4u7_2.8A_2020"
			(at 0 4 270)
			(layer "F.Fab")
			(effects
				(font
					(size 0.7 0.7)
					(thickness 0.15)
				)
				(justify left bottom)
			)
		)
		(property "Author" "Antmicro"
			(at 67.825 192.775 0)
			(layer "F.Fab")
			(hide yes)
			(effects
				(font
					(size 1 1)
					(thickness 0.15)
				)
			)
		)
		(property "IMax" ""
			(at 67.825 192.775 0)
			(layer "F.Fab")
			(hide yes)
			(effects
				(font
					(size 1 1)
					(thickness 0.15)
				)
			)
		)
		(property "ISat" ""
			(at 67.825 192.775 0)
			(layer "F.Fab")
			(hide yes)
			(effects
				(font
					(size 1 1)
					(thickness 0.15)
				)
			)
		)
		(property "License" "Apache-2.0"
			(at 67.825 192.775 0)
			(layer "F.Fab")
			(hide yes)
			(effects
				(font
					(size 1 1)
					(thickness 0.15)
				)
			)
		)
		(property "MPN" "IHLP2020BZER4R7M01"
			(at 67.825 192.775 0)
			(layer "F.Fab")
			(hide yes)
			(effects
				(font
					(size 1 1)
					(thickness 0.15)
				)
			)
		)
		(property "Manufacturer" "Vishay"
			(at 67.825 192.775 0)
			(layer "F.Fab")
			(hide yes)
			(effects
				(font
					(size 1 1)
					(thickness 0.15)
				)
			)
		)
		(property "Size" "5.18x5.18"
			(at 67.825 192.775 0)
			(layer "F.Fab")
			(hide yes)
			(effects
				(font
					(size 1 1)
					(thickness 0.15)
				)
			)
		)
		(property "Val" "4u7/2.8A"
			(at 67.825 192.775 0)
			(layer "F.Fab")
			(hide yes)
			(effects
				(font
					(size 1 1)
					(thickness 0.15)
				)
			)
		)
		(sheetname "Supply")
		(sheetfile "supply.kicad_sch")
		(attr exclude_from_pos_files exclude_from_bom dnp)
		(fp_line
			(start -2.999 2.843)
			(end 2.996 2.843)
			(stroke
				(width 0.15)
				(type solid)
			)
			(layer "F.SilkS")
		)
		(fp_line
			(start 2.996 2.843)
			(end 2.996 1.729)
			(stroke
				(width 0.15)
				(type solid)
			)
			(layer "F.SilkS")
		)
		(fp_line
			(start -2.999 1.729)
			(end -2.999 2.843)
			(stroke
				(width 0.15)
				(type solid)
			)
			(layer "F.SilkS")
		)
		(fp_line
			(start 2.996 -1.73)
			(end 2.996 -2.846)
			(stroke
				(width 0.15)
				(type solid)
			)
			(layer "F.SilkS")
		)
		(fp_line
			(start -2.999 -2.846)
			(end -2.999 -1.73)
			(stroke
				(width 0.15)
				(type solid)
			)
			(layer "F.SilkS")
		)
		(fp_line
			(start 2.996 -2.846)
			(end -2.999 -2.846)
			(stroke
				(width 0.15)
				(type solid)
			)
			(layer "F.SilkS")
		)
		(fp_line
			(start -3.13 2.97)
			(end -3.13 1.65)
			(stroke
				(width 0.05)
				(type solid)
			)
			(layer "F.CrtYd")
		)
		(fp_line
			(start 3.12 2.97)
			(end -3.13 2.97)
			(stroke
				(width 0.05)
				(type solid)
			)
			(layer "F.CrtYd")
		)
		(fp_line
			(start -3.29 1.65)
			(end -3.29 -1.67)
			(stroke
				(width 0.05)
				(type solid)
			)
			(layer "F.CrtYd")
		)
		(fp_line
			(start -3.13 1.65)
			(end -3.29 1.65)
			(stroke
				(width 0.05)
				(type solid)
			)
			(layer "F.CrtYd")
		)
		(fp_line
			(start 3.12 1.65)
			(end 3.12 2.97)
			(stroke
				(width 0.05)
				(type solid)
			)
			(layer "F.CrtYd")
		)
		(fp_line
			(start 3.26 1.65)
			(end 3.12 1.65)
			(stroke
				(width 0.05)
				(type solid)
			)
			(layer "F.CrtYd")
		)
		(fp_line
			(start -3.29 -1.67)
			(end -3.13 -1.67)
			(stroke
				(width 0.05)
				(type solid)
			)
			(layer "F.CrtYd")
		)
		(fp_line
			(start -3.13 -1.67)
			(end -3.13 -2.98)
			(stroke
				(width 0.05)
				(type solid)
			)
			(layer "F.CrtYd")
		)
		(fp_line
			(start 3.12 -1.67)
			(end 3.26 -1.67)
			(stroke
				(width 0.05)
				(type solid)
			)
			(layer "F.CrtYd")
		)
		(fp_line
			(start 3.26 -1.67)
			(end 3.26 1.65)
			(stroke
				(width 0.05)
				(type solid)
			)
			(layer "F.CrtYd")
		)
		(fp_line
			(start -3.13 -2.98)
			(end 3.12 -2.98)
			(stroke
				(width 0.05)
				(type solid)
			)
			(layer "F.CrtYd")
		)
		(fp_line
			(start 3.12 -2.98)
			(end 3.12 -1.67)
			(stroke
				(width 0.05)
				(type solid)
			)
			(layer "F.CrtYd")
		)
		(fp_line
			(start -2.871 2.717)
			(end 2.87 2.717)
			(stroke
				(width 0.15)
				(type solid)
			)
			(layer "F.Fab")
		)
		(fp_line
			(start 2.87 2.717)
			(end 2.87 -2.718)
			(stroke
				(width 0.15)
				(type solid)
			)
			(layer "F.Fab")
		)
		(fp_line
			(start -2.871 -2.718)
			(end -2.871 2.717)
			(stroke
				(width 0.15)
				(type solid)
			)
			(layer "F.Fab")
		)
		(fp_line
			(start 2.87 -2.718)
			(end -2.871 -2.718)
			(stroke
				(width 0.15)
				(type solid)
			)
			(layer "F.Fab")
		)
		(pad "1" smd rect
			(at -2.032 0)
			(size 2.794 1.9812)
			(layers "F.Cu" "F.Mask" "F.Paste")
			(net 628 "/Supply/VDD1_SW")
			(pintype "passive")
		)
		(pad "2" smd rect
			(at 2.031 0)
			(size 2.794 1.9812)
			(layers "F.Cu" "F.Mask" "F.Paste")
			(net 551 "/Supply/VDD1V8")
			(pintype "passive")
		)
	)
	(footprint "antmicro-footprints:R_0402_1005Metric"
		(layer "F.Cu")
		(at 135.6 59.7)
		(descr "Resistor SMD 0402")
		(tags "resistor SMD 0402")
		(property "Reference" "R148"
			(at -1.9 -0.5 0)
			(layer "F.SilkS")
			(effects
				(font
					(size 0.7 0.7)
					(thickness 0.15)
				)
				(justify left bottom)
			)
		)
		(property "Value" "R_10k_0402"
			(at 0 1.4 0)
			(layer "F.Fab")
			(effects
				(font
					(size 0.7 0.7)
					(thickness 0.15)
				)
				(justify left bottom)
			)
		)
		(property "Description" "10k resistor in 0402 package with 1% tolerance"
			(at 0 0 0)
			(layer "F.Fab")
			(hide yes)
			(effects
				(font
					(size 1.27 1.27)
					(thickness 0.15)
				)
			)
		)
		(property "Author" "Antmicro"
			(at 0 0 0)
			(layer "F.Fab")
			(hide yes)
			(effects
				(font
					(size 1 1)
					(thickness 0.15)
				)
			)
		)
		(property "License" "Apache-2.0"
			(at 0 0 0)
			(layer "F.Fab")
			(hide yes)
			(effects
				(font
					(size 1 1)
					(thickness 0.15)
				)
			)
		)
		(property "MPN" "CR0402-FX-1002GLF"
			(at 0 0 0)
			(layer "F.Fab")
			(hide yes)
			(effects
				(font
					(size 1 1)
					(thickness 0.15)
				)
			)
		)
		(property "Manufacturer" "Bourns"
			(at 0 0 0)
			(layer "F.Fab")
			(hide yes)
			(effects
				(font
					(size 1 1)
					(thickness 0.15)
				)
			)
		)
		(property "Tolerance" "1%"
			(at 0 0 0)
			(layer "F.Fab")
			(hide yes)
			(effects
				(font
					(size 1 1)
					(thickness 0.15)
				)
			)
		)
		(property "Val" "10k"
			(at 0 0 0)
			(layer "F.Fab")
			(hide yes)
			(effects
				(font
					(size 1 1)
					(thickness 0.15)
				)
			)
		)
		(sheetname "Supply")
		(sheetfile "supply.kicad_sch")
		(attr smd)
		(fp_rect
			(start -0.93 -0.47)
			(end 0.93 0.47)
			(stroke
				(width 0.05)
				(type solid)
			)
			(fill no)
			(layer "F.CrtYd")
		)
		(fp_rect
			(start -0.5 -0.25)
			(end 0.5 0.25)
			(stroke
				(width 0.15)
				(type solid)
			)
			(fill no)
			(layer "F.Fab")
		)
		(pad "1" smd roundrect
			(at -0.485 0)
			(size 0.59 0.64)
			(layers "F.Cu" "F.Mask" "F.Paste")
			(roundrect_rratio 0.25)
			(net 470 "/Supply/VCC_IO_EN")
			(pintype "passive")
		)
		(pad "2" smd roundrect
			(at 0.485 0)
			(size 0.59 0.64)
			(layers "F.Cu" "F.Mask" "F.Paste")
			(roundrect_rratio 0.25)
			(net 636 "/Supply/0V6_EN")
			(pintype "passive")
		)
	)
	(footprint "antmicro-footprints:TP_SMD_1mm"
		(layer "F.Cu")
		(at 170.6 109.9)
		(property "Reference" "TP8"
			(at -2.6 0.4 0)
			(layer "F.SilkS")
			(effects
				(font
					(size 0.7 0.7)
					(thickness 0.15)
				)
				(justify left bottom)
			)
		)
		(property "Value" "TP_1mm_SMD"
			(at 0 1.4 0)
			(layer "F.Fab")
			(effects
				(font
					(size 0.7 0.7)
					(thickness 0.15)
				)
				(justify left bottom)
			)
		)
		(property "Description" "Test Point 1mm"
			(at 0 0 0)
			(layer "F.Fab")
			(hide yes)
			(effects
				(font
					(size 1.27 1.27)
					(thickness 0.15)
				)
			)
		)
		(property "Author" "Antmicro"
			(at 0 0 0)
			(layer "F.Fab")
			(hide yes)
			(effects
				(font
					(size 1 1)
					(thickness 0.15)
				)
			)
		)
		(property "License" "Apache-2.0"
			(at 0 0 0)
			(layer "F.Fab")
			(hide yes)
			(effects
				(font
					(size 1 1)
					(thickness 0.15)
				)
			)
		)
		(property "MPN" ""
			(at 0 0 0)
			(layer "F.Fab")
			(hide yes)
			(effects
				(font
					(size 1 1)
					(thickness 0.15)
				)
			)
		)
		(property "Manufacturer" ""
			(at 0 0 0)
			(layer "F.Fab")
			(hide yes)
			(effects
				(font
					(size 1 1)
					(thickness 0.15)
				)
			)
		)
		(sheetname "Config SPI flash")
		(sheetfile "config-spi.kicad_sch")
		(attr exclude_from_pos_files)
		(pad "1" smd circle
			(at 0 0)
			(size 1 1)
			(layers "F.Cu" "F.Mask")
			(net 217 "EMCCLK")
			(pinfunction "1")
			(pintype "passive")
		)
	)
	(footprint "antmicro-footprints:L_WE-MAIA-2512"
		(layer "F.Cu")
		(at 113.897806 84.774 180)
		(property "Reference" "L3"
			(at -1.5 -1.4 180)
			(layer "F.SilkS")
			(effects
				(font
					(size 0.7 0.7)
					(thickness 0.15)
				)
				(justify left bottom)
			)
		)
		(property "Value" "784383240047"
			(at 0 2.3 180)
			(layer "F.Fab")
			(effects
				(font
					(size 0.7 0.7)
					(thickness 0.15)
				)
				(justify left bottom)
			)
		)
		(property "Description" "Power Inductor (SMT), AEC-Q200, 470 nH, 3.4 A, Shielded, 6.25 A, WE-MAIA"
			(at 0 0 180)
			(layer "F.Fab")
			(hide yes)
			(effects
				(font
					(size 1.27 1.27)
					(thickness 0.15)
				)
			)
		)
		(property "Author" "Antmicro"
			(at 227.795612 169.548 0)
			(layer "F.Fab")
			(hide yes)
			(effects
				(font
					(size 1 1)
					(thickness 0.15)
				)
			)
		)
		(property "IMax" "3.4 A"
			(at 227.795612 169.548 0)
			(layer "F.Fab")
			(hide yes)
			(effects
				(font
					(size 1 1)
					(thickness 0.15)
				)
			)
		)
		(property "ISat" "6.25 A"
			(at 227.795612 169.548 0)
			(layer "F.Fab")
			(hide yes)
			(effects
				(font
					(size 1 1)
					(thickness 0.15)
				)
			)
		)
		(property "License" "Apache-2.0"
			(at 227.795612 169.548 0)
			(layer "F.Fab")
			(hide yes)
			(effects
				(font
					(size 1 1)
					(thickness 0.15)
				)
			)
		)
		(property "MPN" "784383240047"
			(at 227.795612 169.548 0)
			(layer "F.Fab")
			(hide yes)
			(effects
				(font
					(size 1 1)
					(thickness 0.15)
				)
			)
		)
		(property "Manufacturer" "Würth Elektronik"
			(at 227.795612 169.548 0)
			(layer "F.Fab")
			(hide yes)
			(effects
				(font
					(size 1 1)
					(thickness 0.15)
				)
			)
		)
		(property "Size" "2x2.5"
			(at 227.795612 169.548 0)
			(layer "F.Fab")
			(hide yes)
			(effects
				(font
					(size 1 1)
					(thickness 0.15)
				)
			)
		)
		(property "Val" "470n/3.4A"
			(at 227.795612 169.548 0)
			(layer "F.Fab")
			(hide yes)
			(effects
				(font
					(size 1 1)
					(thickness 0.15)
				)
			)
		)
		(sheetname "Supply")
		(sheetfile "supply.kicad_sch")
		(attr smd)
		(fp_line
			(start -0.325 1.125)
			(end 0.325 1.125)
			(stroke
				(width 0.15)
				(type solid)
			)
			(layer "F.SilkS")
		)
		(fp_line
			(start -0.325 -1.125)
			(end 0.325 -1.125)
			(stroke
				(width 0.15)
				(type solid)
			)
			(layer "F.SilkS")
		)
		(fp_rect
			(start -1.65 -1.4)
			(end 1.65 1.4)
			(stroke
				(width 0.05)
				(type solid)
			)
			(fill no)
			(layer "F.CrtYd")
		)
		(fp_rect
			(start -1.25 -1)
			(end 1.25 1)
			(stroke
				(width 0.15)
				(type solid)
			)
			(fill no)
			(layer "F.Fab")
		)
		(pad "1" smd roundrect
			(at -0.975 0 180)
			(size 0.85 2.3)
			(layers "F.Cu" "F.Mask" "F.Paste")
			(roundrect_rratio 0.1)
			(net 584 "/Supply/1V8_SW")
			(pintype "passive")
		)
		(pad "2" smd roundrect
			(at 0.975 0 180)
			(size 0.85 2.3)
			(layers "F.Cu" "F.Mask" "F.Paste")
			(roundrect_rratio 0.1)
			(net 583 "/Supply/1V8_REG")
			(pintype "passive")
		)
	)
	(footprint "antmicro-footprints:R_0805_2012Metric"
		(layer "F.Cu")
		(at 114.325 93.749)
		(property "Reference" "R117"
			(at 1.575 0.351 0)
			(layer "F.SilkS")
			(effects
				(font
					(size 0.7 0.7)
					(thickness 0.15)
				)
				(justify left bottom)
			)
		)
		(property "Value" "R_0R_0805"
			(at 0 1.8 0)
			(layer "F.Fab")
			(effects
				(font
					(size 0.7 0.7)
					(thickness 0.15)
				)
				(justify left bottom)
			)
		)
		(property "Description" "0R resistor in 0805 package with unspecified tolerance"
			(at 0 0 0)
			(layer "F.Fab")
			(hide yes)
			(effects
				(font
					(size 1.27 1.27)
					(thickness 0.15)
				)
			)
		)
		(property "Author" "Antmicro"
			(at 0 0 0)
			(layer "F.Fab")
			(hide yes)
			(effects
				(font
					(size 1 1)
					(thickness 0.15)
				)
			)
		)
		(property "Current" "2.5A"
			(at 0 0 0)
			(layer "F.Fab")
			(hide yes)
			(effects
				(font
					(size 1 1)
					(thickness 0.15)
				)
			)
		)
		(property "License" "Apache-2.0"
			(at 0 0 0)
			(layer "F.Fab")
			(hide yes)
			(effects
				(font
					(size 1 1)
					(thickness 0.15)
				)
			)
		)
		(property "MPN" "CRCW08050000Z0EA"
			(at 0 0 0)
			(layer "F.Fab")
			(hide yes)
			(effects
				(font
					(size 1 1)
					(thickness 0.15)
				)
			)
		)
		(property "Manufacturer" "Vishay"
			(at 0 0 0)
			(layer "F.Fab")
			(hide yes)
			(effects
				(font
					(size 1 1)
					(thickness 0.15)
				)
			)
		)
		(property "Tolerance" ""
			(at 0 0 0)
			(layer "F.Fab")
			(hide yes)
			(effects
				(font
					(size 1 1)
					(thickness 0.15)
				)
			)
		)
		(property "Val" "0R"
			(at 0 0 0)
			(layer "F.Fab")
			(hide yes)
			(effects
				(font
					(size 1 1)
					(thickness 0.15)
				)
			)
		)
		(sheetname "Supply")
		(sheetfile "supply.kicad_sch")
		(attr smd)
		(fp_line
			(start -0.32 0.699)
			(end 0.28 0.699)
			(stroke
				(width 0.15)
				(type solid)
			)
			(layer "F.SilkS")
		)
		(fp_line
			(start -0.3 -0.701)
			(end 0.298 -0.701)
			(stroke
				(width 0.15)
				(type solid)
			)
			(layer "F.SilkS")
		)
		(fp_rect
			(start -1.75 -0.85)
			(end 1.75 0.85)
			(stroke
				(width 0.05)
				(type solid)
			)
			(fill no)
			(layer "F.CrtYd")
		)
		(fp_line
			(start -0.951 -0.682)
			(end 0.949 -0.682)
			(stroke
				(width 0.15)
				(type solid)
			)
			(layer "F.Fab")
		)
		(fp_line
			(start -0.951 -0.677)
			(end -0.951 0.675)
			(stroke
				(width 0.15)
				(type solid)
			)
			(layer "F.Fab")
		)
		(fp_line
			(start -0.951 0.68)
			(end 0.949 0.68)
			(stroke
				(width 0.15)
				(type solid)
			)
			(layer "F.Fab")
		)
		(fp_line
			(start 0.949 -0.677)
			(end 0.949 0.675)
			(stroke
				(width 0.15)
				(type solid)
			)
			(layer "F.Fab")
		)
		(pad "1" smd roundrect
			(at -1.1 -0.001)
			(size 1 1.4)
			(layers "F.Cu" "F.Mask" "F.Paste")
			(roundrect_rratio 0.15)
			(net 576 "/Supply/3V3_REG")
			(pintype "passive")
		)
		(pad "2" smd roundrect
			(at 1.1 -0.001)
			(size 1 1.4)
			(layers "F.Cu" "F.Mask" "F.Paste")
			(roundrect_rratio 0.15)
			(net 459 "3V3_SYS")
			(pintype "passive")
		)
	)
	(footprint "antmicro-footprints:R_0402_1005Metric"
		(layer "F.Cu")
		(at 117.697806 90.074 180)
		(descr "Resistor SMD 0402")
		(tags "resistor SMD 0402")
		(property "Reference" "R118"
			(at 0.897806 3.574 180)
			(layer "F.SilkS")
			(effects
				(font
					(size 0.7 0.7)
					(thickness 0.15)
				)
				(justify left bottom)
			)
		)
		(property "Value" "R_100k_0402"
			(at 0 1.4 180)
			(layer "F.Fab")
			(effects
				(font
					(size 0.7 0.7)
					(thickness 0.15)
				)
				(justify left bottom)
			)
		)
		(property "Description" "100k resistor in 0402 package with 1% tolerance"
			(at 0 0 180)
			(layer "F.Fab")
			(hide yes)
			(effects
				(font
					(size 1.27 1.27)
					(thickness 0.15)
				)
			)
		)
		(property "Author" "Antmicro"
			(at 235.395612 180.148 0)
			(layer "F.Fab")
			(hide yes)
			(effects
				(font
					(size 1 1)
					(thickness 0.15)
				)
			)
		)
		(property "License" "Apache-2.0"
			(at 235.395612 180.148 0)
			(layer "F.Fab")
			(hide yes)
			(effects
				(font
					(size 1 1)
					(thickness 0.15)
				)
			)
		)
		(property "MPN" "CR0402-FX-1003GLF"
			(at 235.395612 180.148 0)
			(layer "F.Fab")
			(hide yes)
			(effects
				(font
					(size 1 1)
					(thickness 0.15)
				)
			)
		)
		(property "Manufacturer" "Bourns"
			(at 235.395612 180.148 0)
			(layer "F.Fab")
			(hide yes)
			(effects
				(font
					(size 1 1)
					(thickness 0.15)
				)
			)
		)
		(property "Tolerance" "1%"
			(at 235.395612 180.148 0)
			(layer "F.Fab")
			(hide yes)
			(effects
				(font
					(size 1 1)
					(thickness 0.15)
				)
			)
		)
		(property "Val" "100k"
			(at 235.395612 180.148 0)
			(layer "F.Fab")
			(hide yes)
			(effects
				(font
					(size 1 1)
					(thickness 0.15)
				)
			)
		)
		(sheetname "Supply")
		(sheetfile "supply.kicad_sch")
		(attr smd)
		(fp_rect
			(start -0.93 -0.47)
			(end 0.93 0.47)
			(stroke
				(width 0.05)
				(type solid)
			)
			(fill no)
			(layer "F.CrtYd")
		)
		(fp_rect
			(start -0.5 -0.25)
			(end 0.5 0.25)
			(stroke
				(width 0.15)
				(type solid)
			)
			(fill no)
			(layer "F.Fab")
		)
		(pad "1" smd roundrect
			(at -0.485 0 180)
			(size 0.59 0.64)
			(layers "F.Cu" "F.Mask" "F.Paste")
			(roundrect_rratio 0.25)
			(net 469 "/Supply/VCC_AUX_EN")
			(pintype "passive")
		)
		(pad "2" smd roundrect
			(at 0.485 0 180)
			(size 0.59 0.64)
			(layers "F.Cu" "F.Mask" "F.Paste")
			(roundrect_rratio 0.25)
			(net 594 "/Supply/1V8_EN")
			(pintype "passive")
		)
	)
	(footprint "antmicro-footprints:C_0402_1005Metric"
		(layer "F.Cu")
		(at 111.362806 87.974 180)
		(descr "Capacitor SMD 0402")
		(tags "capacitor SMD 0402")
		(property "Reference" "C163"
			(at 3.662806 -0.326 180)
			(layer "F.SilkS")
			(effects
				(font
					(size 0.7 0.7)
					(thickness 0.15)
				)
				(justify left bottom)
			)
		)
		(property "Value" "C_1u_0402"
			(at 0 1.4 180)
			(layer "F.Fab")
			(effects
				(font
					(size 0.7 0.7)
					(thickness 0.15)
				)
				(justify left bottom)
			)
		)
		(property "Description" " "
			(at 0 0 180)
			(layer "F.Fab")
			(hide yes)
			(effects
				(font
					(size 1.27 1.27)
					(thickness 0.15)
				)
			)
		)
		(property "Author" "Antmicro"
			(at 222.725612 175.948 0)
			(layer "F.Fab")
			(hide yes)
			(effects
				(font
					(size 1 1)
					(thickness 0.15)
				)
			)
		)
		(property "Dielectric" ""
			(at 222.725612 175.948 0)
			(layer "F.Fab")
			(hide yes)
			(effects
				(font
					(size 1 1)
					(thickness 0.15)
				)
			)
		)
		(property "License" "Apache-2.0"
			(at 222.725612 175.948 0)
			(layer "F.Fab")
			(hide yes)
			(effects
				(font
					(size 1 1)
					(thickness 0.15)
				)
			)
		)
		(property "MPN" "C1005X6S1A105K050BC"
			(at 222.725612 175.948 0)
			(layer "F.Fab")
			(hide yes)
			(effects
				(font
					(size 1 1)
					(thickness 0.15)
				)
			)
		)
		(property "Manufacturer" "TDK"
			(at 222.725612 175.948 0)
			(layer "F.Fab")
			(hide yes)
			(effects
				(font
					(size 1 1)
					(thickness 0.15)
				)
			)
		)
		(property "Val" "1u"
			(at 222.725612 175.948 0)
			(layer "F.Fab")
			(hide yes)
			(effects
				(font
					(size 1 1)
					(thickness 0.15)
				)
			)
		)
		(property "Voltage" ""
			(at 222.725612 175.948 0)
			(layer "F.Fab")
			(hide yes)
			(effects
				(font
					(size 1 1)
					(thickness 0.15)
				)
			)
		)
		(sheetname "Supply")
		(sheetfile "supply.kicad_sch")
		(attr smd)
		(fp_rect
			(start -0.94 -0.47)
			(end 0.94 0.47)
			(stroke
				(width 0.05)
				(type solid)
			)
			(fill no)
			(layer "F.CrtYd")
		)
		(fp_rect
			(start -0.499 -0.249)
			(end 0.499 0.249)
			(stroke
				(width 0.15)
				(type solid)
			)
			(fill no)
			(layer "F.Fab")
		)
		(pad "1" smd roundrect
			(at -0.484 0 180)
			(size 0.59 0.64)
			(layers "F.Cu" "F.Mask" "F.Paste")
			(roundrect_rratio 0.25)
			(net 595 "/Supply/1V8_VCC_INT")
			(pintype "passive")
		)
		(pad "2" smd roundrect
			(at 0.484 0 180)
			(size 0.59 0.64)
			(layers "F.Cu" "F.Mask" "F.Paste")
			(roundrect_rratio 0.25)
			(net 5 "GND")
			(pintype "passive")
		)
	)
	(footprint "antmicro-footprints:R_0402_1005Metric"
		(layer "F.Cu")
		(at 129.9825 101.549 180)
		(descr "Resistor SMD 0402")
		(tags "resistor SMD 0402")
		(property "Reference" "R130"
			(at -0.7175 -0.451 180)
			(layer "F.SilkS")
			(effects
				(font
					(size 0.7 0.7)
					(thickness 0.15)
				)
				(justify left bottom)
			)
		)
		(property "Value" "R_100k_0402"
			(at 0 1.4 180)
			(layer "F.Fab")
			(effects
				(font
					(size 0.7 0.7)
					(thickness 0.15)
				)
				(justify left bottom)
			)
		)
		(property "Description" "100k resistor in 0402 package with 1% tolerance"
			(at 0 0 180)
			(layer "F.Fab")
			(hide yes)
			(effects
				(font
					(size 1.27 1.27)
					(thickness 0.15)
				)
			)
		)
		(property "Author" "Antmicro"
			(at 259.965 203.098 0)
			(layer "F.Fab")
			(hide yes)
			(effects
				(font
					(size 1 1)
					(thickness 0.15)
				)
			)
		)
		(property "License" "Apache-2.0"
			(at 259.965 203.098 0)
			(layer "F.Fab")
			(hide yes)
			(effects
				(font
					(size 1 1)
					(thickness 0.15)
				)
			)
		)
		(property "MPN" "CR0402-FX-1003GLF"
			(at 259.965 203.098 0)
			(layer "F.Fab")
			(hide yes)
			(effects
				(font
					(size 1 1)
					(thickness 0.15)
				)
			)
		)
		(property "Manufacturer" "Bourns"
			(at 259.965 203.098 0)
			(layer "F.Fab")
			(hide yes)
			(effects
				(font
					(size 1 1)
					(thickness 0.15)
				)
			)
		)
		(property "Tolerance" "1%"
			(at 259.965 203.098 0)
			(layer "F.Fab")
			(hide yes)
			(effects
				(font
					(size 1 1)
					(thickness 0.15)
				)
			)
		)
		(property "Val" "100k"
			(at 259.965 203.098 0)
			(layer "F.Fab")
			(hide yes)
			(effects
				(font
					(size 1 1)
					(thickness 0.15)
				)
			)
		)
		(sheetname "Supply")
		(sheetfile "supply.kicad_sch")
		(attr smd)
		(fp_rect
			(start -0.93 -0.47)
			(end 0.93 0.47)
			(stroke
				(width 0.05)
				(type solid)
			)
			(fill no)
			(layer "F.CrtYd")
		)
		(fp_rect
			(start -0.5 -0.25)
			(end 0.5 0.25)
			(stroke
				(width 0.15)
				(type solid)
			)
			(fill no)
			(layer "F.Fab")
		)
		(pad "1" smd roundrect
			(at -0.485 0 180)
			(size 0.59 0.64)
			(layers "F.Cu" "F.Mask" "F.Paste")
			(roundrect_rratio 0.25)
			(net 468 "/Supply/VCC_INT_EN")
			(pintype "passive")
		)
		(pad "2" smd roundrect
			(at 0.485 0 180)
			(size 0.59 0.64)
			(layers "F.Cu" "F.Mask" "F.Paste")
			(roundrect_rratio 0.25)
			(net 592 "/Supply/1V0_EN")
			(pintype "passive")
		)
	)
	(footprint "antmicro-footprints:R_0402_1005Metric"
		(layer "F.Cu")
		(at 186 118.185 90)
		(descr "Resistor SMD 0402")
		(tags "resistor SMD 0402")
		(property "Reference" "R151"
			(at -3.615 0.436828 90)
			(layer "F.SilkS")
			(effects
				(font
					(size 0.7 0.7)
					(thickness 0.15)
				)
				(justify left bottom)
			)
		)
		(property "Value" "R_0R_0402"
			(at 0 1.4 90)
			(layer "F.Fab")
			(effects
				(font
					(size 0.7 0.7)
					(thickness 0.15)
				)
				(justify left bottom)
			)
		)
		(property "Description" "0R resistor in 0402 package with unspecified tolerance"
			(at 0 0 90)
			(layer "F.Fab")
			(hide yes)
			(effects
				(font
					(size 1.27 1.27)
					(thickness 0.15)
				)
			)
		)
		(property "Author" "Antmicro"
			(at 304.185 -67.815 0)
			(layer "F.Fab")
			(hide yes)
			(effects
				(font
					(size 1 1)
					(thickness 0.15)
				)
			)
		)
		(property "Current" "1A"
			(at 304.185 -67.815 0)
			(layer "F.Fab")
			(hide yes)
			(effects
				(font
					(size 1 1)
					(thickness 0.15)
				)
			)
		)
		(property "License" "Apache-2.0"
			(at 304.185 -67.815 0)
			(layer "F.Fab")
			(hide yes)
			(effects
				(font
					(size 1 1)
					(thickness 0.15)
				)
			)
		)
		(property "MPN" "ERJ2GE0R00X"
			(at 304.185 -67.815 0)
			(layer "F.Fab")
			(hide yes)
			(effects
				(font
					(size 1 1)
					(thickness 0.15)
				)
			)
		)
		(property "Manufacturer" "Panasonic"
			(at 304.185 -67.815 0)
			(layer "F.Fab")
			(hide yes)
			(effects
				(font
					(size 1 1)
					(thickness 0.15)
				)
			)
		)
		(property "Tolerance" ""
			(at 304.185 -67.815 0)
			(layer "F.Fab")
			(hide yes)
			(effects
				(font
					(size 1 1)
					(thickness 0.15)
				)
			)
		)
		(property "Val" "0R"
			(at 304.185 -67.815 0)
			(layer "F.Fab")
			(hide yes)
			(effects
				(font
					(size 1 1)
					(thickness 0.15)
				)
			)
		)
		(sheetname "Supply")
		(sheetfile "supply.kicad_sch")
		(attr smd)
		(fp_rect
			(start -0.93 -0.47)
			(end 0.93 0.47)
			(stroke
				(width 0.05)
				(type solid)
			)
			(fill no)
			(layer "F.CrtYd")
		)
		(fp_rect
			(start -0.5 -0.25)
			(end 0.5 0.25)
			(stroke
				(width 0.15)
				(type solid)
			)
			(fill no)
			(layer "F.Fab")
		)
		(pad "1" smd roundrect
			(at -0.485 0 90)
			(size 0.59 0.64)
			(layers "F.Cu" "F.Mask" "F.Paste")
			(roundrect_rratio 0.25)
			(net 5 "GND")
			(pintype "passive")
		)
		(pad "2" smd roundrect
			(at 0.485 0 90)
			(size 0.59 0.64)
			(layers "F.Cu" "F.Mask" "F.Paste")
			(roundrect_rratio 0.25)
			(net 623 "/Supply/1V2_MODE")
			(pintype "passive")
		)
	)
	(footprint "antmicro-footprints:USON-14_3.5X1.3X0.5mm_P0.5mm"
		(layer "B.Cu")
		(at 208.484328 70.418008 90)
		(property "Reference" "D7"
			(at -0.781992 -1.184328 270)
			(layer "B.SilkS")
			(effects
				(font
					(size 0.7 0.7)
					(thickness 0.15)
				)
				(justify right bottom mirror)
			)
		)
		(property "Value" "TPD6E05U06RVZR"
			(at 0 -2.2 270)
			(layer "B.Fab")
			(effects
				(font
					(size 0.7 0.7)
					(thickness 0.15)
				)
				(justify left bottom mirror)
			)
		)
		(property "Author" "Antmicro"
			(at 278.902336 -138.06632 0)
			(layer "B.Fab")
			(hide yes)
			(effects
				(font
					(size 1 1)
					(thickness 0.15)
				)
				(justify mirror)
			)
		)
		(property "License" "Apache-2.0"
			(at 278.902336 -138.06632 0)
			(layer "B.Fab")
			(hide yes)
			(effects
				(font
					(size 1 1)
					(thickness 0.15)
				)
				(justify mirror)
			)
		)
		(property "MPN" "TPD6E05U06RVZR"
			(at 278.902336 -138.06632 0)
			(layer "B.Fab")
			(hide yes)
			(effects
				(font
					(size 1 1)
					(thickness 0.15)
				)
				(justify mirror)
			)
		)
		(property "Manufacturer" "Texas Instruments"
			(at 278.902336 -138.06632 0)
			(layer "B.Fab")
			(hide yes)
			(effects
				(font
					(size 1 1)
					(thickness 0.15)
				)
				(justify mirror)
			)
		)
		(sheetname "Config SPI flash")
		(sheetfile "config-spi.kicad_sch")
		(attr smd)
		(fp_line
			(start 1.85 -0.96)
			(end -1.59 -0.96)
			(stroke
				(width 0.15)
				(type solid)
			)
			(layer "B.SilkS")
		)
		(fp_line
			(start -1.59 -0.96)
			(end -1.86 -0.69)
			(stroke
				(width 0.15)
				(type solid)
			)
			(layer "B.SilkS")
		)
		(fp_line
			(start -1.86 -0.69)
			(end -1.86 0.96)
			(stroke
				(width 0.15)
				(type solid)
			)
			(layer "B.SilkS")
		)
		(fp_line
			(start 1.85 0.96)
			(end 1.85 -0.96)
			(stroke
				(width 0.15)
				(type solid)
			)
			(layer "B.SilkS")
		)
		(fp_line
			(start -1.86 0.96)
			(end 1.85 0.96)
			(stroke
				(width 0.15)
				(type solid)
			)
			(layer "B.SilkS")
		)
		(fp_circle
			(center -1.86 -0.98)
			(end -1.81 -0.98)
			(stroke
				(width 0.15)
				(type solid)
			)
			(fill no)
			(layer "B.SilkS")
		)
		(fp_rect
			(start -2 1.125)
			(end 2 -1.125)
			(stroke
				(width 0.05)
				(type solid)
			)
			(fill no)
			(layer "B.CrtYd")
		)
		(fp_line
			(start 1.85 -0.96)
			(end 1.85 0.96)
			(stroke
				(width 0.15)
				(type solid)
			)
			(layer "B.Fab")
		)
		(fp_line
			(start -1.58 -0.96)
			(end 1.85 -0.96)
			(stroke
				(width 0.15)
				(type solid)
			)
			(layer "B.Fab")
		)
		(fp_line
			(start -1.845 -0.705)
			(end -1.595 -0.955)
			(stroke
				(width 0.15)
				(type solid)
			)
			(layer "B.Fab")
		)
		(fp_line
			(start 1.85 0.96)
			(end -1.86 0.96)
			(stroke
				(width 0.15)
				(type solid)
			)
			(layer "B.Fab")
		)
		(fp_line
			(start -1.86 0.96)
			(end -1.86 -0.69)
			(stroke
				(width 0.15)
				(type solid)
			)
			(layer "B.Fab")
		)
		(pad "1" smd roundrect
			(at -1.5 -0.623 90)
			(size 0.2 0.5)
			(layers "B.Cu" "B.Mask" "B.Paste")
			(roundrect_rratio 0.25)
			(net 9 "TMS_JTAG")
			(pinfunction "D1+")
			(pintype "passive")
		)
		(pad "2" smd roundrect
			(at -1 -0.623 90)
			(size 0.2 0.5)
			(layers "B.Cu" "B.Mask" "B.Paste")
			(roundrect_rratio 0.25)
			(net 8 "TCK_JTAG")
			(pinfunction "D1-")
			(pintype "passive")
		)
		(pad "3" smd roundrect
			(at -0.5 -0.623 90)
			(size 0.2 0.5)
			(layers "B.Cu" "B.Mask" "B.Paste")
			(roundrect_rratio 0.25)
			(net 64 "unconnected-(D7-D2+-Pad12)")
			(pinfunction "D2+")
			(pintype "passive+no_connect")
		)
		(pad "4" smd roundrect
			(at 0 -0.623 90)
			(size 0.2 0.5)
			(layers "B.Cu" "B.Mask" "B.Paste")
			(roundrect_rratio 0.25)
			(net 65 "unconnected-(D7-D2--Pad11)")
			(pinfunction "D2-")
			(pintype "passive+no_connect")
		)
		(pad "5" smd roundrect
			(at 0.498 -0.623 90)
			(size 0.2 0.5)
			(layers "B.Cu" "B.Mask" "B.Paste")
			(roundrect_rratio 0.25)
			(net 5 "GND")
			(pinfunction "GND")
			(pintype "power_in")
		)
		(pad "6" smd roundrect
			(at 0.998 -0.623 90)
			(size 0.2 0.5)
			(layers "B.Cu" "B.Mask" "B.Paste")
			(roundrect_rratio 0.25)
			(net 11 "TDO_JTAG")
			(pinfunction "D3+")
			(pintype "passive")
		)
		(pad "7" smd roundrect
			(at 1.499 -0.623 90)
			(size 0.2 0.5)
			(layers "B.Cu" "B.Mask" "B.Paste")
			(roundrect_rratio 0.25)
			(net 10 "TDI_JTAG")
			(pinfunction "D3-")
			(pintype "passive")
		)
		(pad "8" smd roundrect
			(at 1.499 0.625 90)
			(size 0.2 0.5)
			(layers "B.Cu" "B.Mask" "B.Paste")
			(roundrect_rratio 0.25)
			(net 10 "TDI_JTAG")
			(pinfunction "D3-")
			(pintype "passive")
		)
		(pad "9" smd roundrect
			(at 0.998 0.625 90)
			(size 0.2 0.5)
			(layers "B.Cu" "B.Mask" "B.Paste")
			(roundrect_rratio 0.25)
			(net 11 "TDO_JTAG")
			(pinfunction "D3+")
			(pintype "passive")
		)
		(pad "10" smd roundrect
			(at 0.498 0.625 90)
			(size 0.2 0.5)
			(layers "B.Cu" "B.Mask" "B.Paste")
			(roundrect_rratio 0.25)
			(net 5 "GND")
			(pinfunction "GND")
			(pintype "passive")
		)
		(pad "11" smd roundrect
			(at 0 0.625 90)
			(size 0.2 0.5)
			(layers "B.Cu" "B.Mask" "B.Paste")
			(roundrect_rratio 0.25)
			(net 65 "unconnected-(D7-D2--Pad11)")
			(pinfunction "D2-")
			(pintype "passive+no_connect")
		)
		(pad "12" smd roundrect
			(at -0.5 0.625 90)
			(size 0.2 0.5)
			(layers "B.Cu" "B.Mask" "B.Paste")
			(roundrect_rratio 0.25)
			(net 64 "unconnected-(D7-D2+-Pad12)")
			(pinfunction "D2+")
			(pintype "passive+no_connect")
		)
		(pad "13" smd roundrect
			(at -1 0.625 90)
			(size 0.2 0.5)
			(layers "B.Cu" "B.Mask" "B.Paste")
			(roundrect_rratio 0.25)
			(net 8 "TCK_JTAG")
			(pinfunction "D1-")
			(pintype "passive")
		)
		(pad "14" smd roundrect
			(at -1.5 0.625 90)
			(size 0.2 0.5)
			(layers "B.Cu" "B.Mask" "B.Paste")
			(roundrect_rratio 0.25)
			(net 9 "TMS_JTAG")
			(pinfunction "D1+")
			(pintype "passive")
		)
	)
	(footprint "antmicro-footprints:R_0402_1005Metric"
		(layer "B.Cu")
		(at 180.1885 118.285757)
		(descr "Resistor SMD 0402")
		(tags "resistor SMD 0402")
		(property "Reference" "R54"
			(at -0.7885 0.414243 180)
			(layer "B.SilkS")
			(effects
				(font
					(size 0.7 0.7)
					(thickness 0.15)
				)
				(justify left bottom mirror)
			)
		)
		(property "Value" "R_100R_0402"
			(at 0 -1.4 180)
			(layer "B.Fab")
			(effects
				(font
					(size 0.7 0.7)
					(thickness 0.15)
				)
				(justify left bottom mirror)
			)
		)
		(property "Description" "100R resistor in 0402 package with 1% tolerance"
			(at 0 0 0)
			(layer "F.Fab")
			(hide yes)
			(effects
				(font
					(size 1.27 1.27)
					(thickness 0.15)
				)
			)
		)
		(property "Author" "Antmicro"
			(at 0 0 0)
			(layer "B.Fab")
			(hide yes)
			(effects
				(font
					(size 1 1)
					(thickness 0.15)
				)
				(justify mirror)
			)
		)
		(property "License" "Apache-2.0"
			(at 0 0 0)
			(layer "B.Fab")
			(hide yes)
			(effects
				(font
					(size 1 1)
					(thickness 0.15)
				)
				(justify mirror)
			)
		)
		(property "MPN" "CR0402-FX-1000GLF"
			(at 0 0 0)
			(layer "B.Fab")
			(hide yes)
			(effects
				(font
					(size 1 1)
					(thickness 0.15)
				)
				(justify mirror)
			)
		)
		(property "Manufacturer" "Bourns"
			(at 0 0 0)
			(layer "B.Fab")
			(hide yes)
			(effects
				(font
					(size 1 1)
					(thickness 0.15)
				)
				(justify mirror)
			)
		)
		(property "Tolerance" "1%"
			(at 0 0 0)
			(layer "B.Fab")
			(hide yes)
			(effects
				(font
					(size 1 1)
					(thickness 0.15)
				)
				(justify mirror)
			)
		)
		(property "Val" "100R"
			(at 0 0 0)
			(layer "B.Fab")
			(hide yes)
			(effects
				(font
					(size 1 1)
					(thickness 0.15)
				)
				(justify mirror)
			)
		)
		(sheetname "Config SPI flash")
		(sheetfile "config-spi.kicad_sch")
		(attr exclude_from_pos_files exclude_from_bom dnp)
		(fp_rect
			(start -0.93 0.47)
			(end 0.93 -0.47)
			(stroke
				(width 0.05)
				(type solid)
			)
			(fill no)
			(layer "B.CrtYd")
		)
		(fp_rect
			(start -0.5 0.25)
			(end 0.5 -0.25)
			(stroke
				(width 0.15)
				(type solid)
			)
			(fill no)
			(layer "B.Fab")
		)
		(pad "1" smd roundrect
			(at -0.485 0)
			(size 0.59 0.64)
			(layers "B.Cu" "B.Mask" "B.Paste")
			(roundrect_rratio 0.25)
			(net 459 "3V3_SYS")
			(pintype "passive")
		)
		(pad "2" smd roundrect
			(at 0.485 0)
			(size 0.59 0.64)
			(layers "B.Cu" "B.Mask" "B.Paste")
			(roundrect_rratio 0.25)
			(net 213 "CCLK")
			(pintype "passive")
		)
	)
	(footprint "antmicro-footprints:R_0402_1005Metric"
		(layer "B.Cu")
		(at 180.1885 119.555757 180)
		(descr "Resistor SMD 0402")
		(tags "resistor SMD 0402")
		(property "Reference" "R55"
			(at 0.7885 -0.444243 0)
			(layer "B.SilkS")
			(effects
				(font
					(size 0.7 0.7)
					(thickness 0.15)
				)
				(justify left bottom mirror)
			)
		)
		(property "Value" "R_100R_0402"
			(at 0 -1.4 0)
			(layer "B.Fab")
			(effects
				(font
					(size 0.7 0.7)
					(thickness 0.15)
				)
				(justify left bottom mirror)
			)
		)
		(property "Description" "100R resistor in 0402 package with 1% tolerance"
			(at 0 0 180)
			(layer "F.Fab")
			(hide yes)
			(effects
				(font
					(size 1.27 1.27)
					(thickness 0.15)
				)
			)
		)
		(property "Author" "Antmicro"
			(at 360.377 239.111514 0)
			(layer "B.Fab")
			(hide yes)
			(effects
				(font
					(size 1 1)
					(thickness 0.15)
				)
				(justify mirror)
			)
		)
		(property "License" "Apache-2.0"
			(at 360.377 239.111514 0)
			(layer "B.Fab")
			(hide yes)
			(effects
				(font
					(size 1 1)
					(thickness 0.15)
				)
				(justify mirror)
			)
		)
		(property "MPN" "CR0402-FX-1000GLF"
			(at 360.377 239.111514 0)
			(layer "B.Fab")
			(hide yes)
			(effects
				(font
					(size 1 1)
					(thickness 0.15)
				)
				(justify mirror)
			)
		)
		(property "Manufacturer" "Bourns"
			(at 360.377 239.111514 0)
			(layer "B.Fab")
			(hide yes)
			(effects
				(font
					(size 1 1)
					(thickness 0.15)
				)
				(justify mirror)
			)
		)
		(property "Tolerance" "1%"
			(at 360.377 239.111514 0)
			(layer "B.Fab")
			(hide yes)
			(effects
				(font
					(size 1 1)
					(thickness 0.15)
				)
				(justify mirror)
			)
		)
		(property "Val" "100R"
			(at 360.377 239.111514 0)
			(layer "B.Fab")
			(hide yes)
			(effects
				(font
					(size 1 1)
					(thickness 0.15)
				)
				(justify mirror)
			)
		)
		(sheetname "Config SPI flash")
		(sheetfile "config-spi.kicad_sch")
		(attr exclude_from_pos_files exclude_from_bom dnp)
		(fp_rect
			(start -0.93 0.47)
			(end 0.93 -0.47)
			(stroke
				(width 0.05)
				(type solid)
			)
			(fill no)
			(layer "B.CrtYd")
		)
		(fp_rect
			(start -0.5 0.25)
			(end 0.5 -0.25)
			(stroke
				(width 0.15)
				(type solid)
			)
			(fill no)
			(layer "B.Fab")
		)
		(pad "1" smd roundrect
			(at -0.485 0 180)
			(size 0.59 0.64)
			(layers "B.Cu" "B.Mask" "B.Paste")
			(roundrect_rratio 0.25)
			(net 213 "CCLK")
			(pintype "passive")
		)
		(pad "2" smd roundrect
			(at 0.485 0 180)
			(size 0.59 0.64)
			(layers "B.Cu" "B.Mask" "B.Paste")
			(roundrect_rratio 0.25)
			(net 5 "GND")
			(pintype "passive")
		)
	)
	(footprint "antmicro-footprints:C_0603_1608Metric"
		(layer "B.Cu")
		(at 159.536328 92.997157 180)
		(descr "Capacitor SMD 0603")
		(tags "capacitor 0603")
		(property "Reference" "C31"
			(at 1.036328 -0.402843 0)
			(layer "B.SilkS")
			(effects
				(font
					(size 0.7 0.7)
					(thickness 0.15)
				)
				(justify left bottom mirror)
			)
		)
		(property "Value" "C_47u_0603"
			(at 0 -1.6 0)
			(layer "B.Fab")
			(effects
				(font
					(size 0.7 0.7)
					(thickness 0.15)
				)
				(justify left bottom mirror)
			)
		)
		(property "Description" " "
			(at 0 0 180)
			(layer "F.Fab")
			(hide yes)
			(effects
				(font
					(size 1.27 1.27)
					(thickness 0.15)
				)
			)
		)
		(property "Author" "Antmicro"
			(at 319.072656 185.994314 0)
			(layer "B.Fab")
			(hide yes)
			(effects
				(font
					(size 1 1)
					(thickness 0.15)
				)
				(justify mirror)
			)
		)
		(property "Dielectric" ""
			(at 319.072656 185.994314 0)
			(layer "B.Fab")
			(hide yes)
			(effects
				(font
					(size 1 1)
					(thickness 0.15)
				)
				(justify mirror)
			)
		)
		(property "License" "Apache-2.0"
			(at 319.072656 185.994314 0)
			(layer "B.Fab")
			(hide yes)
			(effects
				(font
					(size 1 1)
					(thickness 0.15)
				)
				(justify mirror)
			)
		)
		(property "MPN" "GRM188R60J476ME15D"
			(at 319.072656 185.994314 0)
			(layer "B.Fab")
			(hide yes)
			(effects
				(font
					(size 1 1)
					(thickness 0.15)
				)
				(justify mirror)
			)
		)
		(property "Manufacturer" "Murata"
			(at 319.072656 185.994314 0)
			(layer "B.Fab")
			(hide yes)
			(effects
				(font
					(size 1 1)
					(thickness 0.15)
				)
				(justify mirror)
			)
		)
		(property "Val" "47u"
			(at 319.072656 185.994314 0)
			(layer "B.Fab")
			(hide yes)
			(effects
				(font
					(size 1 1)
					(thickness 0.15)
				)
				(justify mirror)
			)
		)
		(property "Voltage" ""
			(at 319.072656 185.994314 0)
			(layer "B.Fab")
			(hide yes)
			(effects
				(font
					(size 1 1)
					(thickness 0.15)
				)
				(justify mirror)
			)
		)
		(sheetname "FPGA power")
		(sheetfile "fpga-power.kicad_sch")
		(attr smd)
		(fp_line
			(start -0.3 0.3)
			(end 0.3 0.3)
			(stroke
				(width 0.15)
				(type solid)
			)
			(layer "B.SilkS")
		)
		(fp_line
			(start -0.3 -0.3)
			(end 0.3 -0.3)
			(stroke
				(width 0.15)
				(type solid)
			)
			(layer "B.SilkS")
		)
		(fp_rect
			(start -1.24 0.7)
			(end 1.24 -0.7)
			(stroke
				(width 0.05)
				(type solid)
			)
			(fill no)
			(layer "B.CrtYd")
		)
		(fp_rect
			(start -0.8 0.4)
			(end 0.8 -0.4)
			(stroke
				(width 0.15)
				(type solid)
			)
			(fill no)
			(layer "B.Fab")
		)
		(pad "1" smd roundrect
			(at -0.7 0 180)
			(size 0.6 0.8)
			(layers "B.Cu" "B.Mask" "B.Paste")
			(roundrect_rratio 0.2)
			(net 66 "VDDQ")
			(pintype "passive")
		)
		(pad "2" smd roundrect
			(at 0.7 0 180)
			(size 0.6 0.8)
			(layers "B.Cu" "B.Mask" "B.Paste")
			(roundrect_rratio 0.2)
			(net 5 "GND")
			(pintype "passive")
		)
	)
	(footprint "antmicro-footprints:C_0603_1608Metric"
		(layer "B.Cu")
		(at 173.036328 89.647157 90)
		(descr "Capacitor SMD 0603")
		(tags "capacitor 0603")
		(property "Reference" "C23"
			(at 3.147157 0.463672 270)
			(layer "B.SilkS")
			(effects
				(font
					(size 0.7 0.7)
					(thickness 0.15)
				)
				(justify left bottom mirror)
			)
		)
		(property "Value" "C_47u_0603"
			(at 0 -1.6 270)
			(layer "B.Fab")
			(effects
				(font
					(size 0.7 0.7)
					(thickness 0.15)
				)
				(justify left bottom mirror)
			)
		)
		(property "Description" " "
			(at 0 0 90)
			(layer "F.Fab")
			(hide yes)
			(effects
				(font
					(size 1.27 1.27)
					(thickness 0.15)
				)
			)
		)
		(property "Author" "Antmicro"
			(at 262.683485 -83.389171 0)
			(layer "B.Fab")
			(hide yes)
			(effects
				(font
					(size 1 1)
					(thickness 0.15)
				)
				(justify mirror)
			)
		)
		(property "Dielectric" ""
			(at 262.683485 -83.389171 0)
			(layer "B.Fab")
			(hide yes)
			(effects
				(font
					(size 1 1)
					(thickness 0.15)
				)
				(justify mirror)
			)
		)
		(property "License" "Apache-2.0"
			(at 262.683485 -83.389171 0)
			(layer "B.Fab")
			(hide yes)
			(effects
				(font
					(size 1 1)
					(thickness 0.15)
				)
				(justify mirror)
			)
		)
		(property "MPN" "GRM188R60J476ME15D"
			(at 262.683485 -83.389171 0)
			(layer "B.Fab")
			(hide yes)
			(effects
				(font
					(size 1 1)
					(thickness 0.15)
				)
				(justify mirror)
			)
		)
		(property "Manufacturer" "Murata"
			(at 262.683485 -83.389171 0)
			(layer "B.Fab")
			(hide yes)
			(effects
				(font
					(size 1 1)
					(thickness 0.15)
				)
				(justify mirror)
			)
		)
		(property "Val" "47u"
			(at 262.683485 -83.389171 0)
			(layer "B.Fab")
			(hide yes)
			(effects
				(font
					(size 1 1)
					(thickness 0.15)
				)
				(justify mirror)
			)
		)
		(property "Voltage" ""
			(at 262.683485 -83.389171 0)
			(layer "B.Fab")
			(hide yes)
			(effects
				(font
					(size 1 1)
					(thickness 0.15)
				)
				(justify mirror)
			)
		)
		(sheetname "FPGA power")
		(sheetfile "fpga-power.kicad_sch")
		(attr smd)
		(fp_line
			(start -0.3 -0.3)
			(end 0.3 -0.3)
			(stroke
				(width 0.15)
				(type solid)
			)
			(layer "B.SilkS")
		)
		(fp_line
			(start -0.3 0.3)
			(end 0.3 0.3)
			(stroke
				(width 0.15)
				(type solid)
			)
			(layer "B.SilkS")
		)
		(fp_rect
			(start -1.24 0.7)
			(end 1.24 -0.7)
			(stroke
				(width 0.05)
				(type solid)
			)
			(fill no)
			(layer "B.CrtYd")
		)
		(fp_rect
			(start -0.8 0.4)
			(end 0.8 -0.4)
			(stroke
				(width 0.15)
				(type solid)
			)
			(fill no)
			(layer "B.Fab")
		)
		(pad "1" smd roundrect
			(at -0.7 0 90)
			(size 0.6 0.8)
			(layers "B.Cu" "B.Mask" "B.Paste")
			(roundrect_rratio 0.2)
			(net 459 "3V3_SYS")
			(pintype "passive")
		)
		(pad "2" smd roundrect
			(at 0.7 0 90)
			(size 0.6 0.8)
			(layers "B.Cu" "B.Mask" "B.Paste")
			(roundrect_rratio 0.2)
			(net 5 "GND")
			(pintype "passive")
		)
	)
	(footprint "antmicro-footprints:C_0603_1608Metric"
		(layer "B.Cu")
		(at 159.036328 87.247157)
		(descr "Capacitor SMD 0603")
		(tags "capacitor 0603")
		(property "Reference" "C27"
			(at 1.063672 -0.547157 180)
			(layer "B.SilkS")
			(effects
				(font
					(size 0.7 0.7)
					(thickness 0.15)
				)
				(justify left bottom mirror)
			)
		)
		(property "Value" "C_47u_0603"
			(at 0 -1.6 180)
			(layer "B.Fab")
			(effects
				(font
					(size 0.7 0.7)
					(thickness 0.15)
				)
				(justify left bottom mirror)
			)
		)
		(property "Description" " "
			(at 0 0 0)
			(layer "F.Fab")
			(hide yes)
			(effects
				(font
					(size 1.27 1.27)
					(thickness 0.15)
				)
			)
		)
		(property "Author" "Antmicro"
			(at 0 0 0)
			(layer "B.Fab")
			(hide yes)
			(effects
				(font
					(size 1 1)
					(thickness 0.15)
				)
				(justify mirror)
			)
		)
		(property "Dielectric" ""
			(at 0 0 0)
			(layer "B.Fab")
			(hide yes)
			(effects
				(font
					(size 1 1)
					(thickness 0.15)
				)
				(justify mirror)
			)
		)
		(property "License" "Apache-2.0"
			(at 0 0 0)
			(layer "B.Fab")
			(hide yes)
			(effects
				(font
					(size 1 1)
					(thickness 0.15)
				)
				(justify mirror)
			)
		)
		(property "MPN" "GRM188R60J476ME15D"
			(at 0 0 0)
			(layer "B.Fab")
			(hide yes)
			(effects
				(font
					(size 1 1)
					(thickness 0.15)
				)
				(justify mirror)
			)
		)
		(property "Manufacturer" "Murata"
			(at 0 0 0)
			(layer "B.Fab")
			(hide yes)
			(effects
				(font
					(size 1 1)
					(thickness 0.15)
				)
				(justify mirror)
			)
		)
		(property "Val" "47u"
			(at 0 0 0)
			(layer "B.Fab")
			(hide yes)
			(effects
				(font
					(size 1 1)
					(thickness 0.15)
				)
				(justify mirror)
			)
		)
		(property "Voltage" ""
			(at 0 0 0)
			(layer "B.Fab")
			(hide yes)
			(effects
				(font
					(size 1 1)
					(thickness 0.15)
				)
				(justify mirror)
			)
		)
		(sheetname "FPGA power")
		(sheetfile "fpga-power.kicad_sch")
		(attr smd)
		(fp_line
			(start -0.3 -0.3)
			(end 0.3 -0.3)
			(stroke
				(width 0.15)
				(type solid)
			)
			(layer "B.SilkS")
		)
		(fp_line
			(start -0.3 0.3)
			(end 0.3 0.3)
			(stroke
				(width 0.15)
				(type solid)
			)
			(layer "B.SilkS")
		)
		(fp_rect
			(start -1.24 0.7)
			(end 1.24 -0.7)
			(stroke
				(width 0.05)
				(type solid)
			)
			(fill no)
			(layer "B.CrtYd")
		)
		(fp_rect
			(start -0.8 0.4)
			(end 0.8 -0.4)
			(stroke
				(width 0.15)
				(type solid)
			)
			(fill no)
			(layer "B.Fab")
		)
		(pad "1" smd roundrect
			(at -0.7 0)
			(size 0.6 0.8)
			(layers "B.Cu" "B.Mask" "B.Paste")
			(roundrect_rratio 0.2)
			(net 66 "VDDQ")
			(pintype "passive")
		)
		(pad "2" smd roundrect
			(at 0.7 0)
			(size 0.6 0.8)
			(layers "B.Cu" "B.Mask" "B.Paste")
			(roundrect_rratio 0.2)
			(net 5 "GND")
			(pintype "passive")
		)
	)
	(footprint "antmicro-footprints:C_0603_1608Metric"
		(layer "B.Cu")
		(at 161.411328 99.247157 180)
		(descr "Capacitor SMD 0603")
		(tags "capacitor 0603")
		(property "Reference" "C96"
			(at -1.088672 -1.352843 0)
			(layer "B.SilkS")
			(effects
				(font
					(size 0.7 0.7)
					(thickness 0.15)
				)
				(justify left bottom mirror)
			)
		)
		(property "Value" "C_47u_0603"
			(at 0 -1.6 0)
			(layer "B.Fab")
			(effects
				(font
					(size 0.7 0.7)
					(thickness 0.15)
				)
				(justify left bottom mirror)
			)
		)
		(property "Description" " "
			(at 0 0 180)
			(layer "F.Fab")
			(hide yes)
			(effects
				(font
					(size 1.27 1.27)
					(thickness 0.15)
				)
			)
		)
		(property "Author" "Antmicro"
			(at 322.822656 198.494314 0)
			(layer "B.Fab")
			(hide yes)
			(effects
				(font
					(size 1 1)
					(thickness 0.15)
				)
				(justify mirror)
			)
		)
		(property "Dielectric" ""
			(at 322.822656 198.494314 0)
			(layer "B.Fab")
			(hide yes)
			(effects
				(font
					(size 1 1)
					(thickness 0.15)
				)
				(justify mirror)
			)
		)
		(property "License" "Apache-2.0"
			(at 322.822656 198.494314 0)
			(layer "B.Fab")
			(hide yes)
			(effects
				(font
					(size 1 1)
					(thickness 0.15)
				)
				(justify mirror)
			)
		)
		(property "MPN" "GRM188R60J476ME15D"
			(at 322.822656 198.494314 0)
			(layer "B.Fab")
			(hide yes)
			(effects
				(font
					(size 1 1)
					(thickness 0.15)
				)
				(justify mirror)
			)
		)
		(property "Manufacturer" "Murata"
			(at 322.822656 198.494314 0)
			(layer "B.Fab")
			(hide yes)
			(effects
				(font
					(size 1 1)
					(thickness 0.15)
				)
				(justify mirror)
			)
		)
		(property "Val" "47u"
			(at 322.822656 198.494314 0)
			(layer "B.Fab")
			(hide yes)
			(effects
				(font
					(size 1 1)
					(thickness 0.15)
				)
				(justify mirror)
			)
		)
		(property "Voltage" ""
			(at 322.822656 198.494314 0)
			(layer "B.Fab")
			(hide yes)
			(effects
				(font
					(size 1 1)
					(thickness 0.15)
				)
				(justify mirror)
			)
		)
		(sheetname "FPGA power")
		(sheetfile "fpga-power.kicad_sch")
		(attr smd)
		(fp_line
			(start -0.3 0.3)
			(end 0.3 0.3)
			(stroke
				(width 0.15)
				(type solid)
			)
			(layer "B.SilkS")
		)
		(fp_line
			(start -0.3 -0.3)
			(end 0.3 -0.3)
			(stroke
				(width 0.15)
				(type solid)
			)
			(layer "B.SilkS")
		)
		(fp_rect
			(start -1.24 0.7)
			(end 1.24 -0.7)
			(stroke
				(width 0.05)
				(type solid)
			)
			(fill no)
			(layer "B.CrtYd")
		)
		(fp_rect
			(start -0.8 0.4)
			(end 0.8 -0.4)
			(stroke
				(width 0.15)
				(type solid)
			)
			(fill no)
			(layer "B.Fab")
		)
		(pad "1" smd roundrect
			(at -0.7 0 180)
			(size 0.6 0.8)
			(layers "B.Cu" "B.Mask" "B.Paste")
			(roundrect_rratio 0.2)
			(net 459 "3V3_SYS")
			(pintype "passive")
		)
		(pad "2" smd roundrect
			(at 0.7 0 180)
			(size 0.6 0.8)
			(layers "B.Cu" "B.Mask" "B.Paste")
			(roundrect_rratio 0.2)
			(net 5 "GND")
			(pintype "passive")
		)
	)
	(footprint "antmicro-footprints:C_0603_1608Metric"
		(layer "B.Cu")
		(at 175.036328 95.497157 90)
		(descr "Capacitor SMD 0603")
		(tags "capacitor 0603")
		(property "Reference" "C93"
			(at 0.397157 1.363672 270)
			(layer "B.SilkS")
			(effects
				(font
					(size 0.7 0.7)
					(thickness 0.15)
				)
				(justify left bottom mirror)
			)
		)
		(property "Value" "C_47u_0603"
			(at 0 -1.6 270)
			(layer "B.Fab")
			(effects
				(font
					(size 0.7 0.7)
					(thickness 0.15)
				)
				(justify left bottom mirror)
			)
		)
		(property "Description" " "
			(at 0 0 90)
			(layer "F.Fab")
			(hide yes)
			(effects
				(font
					(size 1.27 1.27)
					(thickness 0.15)
				)
			)
		)
		(property "Author" "Antmicro"
			(at 270.533485 -79.539171 0)
			(layer "B.Fab")
			(hide yes)
			(effects
				(font
					(size 1 1)
					(thickness 0.15)
				)
				(justify mirror)
			)
		)
		(property "Dielectric" ""
			(at 270.533485 -79.539171 0)
			(layer "B.Fab")
			(hide yes)
			(effects
				(font
					(size 1 1)
					(thickness 0.15)
				)
				(justify mirror)
			)
		)
		(property "License" "Apache-2.0"
			(at 270.533485 -79.539171 0)
			(layer "B.Fab")
			(hide yes)
			(effects
				(font
					(size 1 1)
					(thickness 0.15)
				)
				(justify mirror)
			)
		)
		(property "MPN" "GRM188R60J476ME15D"
			(at 270.533485 -79.539171 0)
			(layer "B.Fab")
			(hide yes)
			(effects
				(font
					(size 1 1)
					(thickness 0.15)
				)
				(justify mirror)
			)
		)
		(property "Manufacturer" "Murata"
			(at 270.533485 -79.539171 0)
			(layer "B.Fab")
			(hide yes)
			(effects
				(font
					(size 1 1)
					(thickness 0.15)
				)
				(justify mirror)
			)
		)
		(property "Val" "47u"
			(at 270.533485 -79.539171 0)
			(layer "B.Fab")
			(hide yes)
			(effects
				(font
					(size 1 1)
					(thickness 0.15)
				)
				(justify mirror)
			)
		)
		(property "Voltage" ""
			(at 270.533485 -79.539171 0)
			(layer "B.Fab")
			(hide yes)
			(effects
				(font
					(size 1 1)
					(thickness 0.15)
				)
				(justify mirror)
			)
		)
		(sheetname "FPGA power")
		(sheetfile "fpga-power.kicad_sch")
		(attr smd)
		(fp_line
			(start -0.3 -0.3)
			(end 0.3 -0.3)
			(stroke
				(width 0.15)
				(type solid)
			)
			(layer "B.SilkS")
		)
		(fp_line
			(start -0.3 0.3)
			(end 0.3 0.3)
			(stroke
				(width 0.15)
				(type solid)
			)
			(layer "B.SilkS")
		)
		(fp_rect
			(start -1.24 0.7)
			(end 1.24 -0.7)
			(stroke
				(width 0.05)
				(type solid)
			)
			(fill no)
			(layer "B.CrtYd")
		)
		(fp_rect
			(start -0.8 0.4)
			(end 0.8 -0.4)
			(stroke
				(width 0.15)
				(type solid)
			)
			(fill no)
			(layer "B.Fab")
		)
		(pad "1" smd roundrect
			(at -0.7 0 90)
			(size 0.6 0.8)
			(layers "B.Cu" "B.Mask" "B.Paste")
			(roundrect_rratio 0.2)
			(net 459 "3V3_SYS")
			(pintype "passive")
		)
		(pad "2" smd roundrect
			(at 0.7 0 90)
			(size 0.6 0.8)
			(layers "B.Cu" "B.Mask" "B.Paste")
			(roundrect_rratio 0.2)
			(net 5 "GND")
			(pintype "passive")
		)
	)
	(footprint "antmicro-footprints:C_0603_1608Metric"
		(layer "B.Cu")
		(at 179.661328 102.247157 -90)
		(descr "Capacitor SMD 0603")
		(tags "capacitor 0603")
		(property "Reference" "C94"
			(at -1.047157 -1.338672 90)
			(layer "B.SilkS")
			(effects
				(font
					(size 0.7 0.7)
					(thickness 0.15)
				)
				(justify left bottom mirror)
			)
		)
		(property "Value" "C_47u_0603"
			(at 0 -1.6 90)
			(layer "B.Fab")
			(effects
				(font
					(size 0.7 0.7)
					(thickness 0.15)
				)
				(justify left bottom mirror)
			)
		)
		(property "Description" " "
			(at 0 0 270)
			(layer "F.Fab")
			(hide yes)
			(effects
				(font
					(size 1.27 1.27)
					(thickness 0.15)
				)
			)
		)
		(property "Author" "Antmicro"
			(at 77.414171 281.908485 0)
			(layer "B.Fab")
			(hide yes)
			(effects
				(font
					(size 1 1)
					(thickness 0.15)
				)
				(justify mirror)
			)
		)
		(property "Dielectric" ""
			(at 77.414171 281.908485 0)
			(layer "B.Fab")
			(hide yes)
			(effects
				(font
					(size 1 1)
					(thickness 0.15)
				)
				(justify mirror)
			)
		)
		(property "License" "Apache-2.0"
			(at 77.414171 281.908485 0)
			(layer "B.Fab")
			(hide yes)
			(effects
				(font
					(size 1 1)
					(thickness 0.15)
				)
				(justify mirror)
			)
		)
		(property "MPN" "GRM188R60J476ME15D"
			(at 77.414171 281.908485 0)
			(layer "B.Fab")
			(hide yes)
			(effects
				(font
					(size 1 1)
					(thickness 0.15)
				)
				(justify mirror)
			)
		)
		(property "Manufacturer" "Murata"
			(at 77.414171 281.908485 0)
			(layer "B.Fab")
			(hide yes)
			(effects
				(font
					(size 1 1)
					(thickness 0.15)
				)
				(justify mirror)
			)
		)
		(property "Val" "47u"
			(at 77.414171 281.908485 0)
			(layer "B.Fab")
			(hide yes)
			(effects
				(font
					(size 1 1)
					(thickness 0.15)
				)
				(justify mirror)
			)
		)
		(property "Voltage" ""
			(at 77.414171 281.908485 0)
			(layer "B.Fab")
			(hide yes)
			(effects
				(font
					(size 1 1)
					(thickness 0.15)
				)
				(justify mirror)
			)
		)
		(sheetname "FPGA power")
		(sheetfile "fpga-power.kicad_sch")
		(attr smd)
		(fp_line
			(start -0.3 0.3)
			(end 0.3 0.3)
			(stroke
				(width 0.15)
				(type solid)
			)
			(layer "B.SilkS")
		)
		(fp_line
			(start -0.3 -0.3)
			(end 0.3 -0.3)
			(stroke
				(width 0.15)
				(type solid)
			)
			(layer "B.SilkS")
		)
		(fp_rect
			(start -1.24 0.7)
			(end 1.24 -0.7)
			(stroke
				(width 0.05)
				(type solid)
			)
			(fill no)
			(layer "B.CrtYd")
		)
		(fp_rect
			(start -0.8 0.4)
			(end 0.8 -0.4)
			(stroke
				(width 0.15)
				(type solid)
			)
			(fill no)
			(layer "B.Fab")
		)
		(pad "1" smd roundrect
			(at -0.7 0 270)
			(size 0.6 0.8)
			(layers "B.Cu" "B.Mask" "B.Paste")
			(roundrect_rratio 0.2)
			(net 459 "3V3_SYS")
			(pintype "passive")
		)
		(pad "2" smd roundrect
			(at 0.7 0 270)
			(size 0.6 0.8)
			(layers "B.Cu" "B.Mask" "B.Paste")
			(roundrect_rratio 0.2)
			(net 5 "GND")
			(pintype "passive")
		)
	)
	(footprint "antmicro-footprints:C_0603_1608Metric"
		(layer "B.Cu")
		(at 169.036328 105.497157 -90)
		(descr "Capacitor SMD 0603")
		(tags "capacitor 0603")
		(property "Reference" "C95"
			(at 1.002843 -0.363672 90)
			(layer "B.SilkS")
			(effects
				(font
					(size 0.7 0.7)
					(thickness 0.15)
				)
				(justify left bottom mirror)
			)
		)
		(property "Value" "C_47u_0603"
			(at 0 -1.6 90)
			(layer "B.Fab")
			(effects
				(font
					(size 0.7 0.7)
					(thickness 0.15)
				)
				(justify left bottom mirror)
			)
		)
		(property "Description" " "
			(at 0 0 270)
			(layer "F.Fab")
			(hide yes)
			(effects
				(font
					(size 1.27 1.27)
					(thickness 0.15)
				)
			)
		)
		(property "Author" "Antmicro"
			(at 63.539171 274.533485 0)
			(layer "B.Fab")
			(hide yes)
			(effects
				(font
					(size 1 1)
					(thickness 0.15)
				)
				(justify mirror)
			)
		)
		(property "Dielectric" ""
			(at 63.539171 274.533485 0)
			(layer "B.Fab")
			(hide yes)
			(effects
				(font
					(size 1 1)
					(thickness 0.15)
				)
				(justify mirror)
			)
		)
		(property "License" "Apache-2.0"
			(at 63.539171 274.533485 0)
			(layer "B.Fab")
			(hide yes)
			(effects
				(font
					(size 1 1)
					(thickness 0.15)
				)
				(justify mirror)
			)
		)
		(property "MPN" "GRM188R60J476ME15D"
			(at 63.539171 274.533485 0)
			(layer "B.Fab")
			(hide yes)
			(effects
				(font
					(size 1 1)
					(thickness 0.15)
				)
				(justify mirror)
			)
		)
		(property "Manufacturer" "Murata"
			(at 63.539171 274.533485 0)
			(layer "B.Fab")
			(hide yes)
			(effects
				(font
					(size 1 1)
					(thickness 0.15)
				)
				(justify mirror)
			)
		)
		(property "Val" "47u"
			(at 63.539171 274.533485 0)
			(layer "B.Fab")
			(hide yes)
			(effects
				(font
					(size 1 1)
					(thickness 0.15)
				)
				(justify mirror)
			)
		)
		(property "Voltage" ""
			(at 63.539171 274.533485 0)
			(layer "B.Fab")
			(hide yes)
			(effects
				(font
					(size 1 1)
					(thickness 0.15)
				)
				(justify mirror)
			)
		)
		(sheetname "FPGA power")
		(sheetfile "fpga-power.kicad_sch")
		(attr smd)
		(fp_line
			(start -0.3 0.3)
			(end 0.3 0.3)
			(stroke
				(width 0.15)
				(type solid)
			)
			(layer "B.SilkS")
		)
		(fp_line
			(start -0.3 -0.3)
			(end 0.3 -0.3)
			(stroke
				(width 0.15)
				(type solid)
			)
			(layer "B.SilkS")
		)
		(fp_rect
			(start -1.24 0.7)
			(end 1.24 -0.7)
			(stroke
				(width 0.05)
				(type solid)
			)
			(fill no)
			(layer "B.CrtYd")
		)
		(fp_rect
			(start -0.8 0.4)
			(end 0.8 -0.4)
			(stroke
				(width 0.15)
				(type solid)
			)
			(fill no)
			(layer "B.Fab")
		)
		(pad "1" smd roundrect
			(at -0.7 0 270)
			(size 0.6 0.8)
			(layers "B.Cu" "B.Mask" "B.Paste")
			(roundrect_rratio 0.2)
			(net 459 "3V3_SYS")
			(pintype "passive")
		)
		(pad "2" smd roundrect
			(at 0.7 0 270)
			(size 0.6 0.8)
			(layers "B.Cu" "B.Mask" "B.Paste")
			(roundrect_rratio 0.2)
			(net 5 "GND")
			(pintype "passive")
		)
	)
	(footprint "antmicro-footprints:C_0201"
		(layer "B.Cu")
		(at 166.036328 98.372157)
		(descr "Capacitor SMD 0201")
		(tags "capacitor SMD 0201")
		(property "Reference" "C70"
			(at 0.663672 1.077843 180)
			(layer "B.SilkS")
			(effects
				(font
					(size 0.7 0.7)
					(thickness 0.15)
				)
				(justify left bottom mirror)
			)
		)
		(property "Value" "C_100n_0201"
			(at 0 -1.4 180)
			(layer "B.Fab")
			(effects
				(font
					(size 0.7 0.7)
					(thickness 0.15)
				)
				(justify left bottom mirror)
			)
		)
		(property "Description" " "
			(at 0 0 0)
			(layer "F.Fab")
			(hide yes)
			(effects
				(font
					(size 1.27 1.27)
					(thickness 0.15)
				)
			)
		)
		(property "Author" "Antmicro"
			(at 0 0 0)
			(layer "B.Fab")
			(hide yes)
			(effects
				(font
					(size 1 1)
					(thickness 0.15)
				)
				(justify mirror)
			)
		)
		(property "Dielectric" ""
			(at 0 0 0)
			(layer "B.Fab")
			(hide yes)
			(effects
				(font
					(size 1 1)
					(thickness 0.15)
				)
				(justify mirror)
			)
		)
		(property "License" "Apache-2.0"
			(at 0 0 0)
			(layer "B.Fab")
			(hide yes)
			(effects
				(font
					(size 1 1)
					(thickness 0.15)
				)
				(justify mirror)
			)
		)
		(property "MPN" "CC0201KRX6S5BB104"
			(at 0 0 0)
			(layer "B.Fab")
			(hide yes)
			(effects
				(font
					(size 1 1)
					(thickness 0.15)
				)
				(justify mirror)
			)
		)
		(property "Manufacturer" "Yaego"
			(at 0 0 0)
			(layer "B.Fab")
			(hide yes)
			(effects
				(font
					(size 1 1)
					(thickness 0.15)
				)
				(justify mirror)
			)
		)
		(property "Val" "100n"
			(at 0 0 0)
			(layer "B.Fab")
			(hide yes)
			(effects
				(font
					(size 1 1)
					(thickness 0.15)
				)
				(justify mirror)
			)
		)
		(property "Voltage" ""
			(at 0 0 0)
			(layer "B.Fab")
			(hide yes)
			(effects
				(font
					(size 1 1)
					(thickness 0.15)
				)
				(justify mirror)
			)
		)
		(sheetname "FPGA power")
		(sheetfile "fpga-power.kicad_sch")
		(attr smd)
		(fp_rect
			(start -0.72 0.38)
			(end 0.72 -0.38)
			(stroke
				(width 0.05)
				(type solid)
			)
			(fill no)
			(layer "B.CrtYd")
		)
		(fp_rect
			(start 0.3 -0.15)
			(end -0.301 0.149)
			(stroke
				(width 0.15)
				(type solid)
			)
			(fill no)
			(layer "B.Fab")
		)
		(pad "" smd roundrect
			(at -0.349 0.002)
			(size 0.318 0.36)
			(layers "B.Paste")
			(roundrect_rratio 0.25)
		)
		(pad "" smd roundrect
			(at 0.341 0.002)
			(size 0.318 0.36)
			(layers "B.Paste")
			(roundrect_rratio 0.25)
		)
		(pad "1" smd roundrect
			(at -0.321 0.002)
			(size 0.46 0.4)
			(layers "B.Cu" "B.Mask")
			(roundrect_rratio 0.25)
			(net 465 "1V0_SYS")
			(pintype "passive")
		)
		(pad "2" smd roundrect
			(at 0.32 0.002)
			(size 0.46 0.4)
			(layers "B.Cu" "B.Mask")
			(roundrect_rratio 0.25)
			(net 5 "GND")
			(pintype "passive")
		)
	)
	(footprint "antmicro-footprints:C_0201"
		(layer "B.Cu")
		(at 165.536328 95.622157)
		(descr "Capacitor SMD 0201")
		(tags "capacitor SMD 0201")
		(property "Reference" "C45"
			(at 0.963672 -0.322157 180)
			(layer "B.SilkS")
			(effects
				(font
					(size 0.7 0.7)
					(thickness 0.15)
				)
				(justify left bottom mirror)
			)
		)
		(property "Value" "C_100n_0201"
			(at 0 -1.4 180)
			(layer "B.Fab")
			(effects
				(font
					(size 0.7 0.7)
					(thickness 0.15)
				)
				(justify left bottom mirror)
			)
		)
		(property "Description" " "
			(at 0 0 0)
			(layer "F.Fab")
			(hide yes)
			(effects
				(font
					(size 1.27 1.27)
					(thickness 0.15)
				)
			)
		)
		(property "Author" "Antmicro"
			(at 0 0 0)
			(layer "B.Fab")
			(hide yes)
			(effects
				(font
					(size 1 1)
					(thickness 0.15)
				)
				(justify mirror)
			)
		)
		(property "Dielectric" ""
			(at 0 0 0)
			(layer "B.Fab")
			(hide yes)
			(effects
				(font
					(size 1 1)
					(thickness 0.15)
				)
				(justify mirror)
			)
		)
		(property "License" "Apache-2.0"
			(at 0 0 0)
			(layer "B.Fab")
			(hide yes)
			(effects
				(font
					(size 1 1)
					(thickness 0.15)
				)
				(justify mirror)
			)
		)
		(property "MPN" "CC0201KRX6S5BB104"
			(at 0 0 0)
			(layer "B.Fab")
			(hide yes)
			(effects
				(font
					(size 1 1)
					(thickness 0.15)
				)
				(justify mirror)
			)
		)
		(property "Manufacturer" "Yaego"
			(at 0 0 0)
			(layer "B.Fab")
			(hide yes)
			(effects
				(font
					(size 1 1)
					(thickness 0.15)
				)
				(justify mirror)
			)
		)
		(property "Val" "100n"
			(at 0 0 0)
			(layer "B.Fab")
			(hide yes)
			(effects
				(font
					(size 1 1)
					(thickness 0.15)
				)
				(justify mirror)
			)
		)
		(property "Voltage" ""
			(at 0 0 0)
			(layer "B.Fab")
			(hide yes)
			(effects
				(font
					(size 1 1)
					(thickness 0.15)
				)
				(justify mirror)
			)
		)
		(sheetname "FPGA power")
		(sheetfile "fpga-power.kicad_sch")
		(attr smd)
		(fp_rect
			(start -0.72 0.38)
			(end 0.72 -0.38)
			(stroke
				(width 0.05)
				(type solid)
			)
			(fill no)
			(layer "B.CrtYd")
		)
		(fp_rect
			(start 0.3 -0.15)
			(end -0.301 0.149)
			(stroke
				(width 0.15)
				(type solid)
			)
			(fill no)
			(layer "B.Fab")
		)
		(pad "" smd roundrect
			(at -0.349 0.002)
			(size 0.318 0.36)
			(layers "B.Paste")
			(roundrect_rratio 0.25)
		)
		(pad "" smd roundrect
			(at 0.341 0.002)
			(size 0.318 0.36)
			(layers "B.Paste")
			(roundrect_rratio 0.25)
		)
		(pad "1" smd roundrect
			(at -0.321 0.002)
			(size 0.46 0.4)
			(layers "B.Cu" "B.Mask")
			(roundrect_rratio 0.25)
			(net 460 "1V8_SYS")
			(pintype "passive")
		)
		(pad "2" smd roundrect
			(at 0.32 0.002)
			(size 0.46 0.4)
			(layers "B.Cu" "B.Mask")
			(roundrect_rratio 0.25)
			(net 5 "GND")
			(pintype "passive")
		)
	)
	(footprint "antmicro-footprints:C_0201"
		(layer "B.Cu")
		(at 165.036328 90.625 180)
		(descr "Capacitor SMD 0201")
		(tags "capacitor SMD 0201")
		(property "Reference" "C71"
			(at -2.463672 -0.375 0)
			(layer "B.SilkS")
			(effects
				(font
					(size 0.7 0.7)
					(thickness 0.15)
				)
				(justify left bottom mirror)
			)
		)
		(property "Value" "C_100n_0201"
			(at 0 -1.4 0)
			(layer "B.Fab")
			(effects
				(font
					(size 0.7 0.7)
					(thickness 0.15)
				)
				(justify left bottom mirror)
			)
		)
		(property "Description" " "
			(at 0 0 180)
			(layer "F.Fab")
			(hide yes)
			(effects
				(font
					(size 1.27 1.27)
					(thickness 0.15)
				)
			)
		)
		(property "Author" "Antmicro"
			(at 330.072656 181.25 0)
			(layer "B.Fab")
			(hide yes)
			(effects
				(font
					(size 1 1)
					(thickness 0.15)
				)
				(justify mirror)
			)
		)
		(property "Dielectric" ""
			(at 330.072656 181.25 0)
			(layer "B.Fab")
			(hide yes)
			(effects
				(font
					(size 1 1)
					(thickness 0.15)
				)
				(justify mirror)
			)
		)
		(property "License" "Apache-2.0"
			(at 330.072656 181.25 0)
			(layer "B.Fab")
			(hide yes)
			(effects
				(font
					(size 1 1)
					(thickness 0.15)
				)
				(justify mirror)
			)
		)
		(property "MPN" "CC0201KRX6S5BB104"
			(at 330.072656 181.25 0)
			(layer "B.Fab")
			(hide yes)
			(effects
				(font
					(size 1 1)
					(thickness 0.15)
				)
				(justify mirror)
			)
		)
		(property "Manufacturer" "Yaego"
			(at 330.072656 181.25 0)
			(layer "B.Fab")
			(hide yes)
			(effects
				(font
					(size 1 1)
					(thickness 0.15)
				)
				(justify mirror)
			)
		)
		(property "Val" "100n"
			(at 330.072656 181.25 0)
			(layer "B.Fab")
			(hide yes)
			(effects
				(font
					(size 1 1)
					(thickness 0.15)
				)
				(justify mirror)
			)
		)
		(property "Voltage" ""
			(at 330.072656 181.25 0)
			(layer "B.Fab")
			(hide yes)
			(effects
				(font
					(size 1 1)
					(thickness 0.15)
				)
				(justify mirror)
			)
		)
		(sheetname "FPGA power")
		(sheetfile "fpga-power.kicad_sch")
		(attr smd)
		(fp_rect
			(start -0.72 0.38)
			(end 0.72 -0.38)
			(stroke
				(width 0.05)
				(type solid)
			)
			(fill no)
			(layer "B.CrtYd")
		)
		(fp_rect
			(start 0.3 -0.15)
			(end -0.301 0.149)
			(stroke
				(width 0.15)
				(type solid)
			)
			(fill no)
			(layer "B.Fab")
		)
		(pad "" smd roundrect
			(at -0.349 0.002 180)
			(size 0.318 0.36)
			(layers "B.Paste")
			(roundrect_rratio 0.25)
		)
		(pad "" smd roundrect
			(at 0.341 0.002 180)
			(size 0.318 0.36)
			(layers "B.Paste")
			(roundrect_rratio 0.25)
		)
		(pad "1" smd roundrect
			(at -0.321 0.002 180)
			(size 0.46 0.4)
			(layers "B.Cu" "B.Mask")
			(roundrect_rratio 0.25)
			(net 460 "1V8_SYS")
			(pintype "passive")
		)
		(pad "2" smd roundrect
			(at 0.32 0.002 180)
			(size 0.46 0.4)
			(layers "B.Cu" "B.Mask")
			(roundrect_rratio 0.25)
			(net 5 "GND")
			(pintype "passive")
		)
	)
	(footprint "antmicro-footprints:C_0201"
		(layer "B.Cu")
		(at 164.336328 92.497157 90)
		(descr "Capacitor SMD 0201")
		(tags "capacitor SMD 0201")
		(property "Reference" "C49"
			(at 0.997157 1.163672 270)
			(layer "B.SilkS")
			(effects
				(font
					(size 0.7 0.7)
					(thickness 0.15)
				)
				(justify left bottom mirror)
			)
		)
		(property "Value" "C_100n_0201"
			(at 0 -1.4 270)
			(layer "B.Fab")
			(effects
				(font
					(size 0.7 0.7)
					(thickness 0.15)
				)
				(justify left bottom mirror)
			)
		)
		(property "Description" " "
			(at 0 0 90)
			(layer "F.Fab")
			(hide yes)
			(effects
				(font
					(size 1.27 1.27)
					(thickness 0.15)
				)
			)
		)
		(property "Author" "Antmicro"
			(at 256.833485 -71.839171 0)
			(layer "B.Fab")
			(hide yes)
			(effects
				(font
					(size 1 1)
					(thickness 0.15)
				)
				(justify mirror)
			)
		)
		(property "Dielectric" ""
			(at 256.833485 -71.839171 0)
			(layer "B.Fab")
			(hide yes)
			(effects
				(font
					(size 1 1)
					(thickness 0.15)
				)
				(justify mirror)
			)
		)
		(property "License" "Apache-2.0"
			(at 256.833485 -71.839171 0)
			(layer "B.Fab")
			(hide yes)
			(effects
				(font
					(size 1 1)
					(thickness 0.15)
				)
				(justify mirror)
			)
		)
		(property "MPN" "CC0201KRX6S5BB104"
			(at 256.833485 -71.839171 0)
			(layer "B.Fab")
			(hide yes)
			(effects
				(font
					(size 1 1)
					(thickness 0.15)
				)
				(justify mirror)
			)
		)
		(property "Manufacturer" "Yaego"
			(at 256.833485 -71.839171 0)
			(layer "B.Fab")
			(hide yes)
			(effects
				(font
					(size 1 1)
					(thickness 0.15)
				)
				(justify mirror)
			)
		)
		(property "Val" "100n"
			(at 256.833485 -71.839171 0)
			(layer "B.Fab")
			(hide yes)
			(effects
				(font
					(size 1 1)
					(thickness 0.15)
				)
				(justify mirror)
			)
		)
		(property "Voltage" ""
			(at 256.833485 -71.839171 0)
			(layer "B.Fab")
			(hide yes)
			(effects
				(font
					(size 1 1)
					(thickness 0.15)
				)
				(justify mirror)
			)
		)
		(sheetname "FPGA power")
		(sheetfile "fpga-power.kicad_sch")
		(attr smd)
		(fp_rect
			(start -0.72 0.38)
			(end 0.72 -0.38)
			(stroke
				(width 0.05)
				(type solid)
			)
			(fill no)
			(layer "B.CrtYd")
		)
		(fp_rect
			(start 0.3 -0.15)
			(end -0.301 0.149)
			(stroke
				(width 0.15)
				(type solid)
			)
			(fill no)
			(layer "B.Fab")
		)
		(pad "" smd roundrect
			(at -0.349 0.002 90)
			(size 0.318 0.36)
			(layers "B.Paste")
			(roundrect_rratio 0.25)
		)
		(pad "" smd roundrect
			(at 0.341 0.002 90)
			(size 0.318 0.36)
			(layers "B.Paste")
			(roundrect_rratio 0.25)
		)
		(pad "1" smd roundrect
			(at -0.321 0.002 90)
			(size 0.46 0.4)
			(layers "B.Cu" "B.Mask")
			(roundrect_rratio 0.25)
			(net 460 "1V8_SYS")
			(pintype "passive")
		)
		(pad "2" smd roundrect
			(at 0.32 0.002 90)
			(size 0.46 0.4)
			(layers "B.Cu" "B.Mask")
			(roundrect_rratio 0.25)
			(net 5 "GND")
			(pintype "passive")
		)
	)
	(footprint "antmicro-footprints:C_0201"
		(layer "B.Cu")
		(at 171.511328 96.372157)
		(descr "Capacitor SMD 0201")
		(tags "capacitor SMD 0201")
		(property "Reference" "C75"
			(at -0.511328 0.427843 180)
			(layer "B.SilkS")
			(effects
				(font
					(size 0.7 0.7)
					(thickness 0.15)
				)
				(justify left bottom mirror)
			)
		)
		(property "Value" "C_100n_0201"
			(at 0 -1.4 180)
			(layer "B.Fab")
			(effects
				(font
					(size 0.7 0.7)
					(thickness 0.15)
				)
				(justify left bottom mirror)
			)
		)
		(property "Description" " "
			(at 0 0 0)
			(layer "F.Fab")
			(hide yes)
			(effects
				(font
					(size 1.27 1.27)
					(thickness 0.15)
				)
			)
		)
		(property "Author" "Antmicro"
			(at 0 0 0)
			(layer "B.Fab")
			(hide yes)
			(effects
				(font
					(size 1 1)
					(thickness 0.15)
				)
				(justify mirror)
			)
		)
		(property "Dielectric" ""
			(at 0 0 0)
			(layer "B.Fab")
			(hide yes)
			(effects
				(font
					(size 1 1)
					(thickness 0.15)
				)
				(justify mirror)
			)
		)
		(property "License" "Apache-2.0"
			(at 0 0 0)
			(layer "B.Fab")
			(hide yes)
			(effects
				(font
					(size 1 1)
					(thickness 0.15)
				)
				(justify mirror)
			)
		)
		(property "MPN" "CC0201KRX6S5BB104"
			(at 0 0 0)
			(layer "B.Fab")
			(hide yes)
			(effects
				(font
					(size 1 1)
					(thickness 0.15)
				)
				(justify mirror)
			)
		)
		(property "Manufacturer" "Yaego"
			(at 0 0 0)
			(layer "B.Fab")
			(hide yes)
			(effects
				(font
					(size 1 1)
					(thickness 0.15)
				)
				(justify mirror)
			)
		)
		(property "Val" "100n"
			(at 0 0 0)
			(layer "B.Fab")
			(hide yes)
			(effects
				(font
					(size 1 1)
					(thickness 0.15)
				)
				(justify mirror)
			)
		)
		(property "Voltage" ""
			(at 0 0 0)
			(layer "B.Fab")
			(hide yes)
			(effects
				(font
					(size 1 1)
					(thickness 0.15)
				)
				(justify mirror)
			)
		)
		(sheetname "FPGA power")
		(sheetfile "fpga-power.kicad_sch")
		(attr smd)
		(fp_rect
			(start -0.72 0.38)
			(end 0.72 -0.38)
			(stroke
				(width 0.05)
				(type solid)
			)
			(fill no)
			(layer "B.CrtYd")
		)
		(fp_rect
			(start 0.3 -0.15)
			(end -0.301 0.149)
			(stroke
				(width 0.15)
				(type solid)
			)
			(fill no)
			(layer "B.Fab")
		)
		(pad "" smd roundrect
			(at -0.349 0.002)
			(size 0.318 0.36)
			(layers "B.Paste")
			(roundrect_rratio 0.25)
		)
		(pad "" smd roundrect
			(at 0.341 0.002)
			(size 0.318 0.36)
			(layers "B.Paste")
			(roundrect_rratio 0.25)
		)
		(pad "1" smd roundrect
			(at -0.321 0.002)
			(size 0.46 0.4)
			(layers "B.Cu" "B.Mask")
			(roundrect_rratio 0.25)
			(net 460 "1V8_SYS")
			(pintype "passive")
		)
		(pad "2" smd roundrect
			(at 0.32 0.002)
			(size 0.46 0.4)
			(layers "B.Cu" "B.Mask")
			(roundrect_rratio 0.25)
			(net 5 "GND")
			(pintype "passive")
		)
	)
	(footprint "antmicro-footprints:C_0201"
		(layer "B.Cu")
		(at 165.536328 96.372157 180)
		(descr "Capacitor SMD 0201")
		(tags "capacitor SMD 0201")
		(property "Reference" "C53"
			(at -1.063672 -1.127843 0)
			(layer "B.SilkS")
			(effects
				(font
					(size 0.7 0.7)
					(thickness 0.15)
				)
				(justify left bottom mirror)
			)
		)
		(property "Value" "C_100n_0201"
			(at 0 -1.4 0)
			(layer "B.Fab")
			(effects
				(font
					(size 0.7 0.7)
					(thickness 0.15)
				)
				(justify left bottom mirror)
			)
		)
		(property "Description" " "
			(at 0 0 180)
			(layer "F.Fab")
			(hide yes)
			(effects
				(font
					(size 1.27 1.27)
					(thickness 0.15)
				)
			)
		)
		(property "Author" "Antmicro"
			(at 331.072656 192.744314 0)
			(layer "B.Fab")
			(hide yes)
			(effects
				(font
					(size 1 1)
					(thickness 0.15)
				)
				(justify mirror)
			)
		)
		(property "Dielectric" ""
			(at 331.072656 192.744314 0)
			(layer "B.Fab")
			(hide yes)
			(effects
				(font
					(size 1 1)
					(thickness 0.15)
				)
				(justify mirror)
			)
		)
		(property "License" "Apache-2.0"
			(at 331.072656 192.744314 0)
			(layer "B.Fab")
			(hide yes)
			(effects
				(font
					(size 1 1)
					(thickness 0.15)
				)
				(justify mirror)
			)
		)
		(property "MPN" "CC0201KRX6S5BB104"
			(at 331.072656 192.744314 0)
			(layer "B.Fab")
			(hide yes)
			(effects
				(font
					(size 1 1)
					(thickness 0.15)
				)
				(justify mirror)
			)
		)
		(property "Manufacturer" "Yaego"
			(at 331.072656 192.744314 0)
			(layer "B.Fab")
			(hide yes)
			(effects
				(font
					(size 1 1)
					(thickness 0.15)
				)
				(justify mirror)
			)
		)
		(property "Val" "100n"
			(at 331.072656 192.744314 0)
			(layer "B.Fab")
			(hide yes)
			(effects
				(font
					(size 1 1)
					(thickness 0.15)
				)
				(justify mirror)
			)
		)
		(property "Voltage" ""
			(at 331.072656 192.744314 0)
			(layer "B.Fab")
			(hide yes)
			(effects
				(font
					(size 1 1)
					(thickness 0.15)
				)
				(justify mirror)
			)
		)
		(sheetname "FPGA power")
		(sheetfile "fpga-power.kicad_sch")
		(attr smd)
		(fp_rect
			(start -0.72 0.38)
			(end 0.72 -0.38)
			(stroke
				(width 0.05)
				(type solid)
			)
			(fill no)
			(layer "B.CrtYd")
		)
		(fp_rect
			(start 0.3 -0.15)
			(end -0.301 0.149)
			(stroke
				(width 0.15)
				(type solid)
			)
			(fill no)
			(layer "B.Fab")
		)
		(pad "" smd roundrect
			(at -0.349 0.002 180)
			(size 0.318 0.36)
			(layers "B.Paste")
			(roundrect_rratio 0.25)
		)
		(pad "" smd roundrect
			(at 0.341 0.002 180)
			(size 0.318 0.36)
			(layers "B.Paste")
			(roundrect_rratio 0.25)
		)
		(pad "1" smd roundrect
			(at -0.321 0.002 180)
			(size 0.46 0.4)
			(layers "B.Cu" "B.Mask")
			(roundrect_rratio 0.25)
			(net 460 "1V8_SYS")
			(pintype "passive")
		)
		(pad "2" smd roundrect
			(at 0.32 0.002 180)
			(size 0.46 0.4)
			(layers "B.Cu" "B.Mask")
			(roundrect_rratio 0.25)
			(net 5 "GND")
			(pintype "passive")
		)
	)
	(footprint "antmicro-footprints:C_0201"
		(layer "B.Cu")
		(at 164.336328 97.997157 -90)
		(descr "Capacitor SMD 0201")
		(tags "capacitor SMD 0201")
		(property "Reference" "C88"
			(at -0.797157 0.336328 90)
			(layer "B.SilkS")
			(effects
				(font
					(size 0.7 0.7)
					(thickness 0.15)
				)
				(justify left bottom mirror)
			)
		)
		(property "Value" "C_100n_0201"
			(at 0 -1.4 90)
			(layer "B.Fab")
			(effects
				(font
					(size 0.7 0.7)
					(thickness 0.15)
				)
				(justify left bottom mirror)
			)
		)
		(property "Description" " "
			(at 0 0 270)
			(layer "F.Fab")
			(hide yes)
			(effects
				(font
					(size 1.27 1.27)
					(thickness 0.15)
				)
			)
		)
		(property "Author" "Antmicro"
			(at 66.339171 262.333485 0)
			(layer "B.Fab")
			(hide yes)
			(effects
				(font
					(size 1 1)
					(thickness 0.15)
				)
				(justify mirror)
			)
		)
		(property "Dielectric" ""
			(at 66.339171 262.333485 0)
			(layer "B.Fab")
			(hide yes)
			(effects
				(font
					(size 1 1)
					(thickness 0.15)
				)
				(justify mirror)
			)
		)
		(property "License" "Apache-2.0"
			(at 66.339171 262.333485 0)
			(layer "B.Fab")
			(hide yes)
			(effects
				(font
					(size 1 1)
					(thickness 0.15)
				)
				(justify mirror)
			)
		)
		(property "MPN" "CC0201KRX6S5BB104"
			(at 66.339171 262.333485 0)
			(layer "B.Fab")
			(hide yes)
			(effects
				(font
					(size 1 1)
					(thickness 0.15)
				)
				(justify mirror)
			)
		)
		(property "Manufacturer" "Yaego"
			(at 66.339171 262.333485 0)
			(layer "B.Fab")
			(hide yes)
			(effects
				(font
					(size 1 1)
					(thickness 0.15)
				)
				(justify mirror)
			)
		)
		(property "Val" "100n"
			(at 66.339171 262.333485 0)
			(layer "B.Fab")
			(hide yes)
			(effects
				(font
					(size 1 1)
					(thickness 0.15)
				)
				(justify mirror)
			)
		)
		(property "Voltage" ""
			(at 66.339171 262.333485 0)
			(layer "B.Fab")
			(hide yes)
			(effects
				(font
					(size 1 1)
					(thickness 0.15)
				)
				(justify mirror)
			)
		)
		(sheetname "FPGA power")
		(sheetfile "fpga-power.kicad_sch")
		(attr smd)
		(fp_rect
			(start -0.72 0.38)
			(end 0.72 -0.38)
			(stroke
				(width 0.05)
				(type solid)
			)
			(fill no)
			(layer "B.CrtYd")
		)
		(fp_rect
			(start 0.3 -0.15)
			(end -0.301 0.149)
			(stroke
				(width 0.15)
				(type solid)
			)
			(fill no)
			(layer "B.Fab")
		)
		(pad "" smd roundrect
			(at -0.349 0.002 270)
			(size 0.318 0.36)
			(layers "B.Paste")
			(roundrect_rratio 0.25)
		)
		(pad "" smd roundrect
			(at 0.341 0.002 270)
			(size 0.318 0.36)
			(layers "B.Paste")
			(roundrect_rratio 0.25)
		)
		(pad "1" smd roundrect
			(at -0.321 0.002 270)
			(size 0.46 0.4)
			(layers "B.Cu" "B.Mask")
			(roundrect_rratio 0.25)
			(net 465 "1V0_SYS")
			(pintype "passive")
		)
		(pad "2" smd roundrect
			(at 0.32 0.002 270)
			(size 0.46 0.4)
			(layers "B.Cu" "B.Mask")
			(roundrect_rratio 0.25)
			(net 5 "GND")
			(pintype "passive")
		)
	)
	(footprint "antmicro-footprints:C_0201"
		(layer "B.Cu")
		(at 166.661328 94.497157 -90)
		(descr "Capacitor SMD 0201")
		(tags "capacitor SMD 0201")
		(property "Reference" "C57"
			(at -2.697157 0.011328 90)
			(layer "B.SilkS")
			(effects
				(font
					(size 0.7 0.7)
					(thickness 0.15)
				)
				(justify left bottom mirror)
			)
		)
		(property "Value" "C_100n_0201"
			(at 0 -1.4 90)
			(layer "B.Fab")
			(effects
				(font
					(size 0.7 0.7)
					(thickness 0.15)
				)
				(justify left bottom mirror)
			)
		)
		(property "Description" " "
			(at 0 0 270)
			(layer "F.Fab")
			(hide yes)
			(effects
				(font
					(size 1.27 1.27)
					(thickness 0.15)
				)
			)
		)
		(property "Author" "Antmicro"
			(at 72.164171 261.158485 0)
			(layer "B.Fab")
			(hide yes)
			(effects
				(font
					(size 1 1)
					(thickness 0.15)
				)
				(justify mirror)
			)
		)
		(property "Dielectric" ""
			(at 72.164171 261.158485 0)
			(layer "B.Fab")
			(hide yes)
			(effects
				(font
					(size 1 1)
					(thickness 0.15)
				)
				(justify mirror)
			)
		)
		(property "License" "Apache-2.0"
			(at 72.164171 261.158485 0)
			(layer "B.Fab")
			(hide yes)
			(effects
				(font
					(size 1 1)
					(thickness 0.15)
				)
				(justify mirror)
			)
		)
		(property "MPN" "CC0201KRX6S5BB104"
			(at 72.164171 261.158485 0)
			(layer "B.Fab")
			(hide yes)
			(effects
				(font
					(size 1 1)
					(thickness 0.15)
				)
				(justify mirror)
			)
		)
		(property "Manufacturer" "Yaego"
			(at 72.164171 261.158485 0)
			(layer "B.Fab")
			(hide yes)
			(effects
				(font
					(size 1 1)
					(thickness 0.15)
				)
				(justify mirror)
			)
		)
		(property "Val" "100n"
			(at 72.164171 261.158485 0)
			(layer "B.Fab")
			(hide yes)
			(effects
				(font
					(size 1 1)
					(thickness 0.15)
				)
				(justify mirror)
			)
		)
		(property "Voltage" ""
			(at 72.164171 261.158485 0)
			(layer "B.Fab")
			(hide yes)
			(effects
				(font
					(size 1 1)
					(thickness 0.15)
				)
				(justify mirror)
			)
		)
		(sheetname "FPGA power")
		(sheetfile "fpga-power.kicad_sch")
		(attr smd)
		(fp_rect
			(start -0.72 0.38)
			(end 0.72 -0.38)
			(stroke
				(width 0.05)
				(type solid)
			)
			(fill no)
			(layer "B.CrtYd")
		)
		(fp_rect
			(start 0.3 -0.15)
			(end -0.301 0.149)
			(stroke
				(width 0.15)
				(type solid)
			)
			(fill no)
			(layer "B.Fab")
		)
		(pad "" smd roundrect
			(at -0.349 0.002 270)
			(size 0.318 0.36)
			(layers "B.Paste")
			(roundrect_rratio 0.25)
		)
		(pad "" smd roundrect
			(at 0.341 0.002 270)
			(size 0.318 0.36)
			(layers "B.Paste")
			(roundrect_rratio 0.25)
		)
		(pad "1" smd roundrect
			(at -0.321 0.002 270)
			(size 0.46 0.4)
			(layers "B.Cu" "B.Mask")
			(roundrect_rratio 0.25)
			(net 460 "1V8_SYS")
			(pintype "passive")
		)
		(pad "2" smd roundrect
			(at 0.32 0.002 270)
			(size 0.46 0.4)
			(layers "B.Cu" "B.Mask")
			(roundrect_rratio 0.25)
			(net 5 "GND")
			(pintype "passive")
		)
	)
	(footprint "antmicro-footprints:C_0201"
		(layer "B.Cu")
		(at 167.736328 97.997157 90)
		(descr "Capacitor SMD 0201")
		(tags "capacitor SMD 0201")
		(property "Reference" "C90"
			(at 0.847157 -0.286328 270)
			(layer "B.SilkS")
			(effects
				(font
					(size 0.7 0.7)
					(thickness 0.15)
				)
				(justify left bottom mirror)
			)
		)
		(property "Value" "C_100n_0201"
			(at 0 -1.4 270)
			(layer "B.Fab")
			(effects
				(font
					(size 0.7 0.7)
					(thickness 0.15)
				)
				(justify left bottom mirror)
			)
		)
		(property "Description" " "
			(at 0 0 90)
			(layer "F.Fab")
			(hide yes)
			(effects
				(font
					(size 1.27 1.27)
					(thickness 0.15)
				)
			)
		)
		(property "Author" "Antmicro"
			(at 265.733485 -69.739171 0)
			(layer "B.Fab")
			(hide yes)
			(effects
				(font
					(size 1 1)
					(thickness 0.15)
				)
				(justify mirror)
			)
		)
		(property "Dielectric" ""
			(at 265.733485 -69.739171 0)
			(layer "B.Fab")
			(hide yes)
			(effects
				(font
					(size 1 1)
					(thickness 0.15)
				)
				(justify mirror)
			)
		)
		(property "License" "Apache-2.0"
			(at 265.733485 -69.739171 0)
			(layer "B.Fab")
			(hide yes)
			(effects
				(font
					(size 1 1)
					(thickness 0.15)
				)
				(justify mirror)
			)
		)
		(property "MPN" "CC0201KRX6S5BB104"
			(at 265.733485 -69.739171 0)
			(layer "B.Fab")
			(hide yes)
			(effects
				(font
					(size 1 1)
					(thickness 0.15)
				)
				(justify mirror)
			)
		)
		(property "Manufacturer" "Yaego"
			(at 265.733485 -69.739171 0)
			(layer "B.Fab")
			(hide yes)
			(effects
				(font
					(size 1 1)
					(thickness 0.15)
				)
				(justify mirror)
			)
		)
		(property "Val" "100n"
			(at 265.733485 -69.739171 0)
			(layer "B.Fab")
			(hide yes)
			(effects
				(font
					(size 1 1)
					(thickness 0.15)
				)
				(justify mirror)
			)
		)
		(property "Voltage" ""
			(at 265.733485 -69.739171 0)
			(layer "B.Fab")
			(hide yes)
			(effects
				(font
					(size 1 1)
					(thickness 0.15)
				)
				(justify mirror)
			)
		)
		(sheetname "FPGA power")
		(sheetfile "fpga-power.kicad_sch")
		(attr smd)
		(fp_rect
			(start -0.72 0.38)
			(end 0.72 -0.38)
			(stroke
				(width 0.05)
				(type solid)
			)
			(fill no)
			(layer "B.CrtYd")
		)
		(fp_rect
			(start 0.3 -0.15)
			(end -0.301 0.149)
			(stroke
				(width 0.15)
				(type solid)
			)
			(fill no)
			(layer "B.Fab")
		)
		(pad "" smd roundrect
			(at -0.349 0.002 90)
			(size 0.318 0.36)
			(layers "B.Paste")
			(roundrect_rratio 0.25)
		)
		(pad "" smd roundrect
			(at 0.341 0.002 90)
			(size 0.318 0.36)
			(layers "B.Paste")
			(roundrect_rratio 0.25)
		)
		(pad "1" smd roundrect
			(at -0.321 0.002 90)
			(size 0.46 0.4)
			(layers "B.Cu" "B.Mask")
			(roundrect_rratio 0.25)
			(net 465 "1V0_SYS")
			(pintype "passive")
		)
		(pad "2" smd roundrect
			(at 0.32 0.002 90)
			(size 0.46 0.4)
			(layers "B.Cu" "B.Mask")
			(roundrect_rratio 0.25)
			(net 5 "GND")
			(pintype "passive")
		)
	)
	(footprint "antmicro-footprints:C_0201"
		(layer "B.Cu")
		(at 165.036328 91.375 180)
		(descr "Capacitor SMD 0201")
		(tags "capacitor SMD 0201")
		(property "Reference" "C60"
			(at 0.536328 -0.325 0)
			(layer "B.SilkS")
			(effects
				(font
					(size 0.7 0.7)
					(thickness 0.15)
				)
				(justify left bottom mirror)
			)
		)
		(property "Value" "C_100n_0201"
			(at 0 -1.4 0)
			(layer "B.Fab")
			(effects
				(font
					(size 0.7 0.7)
					(thickness 0.15)
				)
				(justify left bottom mirror)
			)
		)
		(property "Description" " "
			(at 0 0 180)
			(layer "F.Fab")
			(hide yes)
			(effects
				(font
					(size 1.27 1.27)
					(thickness 0.15)
				)
			)
		)
		(property "Author" "Antmicro"
			(at 330.072656 182.75 0)
			(layer "B.Fab")
			(hide yes)
			(effects
				(font
					(size 1 1)
					(thickness 0.15)
				)
				(justify mirror)
			)
		)
		(property "Dielectric" ""
			(at 330.072656 182.75 0)
			(layer "B.Fab")
			(hide yes)
			(effects
				(font
					(size 1 1)
					(thickness 0.15)
				)
				(justify mirror)
			)
		)
		(property "License" "Apache-2.0"
			(at 330.072656 182.75 0)
			(layer "B.Fab")
			(hide yes)
			(effects
				(font
					(size 1 1)
					(thickness 0.15)
				)
				(justify mirror)
			)
		)
		(property "MPN" "CC0201KRX6S5BB104"
			(at 330.072656 182.75 0)
			(layer "B.Fab")
			(hide yes)
			(effects
				(font
					(size 1 1)
					(thickness 0.15)
				)
				(justify mirror)
			)
		)
		(property "Manufacturer" "Yaego"
			(at 330.072656 182.75 0)
			(layer "B.Fab")
			(hide yes)
			(effects
				(font
					(size 1 1)
					(thickness 0.15)
				)
				(justify mirror)
			)
		)
		(property "Val" "100n"
			(at 330.072656 182.75 0)
			(layer "B.Fab")
			(hide yes)
			(effects
				(font
					(size 1 1)
					(thickness 0.15)
				)
				(justify mirror)
			)
		)
		(property "Voltage" ""
			(at 330.072656 182.75 0)
			(layer "B.Fab")
			(hide yes)
			(effects
				(font
					(size 1 1)
					(thickness 0.15)
				)
				(justify mirror)
			)
		)
		(sheetname "FPGA power")
		(sheetfile "fpga-power.kicad_sch")
		(attr smd)
		(fp_rect
			(start -0.72 0.38)
			(end 0.72 -0.38)
			(stroke
				(width 0.05)
				(type solid)
			)
			(fill no)
			(layer "B.CrtYd")
		)
		(fp_rect
			(start 0.3 -0.15)
			(end -0.301 0.149)
			(stroke
				(width 0.15)
				(type solid)
			)
			(fill no)
			(layer "B.Fab")
		)
		(pad "" smd roundrect
			(at -0.349 0.002 180)
			(size 0.318 0.36)
			(layers "B.Paste")
			(roundrect_rratio 0.25)
		)
		(pad "" smd roundrect
			(at 0.341 0.002 180)
			(size 0.318 0.36)
			(layers "B.Paste")
			(roundrect_rratio 0.25)
		)
		(pad "1" smd roundrect
			(at -0.321 0.002 180)
			(size 0.46 0.4)
			(layers "B.Cu" "B.Mask")
			(roundrect_rratio 0.25)
			(net 460 "1V8_SYS")
			(pintype "passive")
		)
		(pad "2" smd roundrect
			(at 0.32 0.002 180)
			(size 0.46 0.4)
			(layers "B.Cu" "B.Mask")
			(roundrect_rratio 0.25)
			(net 5 "GND")
			(pintype "passive")
		)
	)
	(footprint "antmicro-footprints:C_0201"
		(layer "B.Cu")
		(at 169.411328 97.497157 90)
		(descr "Capacitor SMD 0201")
		(tags "capacitor SMD 0201")
		(property "Reference" "C92"
			(at 0.697157 -0.311328 270)
			(layer "B.SilkS")
			(effects
				(font
					(size 0.7 0.7)
					(thickness 0.15)
				)
				(justify left bottom mirror)
			)
		)
		(property "Value" "C_100n_0201"
			(at 0 -1.4 270)
			(layer "B.Fab")
			(effects
				(font
					(size 0.7 0.7)
					(thickness 0.15)
				)
				(justify left bottom mirror)
			)
		)
		(property "Description" " "
			(at 0 0 90)
			(layer "F.Fab")
			(hide yes)
			(effects
				(font
					(size 1.27 1.27)
					(thickness 0.15)
				)
			)
		)
		(property "Author" "Antmicro"
			(at 266.908485 -71.914171 0)
			(layer "B.Fab")
			(hide yes)
			(effects
				(font
					(size 1 1)
					(thickness 0.15)
				)
				(justify mirror)
			)
		)
		(property "Dielectric" ""
			(at 266.908485 -71.914171 0)
			(layer "B.Fab")
			(hide yes)
			(effects
				(font
					(size 1 1)
					(thickness 0.15)
				)
				(justify mirror)
			)
		)
		(property "License" "Apache-2.0"
			(at 266.908485 -71.914171 0)
			(layer "B.Fab")
			(hide yes)
			(effects
				(font
					(size 1 1)
					(thickness 0.15)
				)
				(justify mirror)
			)
		)
		(property "MPN" "CC0201KRX6S5BB104"
			(at 266.908485 -71.914171 0)
			(layer "B.Fab")
			(hide yes)
			(effects
				(font
					(size 1 1)
					(thickness 0.15)
				)
				(justify mirror)
			)
		)
		(property "Manufacturer" "Yaego"
			(at 266.908485 -71.914171 0)
			(layer "B.Fab")
			(hide yes)
			(effects
				(font
					(size 1 1)
					(thickness 0.15)
				)
				(justify mirror)
			)
		)
		(property "Val" "100n"
			(at 266.908485 -71.914171 0)
			(layer "B.Fab")
			(hide yes)
			(effects
				(font
					(size 1 1)
					(thickness 0.15)
				)
				(justify mirror)
			)
		)
		(property "Voltage" ""
			(at 266.908485 -71.914171 0)
			(layer "B.Fab")
			(hide yes)
			(effects
				(font
					(size 1 1)
					(thickness 0.15)
				)
				(justify mirror)
			)
		)
		(sheetname "FPGA power")
		(sheetfile "fpga-power.kicad_sch")
		(attr smd)
		(fp_rect
			(start -0.72 0.38)
			(end 0.72 -0.38)
			(stroke
				(width 0.05)
				(type solid)
			)
			(fill no)
			(layer "B.CrtYd")
		)
		(fp_rect
			(start 0.3 -0.15)
			(end -0.301 0.149)
			(stroke
				(width 0.15)
				(type solid)
			)
			(fill no)
			(layer "B.Fab")
		)
		(pad "" smd roundrect
			(at -0.349 0.002 90)
			(size 0.318 0.36)
			(layers "B.Paste")
			(roundrect_rratio 0.25)
		)
		(pad "" smd roundrect
			(at 0.341 0.002 90)
			(size 0.318 0.36)
			(layers "B.Paste")
			(roundrect_rratio 0.25)
		)
		(pad "1" smd roundrect
			(at -0.321 0.002 90)
			(size 0.46 0.4)
			(layers "B.Cu" "B.Mask")
			(roundrect_rratio 0.25)
			(net 465 "1V0_SYS")
			(pintype "passive")
		)
		(pad "2" smd roundrect
			(at 0.32 0.002 90)
			(size 0.46 0.4)
			(layers "B.Cu" "B.Mask")
			(roundrect_rratio 0.25)
			(net 5 "GND")
			(pintype "passive")
		)
	)
	(footprint "antmicro-footprints:C_0201"
		(layer "B.Cu")
		(at 167.411328 94.497157 -90)
		(descr "Capacitor SMD 0201")
		(tags "capacitor SMD 0201")
		(property "Reference" "C63"
			(at -2.697157 -0.188672 90)
			(layer "B.SilkS")
			(effects
				(font
					(size 0.7 0.7)
					(thickness 0.15)
				)
				(justify left bottom mirror)
			)
		)
		(property "Value" "C_100n_0201"
			(at 0 -1.4 90)
			(layer "B.Fab")
			(effects
				(font
					(size 0.7 0.7)
					(thickness 0.15)
				)
				(justify left bottom mirror)
			)
		)
		(property "Description" " "
			(at 0 0 270)
			(layer "F.Fab")
			(hide yes)
			(effects
				(font
					(size 1.27 1.27)
					(thickness 0.15)
				)
			)
		)
		(property "Author" "Antmicro"
			(at 72.914171 261.908485 0)
			(layer "B.Fab")
			(hide yes)
			(effects
				(font
					(size 1 1)
					(thickness 0.15)
				)
				(justify mirror)
			)
		)
		(property "Dielectric" ""
			(at 72.914171 261.908485 0)
			(layer "B.Fab")
			(hide yes)
			(effects
				(font
					(size 1 1)
					(thickness 0.15)
				)
				(justify mirror)
			)
		)
		(property "License" "Apache-2.0"
			(at 72.914171 261.908485 0)
			(layer "B.Fab")
			(hide yes)
			(effects
				(font
					(size 1 1)
					(thickness 0.15)
				)
				(justify mirror)
			)
		)
		(property "MPN" "CC0201KRX6S5BB104"
			(at 72.914171 261.908485 0)
			(layer "B.Fab")
			(hide yes)
			(effects
				(font
					(size 1 1)
					(thickness 0.15)
				)
				(justify mirror)
			)
		)
		(property "Manufacturer" "Yaego"
			(at 72.914171 261.908485 0)
			(layer "B.Fab")
			(hide yes)
			(effects
				(font
					(size 1 1)
					(thickness 0.15)
				)
				(justify mirror)
			)
		)
		(property "Val" "100n"
			(at 72.914171 261.908485 0)
			(layer "B.Fab")
			(hide yes)
			(effects
				(font
					(size 1 1)
					(thickness 0.15)
				)
				(justify mirror)
			)
		)
		(property "Voltage" ""
			(at 72.914171 261.908485 0)
			(layer "B.Fab")
			(hide yes)
			(effects
				(font
					(size 1 1)
					(thickness 0.15)
				)
				(justify mirror)
			)
		)
		(sheetname "FPGA power")
		(sheetfile "fpga-power.kicad_sch")
		(attr smd)
		(fp_rect
			(start -0.72 0.38)
			(end 0.72 -0.38)
			(stroke
				(width 0.05)
				(type solid)
			)
			(fill no)
			(layer "B.CrtYd")
		)
		(fp_rect
			(start 0.3 -0.15)
			(end -0.301 0.149)
			(stroke
				(width 0.15)
				(type solid)
			)
			(fill no)
			(layer "B.Fab")
		)
		(pad "" smd roundrect
			(at -0.349 0.002 270)
			(size 0.318 0.36)
			(layers "B.Paste")
			(roundrect_rratio 0.25)
		)
		(pad "" smd roundrect
			(at 0.341 0.002 270)
			(size 0.318 0.36)
			(layers "B.Paste")
			(roundrect_rratio 0.25)
		)
		(pad "1" smd roundrect
			(at -0.321 0.002 270)
			(size 0.46 0.4)
			(layers "B.Cu" "B.Mask")
			(roundrect_rratio 0.25)
			(net 460 "1V8_SYS")
			(pintype "passive")
		)
		(pad "2" smd roundrect
			(at 0.32 0.002 270)
			(size 0.46 0.4)
			(layers "B.Cu" "B.Mask")
			(roundrect_rratio 0.25)
			(net 5 "GND")
			(pintype "passive")
		)
	)
	(footprint "antmicro-footprints:C_0201"
		(layer "B.Cu")
		(at 169.536328 95.697157 180)
		(descr "Capacitor SMD 0201")
		(tags "capacitor SMD 0201")
		(property "Reference" "C67"
			(at 0.736328 2.797157 90)
			(layer "B.SilkS")
			(effects
				(font
					(size 0.7 0.7)
					(thickness 0.15)
				)
				(justify left bottom mirror)
			)
		)
		(property "Value" "C_100n_0201"
			(at 0 -1.4 0)
			(layer "B.Fab")
			(effects
				(font
					(size 0.7 0.7)
					(thickness 0.15)
				)
				(justify left bottom mirror)
			)
		)
		(property "Description" " "
			(at 0 0 180)
			(layer "F.Fab")
			(hide yes)
			(effects
				(font
					(size 1.27 1.27)
					(thickness 0.15)
				)
			)
		)
		(property "Author" "Antmicro"
			(at 339.072656 191.394314 0)
			(layer "B.Fab")
			(hide yes)
			(effects
				(font
					(size 1 1)
					(thickness 0.15)
				)
				(justify mirror)
			)
		)
		(property "Dielectric" ""
			(at 339.072656 191.394314 0)
			(layer "B.Fab")
			(hide yes)
			(effects
				(font
					(size 1 1)
					(thickness 0.15)
				)
				(justify mirror)
			)
		)
		(property "License" "Apache-2.0"
			(at 339.072656 191.394314 0)
			(layer "B.Fab")
			(hide yes)
			(effects
				(font
					(size 1 1)
					(thickness 0.15)
				)
				(justify mirror)
			)
		)
		(property "MPN" "CC0201KRX6S5BB104"
			(at 339.072656 191.394314 0)
			(layer "B.Fab")
			(hide yes)
			(effects
				(font
					(size 1 1)
					(thickness 0.15)
				)
				(justify mirror)
			)
		)
		(property "Manufacturer" "Yaego"
			(at 339.072656 191.394314 0)
			(layer "B.Fab")
			(hide yes)
			(effects
				(font
					(size 1 1)
					(thickness 0.15)
				)
				(justify mirror)
			)
		)
		(property "Val" "100n"
			(at 339.072656 191.394314 0)
			(layer "B.Fab")
			(hide yes)
			(effects
				(font
					(size 1 1)
					(thickness 0.15)
				)
				(justify mirror)
			)
		)
		(property "Voltage" ""
			(at 339.072656 191.394314 0)
			(layer "B.Fab")
			(hide yes)
			(effects
				(font
					(size 1 1)
					(thickness 0.15)
				)
				(justify mirror)
			)
		)
		(sheetname "FPGA power")
		(sheetfile "fpga-power.kicad_sch")
		(attr smd)
		(fp_rect
			(start -0.72 0.38)
			(end 0.72 -0.38)
			(stroke
				(width 0.05)
				(type solid)
			)
			(fill no)
			(layer "B.CrtYd")
		)
		(fp_rect
			(start 0.3 -0.15)
			(end -0.301 0.149)
			(stroke
				(width 0.15)
				(type solid)
			)
			(fill no)
			(layer "B.Fab")
		)
		(pad "" smd roundrect
			(at -0.349 0.002 180)
			(size 0.318 0.36)
			(layers "B.Paste")
			(roundrect_rratio 0.25)
		)
		(pad "" smd roundrect
			(at 0.341 0.002 180)
			(size 0.318 0.36)
			(layers "B.Paste")
			(roundrect_rratio 0.25)
		)
		(pad "1" smd roundrect
			(at -0.321 0.002 180)
			(size 0.46 0.4)
			(layers "B.Cu" "B.Mask")
			(roundrect_rratio 0.25)
			(net 460 "1V8_SYS")
			(pintype "passive")
		)
		(pad "2" smd roundrect
			(at 0.32 0.002 180)
			(size 0.46 0.4)
			(layers "B.Cu" "B.Mask")
			(roundrect_rratio 0.25)
			(net 5 "GND")
			(pintype "passive")
		)
	)
	(footprint "antmicro-footprints:C_0201"
		(layer "B.Cu")
		(at 172.636328 92.497157 90)
		(descr "Capacitor SMD 0201")
		(tags "capacitor SMD 0201")
		(property "Reference" "C25"
			(at 2.697157 -0.136328 270)
			(layer "B.SilkS")
			(effects
				(font
					(size 0.7 0.7)
					(thickness 0.15)
				)
				(justify left bottom mirror)
			)
		)
		(property "Value" "C_100n_0201"
			(at 0 -1.4 270)
			(layer "B.Fab")
			(effects
				(font
					(size 0.7 0.7)
					(thickness 0.15)
				)
				(justify left bottom mirror)
			)
		)
		(property "Description" " "
			(at 0 0 90)
			(layer "F.Fab")
			(hide yes)
			(effects
				(font
					(size 1.27 1.27)
					(thickness 0.15)
				)
			)
		)
		(property "Author" "Antmicro"
			(at 265.133485 -80.139171 0)
			(layer "B.Fab")
			(hide yes)
			(effects
				(font
					(size 1 1)
					(thickness 0.15)
				)
				(justify mirror)
			)
		)
		(property "Dielectric" ""
			(at 265.133485 -80.139171 0)
			(layer "B.Fab")
			(hide yes)
			(effects
				(font
					(size 1 1)
					(thickness 0.15)
				)
				(justify mirror)
			)
		)
		(property "License" "Apache-2.0"
			(at 265.133485 -80.139171 0)
			(layer "B.Fab")
			(hide yes)
			(effects
				(font
					(size 1 1)
					(thickness 0.15)
				)
				(justify mirror)
			)
		)
		(property "MPN" "CC0201KRX6S5BB104"
			(at 265.133485 -80.139171 0)
			(layer "B.Fab")
			(hide yes)
			(effects
				(font
					(size 1 1)
					(thickness 0.15)
				)
				(justify mirror)
			)
		)
		(property "Manufacturer" "Yaego"
			(at 265.133485 -80.139171 0)
			(layer "B.Fab")
			(hide yes)
			(effects
				(font
					(size 1 1)
					(thickness 0.15)
				)
				(justify mirror)
			)
		)
		(property "Val" "100n"
			(at 265.133485 -80.139171 0)
			(layer "B.Fab")
			(hide yes)
			(effects
				(font
					(size 1 1)
					(thickness 0.15)
				)
				(justify mirror)
			)
		)
		(property "Voltage" ""
			(at 265.133485 -80.139171 0)
			(layer "B.Fab")
			(hide yes)
			(effects
				(font
					(size 1 1)
					(thickness 0.15)
				)
				(justify mirror)
			)
		)
		(sheetname "FPGA power")
		(sheetfile "fpga-power.kicad_sch")
		(attr smd)
		(fp_rect
			(start -0.72 0.38)
			(end 0.72 -0.38)
			(stroke
				(width 0.05)
				(type solid)
			)
			(fill no)
			(layer "B.CrtYd")
		)
		(fp_rect
			(start 0.3 -0.15)
			(end -0.301 0.149)
			(stroke
				(width 0.15)
				(type solid)
			)
			(fill no)
			(layer "B.Fab")
		)
		(pad "" smd roundrect
			(at -0.349 0.002 90)
			(size 0.318 0.36)
			(layers "B.Paste")
			(roundrect_rratio 0.25)
		)
		(pad "" smd roundrect
			(at 0.341 0.002 90)
			(size 0.318 0.36)
			(layers "B.Paste")
			(roundrect_rratio 0.25)
		)
		(pad "1" smd roundrect
			(at -0.321 0.002 90)
			(size 0.46 0.4)
			(layers "B.Cu" "B.Mask")
			(roundrect_rratio 0.25)
			(net 465 "1V0_SYS")
			(pintype "passive")
		)
		(pad "2" smd roundrect
			(at 0.32 0.002 90)
			(size 0.46 0.4)
			(layers "B.Cu" "B.Mask")
			(roundrect_rratio 0.25)
			(net 5 "GND")
			(pintype "passive")
		)
	)
	(footprint "antmicro-footprints:C_0201"
		(layer "B.Cu")
		(at 172.736328 97.497157 90)
		(descr "Capacitor SMD 0201")
		(tags "capacitor SMD 0201")
		(property "Reference" "C33"
			(at 1.097157 1.063672 270)
			(layer "B.SilkS")
			(effects
				(font
					(size 0.7 0.7)
					(thickness 0.15)
				)
				(justify left bottom mirror)
			)
		)
		(property "Value" "C_100n_0201"
			(at 0 -1.4 270)
			(layer "B.Fab")
			(effects
				(font
					(size 0.7 0.7)
					(thickness 0.15)
				)
				(justify left bottom mirror)
			)
		)
		(property "Description" " "
			(at 0 0 90)
			(layer "F.Fab")
			(hide yes)
			(effects
				(font
					(size 1.27 1.27)
					(thickness 0.15)
				)
			)
		)
		(property "Author" "Antmicro"
			(at 270.233485 -75.239171 0)
			(layer "B.Fab")
			(hide yes)
			(effects
				(font
					(size 1 1)
					(thickness 0.15)
				)
				(justify mirror)
			)
		)
		(property "Dielectric" ""
			(at 270.233485 -75.239171 0)
			(layer "B.Fab")
			(hide yes)
			(effects
				(font
					(size 1 1)
					(thickness 0.15)
				)
				(justify mirror)
			)
		)
		(property "License" "Apache-2.0"
			(at 270.233485 -75.239171 0)
			(layer "B.Fab")
			(hide yes)
			(effects
				(font
					(size 1 1)
					(thickness 0.15)
				)
				(justify mirror)
			)
		)
		(property "MPN" "CC0201KRX6S5BB104"
			(at 270.233485 -75.239171 0)
			(layer "B.Fab")
			(hide yes)
			(effects
				(font
					(size 1 1)
					(thickness 0.15)
				)
				(justify mirror)
			)
		)
		(property "Manufacturer" "Yaego"
			(at 270.233485 -75.239171 0)
			(layer "B.Fab")
			(hide yes)
			(effects
				(font
					(size 1 1)
					(thickness 0.15)
				)
				(justify mirror)
			)
		)
		(property "Val" "100n"
			(at 270.233485 -75.239171 0)
			(layer "B.Fab")
			(hide yes)
			(effects
				(font
					(size 1 1)
					(thickness 0.15)
				)
				(justify mirror)
			)
		)
		(property "Voltage" ""
			(at 270.233485 -75.239171 0)
			(layer "B.Fab")
			(hide yes)
			(effects
				(font
					(size 1 1)
					(thickness 0.15)
				)
				(justify mirror)
			)
		)
		(sheetname "FPGA power")
		(sheetfile "fpga-power.kicad_sch")
		(attr smd)
		(fp_rect
			(start -0.72 0.38)
			(end 0.72 -0.38)
			(stroke
				(width 0.05)
				(type solid)
			)
			(fill no)
			(layer "B.CrtYd")
		)
		(fp_rect
			(start 0.3 -0.15)
			(end -0.301 0.149)
			(stroke
				(width 0.15)
				(type solid)
			)
			(fill no)
			(layer "B.Fab")
		)
		(pad "" smd roundrect
			(at -0.349 0.002 90)
			(size 0.318 0.36)
			(layers "B.Paste")
			(roundrect_rratio 0.25)
		)
		(pad "" smd roundrect
			(at 0.341 0.002 90)
			(size 0.318 0.36)
			(layers "B.Paste")
			(roundrect_rratio 0.25)
		)
		(pad "1" smd roundrect
			(at -0.321 0.002 90)
			(size 0.46 0.4)
			(layers "B.Cu" "B.Mask")
			(roundrect_rratio 0.25)
			(net 465 "1V0_SYS")
			(pintype "passive")
		)
		(pad "2" smd roundrect
			(at 0.32 0.002 90)
			(size 0.46 0.4)
			(layers "B.Cu" "B.Mask")
			(roundrect_rratio 0.25)
			(net 5 "GND")
			(pintype "passive")
		)
	)
	(footprint "antmicro-footprints:C_0201"
		(layer "B.Cu")
		(at 173.436328 91.747157 -90)
		(descr "Capacitor SMD 0201")
		(tags "capacitor SMD 0201")
		(property "Reference" "C41"
			(at -3.347157 -1.063672 90)
			(layer "B.SilkS")
			(effects
				(font
					(size 0.7 0.7)
					(thickness 0.15)
				)
				(justify left bottom mirror)
			)
		)
		(property "Value" "C_100n_0201"
			(at 0 -1.4 90)
			(layer "B.Fab")
			(effects
				(font
					(size 0.7 0.7)
					(thickness 0.15)
				)
				(justify left bottom mirror)
			)
		)
		(property "Description" " "
			(at 0 0 270)
			(layer "F.Fab")
			(hide yes)
			(effects
				(font
					(size 1.27 1.27)
					(thickness 0.15)
				)
			)
		)
		(property "Author" "Antmicro"
			(at 81.689171 265.183485 0)
			(layer "B.Fab")
			(hide yes)
			(effects
				(font
					(size 1 1)
					(thickness 0.15)
				)
				(justify mirror)
			)
		)
		(property "Dielectric" ""
			(at 81.689171 265.183485 0)
			(layer "B.Fab")
			(hide yes)
			(effects
				(font
					(size 1 1)
					(thickness 0.15)
				)
				(justify mirror)
			)
		)
		(property "License" "Apache-2.0"
			(at 81.689171 265.183485 0)
			(layer "B.Fab")
			(hide yes)
			(effects
				(font
					(size 1 1)
					(thickness 0.15)
				)
				(justify mirror)
			)
		)
		(property "MPN" "CC0201KRX6S5BB104"
			(at 81.689171 265.183485 0)
			(layer "B.Fab")
			(hide yes)
			(effects
				(font
					(size 1 1)
					(thickness 0.15)
				)
				(justify mirror)
			)
		)
		(property "Manufacturer" "Yaego"
			(at 81.689171 265.183485 0)
			(layer "B.Fab")
			(hide yes)
			(effects
				(font
					(size 1 1)
					(thickness 0.15)
				)
				(justify mirror)
			)
		)
		(property "Val" "100n"
			(at 81.689171 265.183485 0)
			(layer "B.Fab")
			(hide yes)
			(effects
				(font
					(size 1 1)
					(thickness 0.15)
				)
				(justify mirror)
			)
		)
		(property "Voltage" ""
			(at 81.689171 265.183485 0)
			(layer "B.Fab")
			(hide yes)
			(effects
				(font
					(size 1 1)
					(thickness 0.15)
				)
				(justify mirror)
			)
		)
		(sheetname "FPGA power")
		(sheetfile "fpga-power.kicad_sch")
		(attr smd)
		(fp_rect
			(start -0.72 0.38)
			(end 0.72 -0.38)
			(stroke
				(width 0.05)
				(type solid)
			)
			(fill no)
			(layer "B.CrtYd")
		)
		(fp_rect
			(start 0.3 -0.15)
			(end -0.301 0.149)
			(stroke
				(width 0.15)
				(type solid)
			)
			(fill no)
			(layer "B.Fab")
		)
		(pad "" smd roundrect
			(at -0.349 0.002 270)
			(size 0.318 0.36)
			(layers "B.Paste")
			(roundrect_rratio 0.25)
		)
		(pad "" smd roundrect
			(at 0.341 0.002 270)
			(size 0.318 0.36)
			(layers "B.Paste")
			(roundrect_rratio 0.25)
		)
		(pad "1" smd roundrect
			(at -0.321 0.002 270)
			(size 0.46 0.4)
			(layers "B.Cu" "B.Mask")
			(roundrect_rratio 0.25)
			(net 465 "1V0_SYS")
			(pintype "passive")
		)
		(pad "2" smd roundrect
			(at 0.32 0.002 270)
			(size 0.46 0.4)
			(layers "B.Cu" "B.Mask")
			(roundrect_rratio 0.25)
			(net 5 "GND")
			(pintype "passive")
		)
	)
	(footprint "antmicro-footprints:C_0201"
		(layer "B.Cu")
		(at 169.336328 94.017157 -90)
		(descr "Capacitor SMD 0201")
		(tags "capacitor SMD 0201")
		(property "Reference" "C48"
			(at -0.817157 -1.063672 90)
			(layer "B.SilkS")
			(effects
				(font
					(size 0.7 0.7)
					(thickness 0.15)
				)
				(justify left bottom mirror)
			)
		)
		(property "Value" "C_100n_0201"
			(at 0 -1.4 90)
			(layer "B.Fab")
			(effects
				(font
					(size 0.7 0.7)
					(thickness 0.15)
				)
				(justify left bottom mirror)
			)
		)
		(property "Description" " "
			(at 0 0 270)
			(layer "F.Fab")
			(hide yes)
			(effects
				(font
					(size 1.27 1.27)
					(thickness 0.15)
				)
			)
		)
		(property "Author" "Antmicro"
			(at 75.319171 263.353485 0)
			(layer "B.Fab")
			(hide yes)
			(effects
				(font
					(size 1 1)
					(thickness 0.15)
				)
				(justify mirror)
			)
		)
		(property "Dielectric" ""
			(at 75.319171 263.353485 0)
			(layer "B.Fab")
			(hide yes)
			(effects
				(font
					(size 1 1)
					(thickness 0.15)
				)
				(justify mirror)
			)
		)
		(property "License" "Apache-2.0"
			(at 75.319171 263.353485 0)
			(layer "B.Fab")
			(hide yes)
			(effects
				(font
					(size 1 1)
					(thickness 0.15)
				)
				(justify mirror)
			)
		)
		(property "MPN" "CC0201KRX6S5BB104"
			(at 75.319171 263.353485 0)
			(layer "B.Fab")
			(hide yes)
			(effects
				(font
					(size 1 1)
					(thickness 0.15)
				)
				(justify mirror)
			)
		)
		(property "Manufacturer" "Yaego"
			(at 75.319171 263.353485 0)
			(layer "B.Fab")
			(hide yes)
			(effects
				(font
					(size 1 1)
					(thickness 0.15)
				)
				(justify mirror)
			)
		)
		(property "Val" "100n"
			(at 75.319171 263.353485 0)
			(layer "B.Fab")
			(hide yes)
			(effects
				(font
					(size 1 1)
					(thickness 0.15)
				)
				(justify mirror)
			)
		)
		(property "Voltage" ""
			(at 75.319171 263.353485 0)
			(layer "B.Fab")
			(hide yes)
			(effects
				(font
					(size 1 1)
					(thickness 0.15)
				)
				(justify mirror)
			)
		)
		(sheetname "FPGA power")
		(sheetfile "fpga-power.kicad_sch")
		(attr smd)
		(fp_rect
			(start -0.72 0.38)
			(end 0.72 -0.38)
			(stroke
				(width 0.05)
				(type solid)
			)
			(fill no)
			(layer "B.CrtYd")
		)
		(fp_rect
			(start 0.3 -0.15)
			(end -0.301 0.149)
			(stroke
				(width 0.15)
				(type solid)
			)
			(fill no)
			(layer "B.Fab")
		)
		(pad "" smd roundrect
			(at -0.349 0.002 270)
			(size 0.318 0.36)
			(layers "B.Paste")
			(roundrect_rratio 0.25)
		)
		(pad "" smd roundrect
			(at 0.341 0.002 270)
			(size 0.318 0.36)
			(layers "B.Paste")
			(roundrect_rratio 0.25)
		)
		(pad "1" smd roundrect
			(at -0.321 0.002 270)
			(size 0.46 0.4)
			(layers "B.Cu" "B.Mask")
			(roundrect_rratio 0.25)
			(net 465 "1V0_SYS")
			(pintype "passive")
		)
		(pad "2" smd roundrect
			(at 0.32 0.002 270)
			(size 0.46 0.4)
			(layers "B.Cu" "B.Mask")
			(roundrect_rratio 0.25)
			(net 5 "GND")
			(pintype "passive")
		)
	)
	(footprint "antmicro-footprints:C_0201"
		(layer "B.Cu")
		(at 168.661328 99.497157 -90)
		(descr "Capacitor SMD 0201")
		(tags "capacitor SMD 0201")
		(property "Reference" "C59"
			(at 0.502843 -0.538672 90)
			(layer "B.SilkS")
			(effects
				(font
					(size 0.7 0.7)
					(thickness 0.15)
				)
				(justify left bottom mirror)
			)
		)
		(property "Value" "C_100n_0201"
			(at 0 -1.4 90)
			(layer "B.Fab")
			(effects
				(font
					(size 0.7 0.7)
					(thickness 0.15)
				)
				(justify left bottom mirror)
			)
		)
		(property "Description" " "
			(at 0 0 270)
			(layer "F.Fab")
			(hide yes)
			(effects
				(font
					(size 1.27 1.27)
					(thickness 0.15)
				)
			)
		)
		(property "Author" "Antmicro"
			(at 69.164171 268.158485 0)
			(layer "B.Fab")
			(hide yes)
			(effects
				(font
					(size 1 1)
					(thickness 0.15)
				)
				(justify mirror)
			)
		)
		(property "Dielectric" ""
			(at 69.164171 268.158485 0)
			(layer "B.Fab")
			(hide yes)
			(effects
				(font
					(size 1 1)
					(thickness 0.15)
				)
				(justify mirror)
			)
		)
		(property "License" "Apache-2.0"
			(at 69.164171 268.158485 0)
			(layer "B.Fab")
			(hide yes)
			(effects
				(font
					(size 1 1)
					(thickness 0.15)
				)
				(justify mirror)
			)
		)
		(property "MPN" "CC0201KRX6S5BB104"
			(at 69.164171 268.158485 0)
			(layer "B.Fab")
			(hide yes)
			(effects
				(font
					(size 1 1)
					(thickness 0.15)
				)
				(justify mirror)
			)
		)
		(property "Manufacturer" "Yaego"
			(at 69.164171 268.158485 0)
			(layer "B.Fab")
			(hide yes)
			(effects
				(font
					(size 1 1)
					(thickness 0.15)
				)
				(justify mirror)
			)
		)
		(property "Val" "100n"
			(at 69.164171 268.158485 0)
			(layer "B.Fab")
			(hide yes)
			(effects
				(font
					(size 1 1)
					(thickness 0.15)
				)
				(justify mirror)
			)
		)
		(property "Voltage" ""
			(at 69.164171 268.158485 0)
			(layer "B.Fab")
			(hide yes)
			(effects
				(font
					(size 1 1)
					(thickness 0.15)
				)
				(justify mirror)
			)
		)
		(sheetname "FPGA power")
		(sheetfile "fpga-power.kicad_sch")
		(attr smd)
		(fp_rect
			(start -0.72 0.38)
			(end 0.72 -0.38)
			(stroke
				(width 0.05)
				(type solid)
			)
			(fill no)
			(layer "B.CrtYd")
		)
		(fp_rect
			(start 0.3 -0.15)
			(end -0.301 0.149)
			(stroke
				(width 0.15)
				(type solid)
			)
			(fill no)
			(layer "B.Fab")
		)
		(pad "" smd roundrect
			(at -0.349 0.002 270)
			(size 0.318 0.36)
			(layers "B.Paste")
			(roundrect_rratio 0.25)
		)
		(pad "" smd roundrect
			(at 0.341 0.002 270)
			(size 0.318 0.36)
			(layers "B.Paste")
			(roundrect_rratio 0.25)
		)
		(pad "1" smd roundrect
			(at -0.321 0.002 270)
			(size 0.46 0.4)
			(layers "B.Cu" "B.Mask")
			(roundrect_rratio 0.25)
			(net 465 "1V0_SYS")
			(pintype "passive")
		)
		(pad "2" smd roundrect
			(at 0.32 0.002 270)
			(size 0.46 0.4)
			(layers "B.Cu" "B.Mask")
			(roundrect_rratio 0.25)
			(net 5 "GND")
			(pintype "passive")
		)
	)
	(footprint "antmicro-footprints:C_0201"
		(layer "B.Cu")
		(at 165.536328 100.622157)
		(descr "Capacitor SMD 0201")
		(tags "capacitor SMD 0201")
		(property "Reference" "C74"
			(at 0.763672 -0.272157 180)
			(layer "B.SilkS")
			(effects
				(font
					(size 0.7 0.7)
					(thickness 0.15)
				)
				(justify left bottom mirror)
			)
		)
		(property "Value" "C_100n_0201"
			(at 0 -1.4 180)
			(layer "B.Fab")
			(effects
				(font
					(size 0.7 0.7)
					(thickness 0.15)
				)
				(justify left bottom mirror)
			)
		)
		(property "Description" " "
			(at 0 0 0)
			(layer "F.Fab")
			(hide yes)
			(effects
				(font
					(size 1.27 1.27)
					(thickness 0.15)
				)
			)
		)
		(property "Author" "Antmicro"
			(at 0 0 0)
			(layer "B.Fab")
			(hide yes)
			(effects
				(font
					(size 1 1)
					(thickness 0.15)
				)
				(justify mirror)
			)
		)
		(property "Dielectric" ""
			(at 0 0 0)
			(layer "B.Fab")
			(hide yes)
			(effects
				(font
					(size 1 1)
					(thickness 0.15)
				)
				(justify mirror)
			)
		)
		(property "License" "Apache-2.0"
			(at 0 0 0)
			(layer "B.Fab")
			(hide yes)
			(effects
				(font
					(size 1 1)
					(thickness 0.15)
				)
				(justify mirror)
			)
		)
		(property "MPN" "CC0201KRX6S5BB104"
			(at 0 0 0)
			(layer "B.Fab")
			(hide yes)
			(effects
				(font
					(size 1 1)
					(thickness 0.15)
				)
				(justify mirror)
			)
		)
		(property "Manufacturer" "Yaego"
			(at 0 0 0)
			(layer "B.Fab")
			(hide yes)
			(effects
				(font
					(size 1 1)
					(thickness 0.15)
				)
				(justify mirror)
			)
		)
		(property "Val" "100n"
			(at 0 0 0)
			(layer "B.Fab")
			(hide yes)
			(effects
				(font
					(size 1 1)
					(thickness 0.15)
				)
				(justify mirror)
			)
		)
		(property "Voltage" ""
			(at 0 0 0)
			(layer "B.Fab")
			(hide yes)
			(effects
				(font
					(size 1 1)
					(thickness 0.15)
				)
				(justify mirror)
			)
		)
		(sheetname "FPGA power")
		(sheetfile "fpga-power.kicad_sch")
		(attr smd)
		(fp_rect
			(start -0.72 0.38)
			(end 0.72 -0.38)
			(stroke
				(width 0.05)
				(type solid)
			)
			(fill no)
			(layer "B.CrtYd")
		)
		(fp_rect
			(start 0.3 -0.15)
			(end -0.301 0.149)
			(stroke
				(width 0.15)
				(type solid)
			)
			(fill no)
			(layer "B.Fab")
		)
		(pad "" smd roundrect
			(at -0.349 0.002)
			(size 0.318 0.36)
			(layers "B.Paste")
			(roundrect_rratio 0.25)
		)
		(pad "" smd roundrect
			(at 0.341 0.002)
			(size 0.318 0.36)
			(layers "B.Paste")
			(roundrect_rratio 0.25)
		)
		(pad "1" smd roundrect
			(at -0.321 0.002)
			(size 0.46 0.4)
			(layers "B.Cu" "B.Mask")
			(roundrect_rratio 0.25)
			(net 465 "1V0_SYS")
			(pintype "passive")
		)
		(pad "2" smd roundrect
			(at 0.32 0.002)
			(size 0.46 0.4)
			(layers "B.Cu" "B.Mask")
			(roundrect_rratio 0.25)
			(net 5 "GND")
			(pintype "passive")
		)
	)
	(footprint "antmicro-footprints:C_0201"
		(layer "B.Cu")
		(at 171.036328 98.297157)
		(descr "Capacitor SMD 0201")
		(tags "capacitor SMD 0201")
		(property "Reference" "C44"
			(at 1.163672 -0.297157 180)
			(layer "B.SilkS")
			(effects
				(font
					(size 0.7 0.7)
					(thickness 0.15)
				)
				(justify left bottom mirror)
			)
		)
		(property "Value" "C_100n_0201"
			(at 0 -1.4 180)
			(layer "B.Fab")
			(effects
				(font
					(size 0.7 0.7)
					(thickness 0.15)
				)
				(justify left bottom mirror)
			)
		)
		(property "Description" " "
			(at 0 0 0)
			(layer "F.Fab")
			(hide yes)
			(effects
				(font
					(size 1.27 1.27)
					(thickness 0.15)
				)
			)
		)
		(property "Author" "Antmicro"
			(at 0 0 0)
			(layer "B.Fab")
			(hide yes)
			(effects
				(font
					(size 1 1)
					(thickness 0.15)
				)
				(justify mirror)
			)
		)
		(property "Dielectric" ""
			(at 0 0 0)
			(layer "B.Fab")
			(hide yes)
			(effects
				(font
					(size 1 1)
					(thickness 0.15)
				)
				(justify mirror)
			)
		)
		(property "License" "Apache-2.0"
			(at 0 0 0)
			(layer "B.Fab")
			(hide yes)
			(effects
				(font
					(size 1 1)
					(thickness 0.15)
				)
				(justify mirror)
			)
		)
		(property "MPN" "CC0201KRX6S5BB104"
			(at 0 0 0)
			(layer "B.Fab")
			(hide yes)
			(effects
				(font
					(size 1 1)
					(thickness 0.15)
				)
				(justify mirror)
			)
		)
		(property "Manufacturer" "Yaego"
			(at 0 0 0)
			(layer "B.Fab")
			(hide yes)
			(effects
				(font
					(size 1 1)
					(thickness 0.15)
				)
				(justify mirror)
			)
		)
		(property "Val" "100n"
			(at 0 0 0)
			(layer "B.Fab")
			(hide yes)
			(effects
				(font
					(size 1 1)
					(thickness 0.15)
				)
				(justify mirror)
			)
		)
		(property "Voltage" ""
			(at 0 0 0)
			(layer "B.Fab")
			(hide yes)
			(effects
				(font
					(size 1 1)
					(thickness 0.15)
				)
				(justify mirror)
			)
		)
		(sheetname "FPGA power")
		(sheetfile "fpga-power.kicad_sch")
		(attr smd)
		(fp_rect
			(start -0.72 0.38)
			(end 0.72 -0.38)
			(stroke
				(width 0.05)
				(type solid)
			)
			(fill no)
			(layer "B.CrtYd")
		)
		(fp_rect
			(start 0.3 -0.15)
			(end -0.301 0.149)
			(stroke
				(width 0.15)
				(type solid)
			)
			(fill no)
			(layer "B.Fab")
		)
		(pad "" smd roundrect
			(at -0.349 0.002)
			(size 0.318 0.36)
			(layers "B.Paste")
			(roundrect_rratio 0.25)
		)
		(pad "" smd roundrect
			(at 0.341 0.002)
			(size 0.318 0.36)
			(layers "B.Paste")
			(roundrect_rratio 0.25)
		)
		(pad "1" smd roundrect
			(at -0.321 0.002)
			(size 0.46 0.4)
			(layers "B.Cu" "B.Mask")
			(roundrect_rratio 0.25)
			(net 465 "1V0_SYS")
			(pintype "passive")
		)
		(pad "2" smd roundrect
			(at 0.32 0.002)
			(size 0.46 0.4)
			(layers "B.Cu" "B.Mask")
			(roundrect_rratio 0.25)
			(net 5 "GND")
			(pintype "passive")
		)
	)
	(footprint "antmicro-footprints:C_0201"
		(layer "B.Cu")
		(at 169.411328 99.497157 90)
		(descr "Capacitor SMD 0201")
		(tags "capacitor SMD 0201")
		(property "Reference" "C52"
			(at 1.097157 1.088672 270)
			(layer "B.SilkS")
			(effects
				(font
					(size 0.7 0.7)
					(thickness 0.15)
				)
				(justify left bottom mirror)
			)
		)
		(property "Value" "C_100n_0201"
			(at 0 -1.4 270)
			(layer "B.Fab")
			(effects
				(font
					(size 0.7 0.7)
					(thickness 0.15)
				)
				(justify left bottom mirror)
			)
		)
		(property "Description" " "
			(at 0 0 90)
			(layer "F.Fab")
			(hide yes)
			(effects
				(font
					(size 1.27 1.27)
					(thickness 0.15)
				)
			)
		)
		(property "Author" "Antmicro"
			(at 268.908485 -69.914171 0)
			(layer "B.Fab")
			(hide yes)
			(effects
				(font
					(size 1 1)
					(thickness 0.15)
				)
				(justify mirror)
			)
		)
		(property "Dielectric" ""
			(at 268.908485 -69.914171 0)
			(layer "B.Fab")
			(hide yes)
			(effects
				(font
					(size 1 1)
					(thickness 0.15)
				)
				(justify mirror)
			)
		)
		(property "License" "Apache-2.0"
			(at 268.908485 -69.914171 0)
			(layer "B.Fab")
			(hide yes)
			(effects
				(font
					(size 1 1)
					(thickness 0.15)
				)
				(justify mirror)
			)
		)
		(property "MPN" "CC0201KRX6S5BB104"
			(at 268.908485 -69.914171 0)
			(layer "B.Fab")
			(hide yes)
			(effects
				(font
					(size 1 1)
					(thickness 0.15)
				)
				(justify mirror)
			)
		)
		(property "Manufacturer" "Yaego"
			(at 268.908485 -69.914171 0)
			(layer "B.Fab")
			(hide yes)
			(effects
				(font
					(size 1 1)
					(thickness 0.15)
				)
				(justify mirror)
			)
		)
		(property "Val" "100n"
			(at 268.908485 -69.914171 0)
			(layer "B.Fab")
			(hide yes)
			(effects
				(font
					(size 1 1)
					(thickness 0.15)
				)
				(justify mirror)
			)
		)
		(property "Voltage" ""
			(at 268.908485 -69.914171 0)
			(layer "B.Fab")
			(hide yes)
			(effects
				(font
					(size 1 1)
					(thickness 0.15)
				)
				(justify mirror)
			)
		)
		(sheetname "FPGA power")
		(sheetfile "fpga-power.kicad_sch")
		(attr smd)
		(fp_rect
			(start -0.72 0.38)
			(end 0.72 -0.38)
			(stroke
				(width 0.05)
				(type solid)
			)
			(fill no)
			(layer "B.CrtYd")
		)
		(fp_rect
			(start 0.3 -0.15)
			(end -0.301 0.149)
			(stroke
				(width 0.15)
				(type solid)
			)
			(fill no)
			(layer "B.Fab")
		)
		(pad "" smd roundrect
			(at -0.349 0.002 90)
			(size 0.318 0.36)
			(layers "B.Paste")
			(roundrect_rratio 0.25)
		)
		(pad "" smd roundrect
			(at 0.341 0.002 90)
			(size 0.318 0.36)
			(layers "B.Paste")
			(roundrect_rratio 0.25)
		)
		(pad "1" smd roundrect
			(at -0.321 0.002 90)
			(size 0.46 0.4)
			(layers "B.Cu" "B.Mask")
			(roundrect_rratio 0.25)
			(net 465 "1V0_SYS")
			(pintype "passive")
		)
		(pad "2" smd roundrect
			(at 0.32 0.002 90)
			(size 0.46 0.4)
			(layers "B.Cu" "B.Mask")
			(roundrect_rratio 0.25)
			(net 5 "GND")
			(pintype "passive")
		)
	)
	(footprint "antmicro-footprints:C_0402_1005Metric"
		(layer "B.Cu")
		(at 167.5 95.875)
		(descr "Capacitor SMD 0402")
		(tags "capacitor SMD 0402")
		(property "Reference" "C26"
			(at 1.1 1.225 180)
			(layer "B.SilkS")
			(effects
				(font
					(size 0.7 0.7)
					(thickness 0.15)
				)
				(justify left bottom mirror)
			)
		)
		(property "Value" "C_4u7_0402"
			(at 0 -1.4 180)
			(layer "B.Fab")
			(effects
				(font
					(size 0.7 0.7)
					(thickness 0.15)
				)
				(justify left bottom mirror)
			)
		)
		(property "Description" " "
			(at 0 0 0)
			(layer "F.Fab")
			(hide yes)
			(effects
				(font
					(size 1.27 1.27)
					(thickness 0.15)
				)
			)
		)
		(property "Author" "Antmicro"
			(at 0 0 0)
			(layer "B.Fab")
			(hide yes)
			(effects
				(font
					(size 1 1)
					(thickness 0.15)
				)
				(justify mirror)
			)
		)
		(property "Dielectric" ""
			(at 0 0 0)
			(layer "B.Fab")
			(hide yes)
			(effects
				(font
					(size 1 1)
					(thickness 0.15)
				)
				(justify mirror)
			)
		)
		(property "License" "Apache-2.0"
			(at 0 0 0)
			(layer "B.Fab")
			(hide yes)
			(effects
				(font
					(size 1 1)
					(thickness 0.15)
				)
				(justify mirror)
			)
		)
		(property "MPN" "GRM155R61A475MEAAD"
			(at 0 0 0)
			(layer "B.Fab")
			(hide yes)
			(effects
				(font
					(size 1 1)
					(thickness 0.15)
				)
				(justify mirror)
			)
		)
		(property "Manufacturer" "Murata"
			(at 0 0 0)
			(layer "B.Fab")
			(hide yes)
			(effects
				(font
					(size 1 1)
					(thickness 0.15)
				)
				(justify mirror)
			)
		)
		(property "Val" "4u7"
			(at 0 0 0)
			(layer "B.Fab")
			(hide yes)
			(effects
				(font
					(size 1 1)
					(thickness 0.15)
				)
				(justify mirror)
			)
		)
		(property "Voltage" ""
			(at 0 0 0)
			(layer "B.Fab")
			(hide yes)
			(effects
				(font
					(size 1 1)
					(thickness 0.15)
				)
				(justify mirror)
			)
		)
		(sheetname "FPGA power")
		(sheetfile "fpga-power.kicad_sch")
		(attr smd)
		(fp_rect
			(start -0.94 0.47)
			(end 0.94 -0.47)
			(stroke
				(width 0.05)
				(type solid)
			)
			(fill no)
			(layer "B.CrtYd")
		)
		(fp_rect
			(start -0.499 0.249)
			(end 0.499 -0.249)
			(stroke
				(width 0.15)
				(type solid)
			)
			(fill no)
			(layer "B.Fab")
		)
		(pad "1" smd roundrect
			(at -0.484 0)
			(size 0.59 0.64)
			(layers "B.Cu" "B.Mask" "B.Paste")
			(roundrect_rratio 0.25)
			(net 460 "1V8_SYS")
			(pintype "passive")
		)
		(pad "2" smd roundrect
			(at 0.484 0)
			(size 0.59 0.64)
			(layers "B.Cu" "B.Mask" "B.Paste")
			(roundrect_rratio 0.25)
			(net 5 "GND")
			(pintype "passive")
		)
	)
	(footprint "antmicro-footprints:C_0402_1005Metric"
		(layer "B.Cu")
		(at 171.25 94.125)
		(descr "Capacitor SMD 0402")
		(tags "capacitor SMD 0402")
		(property "Reference" "C30"
			(at 2.95 0.175 180)
			(layer "B.SilkS")
			(effects
				(font
					(size 0.7 0.7)
					(thickness 0.15)
				)
				(justify left bottom mirror)
			)
		)
		(property "Value" "C_4u7_0402"
			(at 0 -1.4 180)
			(layer "B.Fab")
			(effects
				(font
					(size 0.7 0.7)
					(thickness 0.15)
				)
				(justify left bottom mirror)
			)
		)
		(property "Description" " "
			(at 0 0 0)
			(layer "F.Fab")
			(hide yes)
			(effects
				(font
					(size 1.27 1.27)
					(thickness 0.15)
				)
			)
		)
		(property "Author" "Antmicro"
			(at 0 0 0)
			(layer "B.Fab")
			(hide yes)
			(effects
				(font
					(size 1 1)
					(thickness 0.15)
				)
				(justify mirror)
			)
		)
		(property "Dielectric" ""
			(at 0 0 0)
			(layer "B.Fab")
			(hide yes)
			(effects
				(font
					(size 1 1)
					(thickness 0.15)
				)
				(justify mirror)
			)
		)
		(property "License" "Apache-2.0"
			(at 0 0 0)
			(layer "B.Fab")
			(hide yes)
			(effects
				(font
					(size 1 1)
					(thickness 0.15)
				)
				(justify mirror)
			)
		)
		(property "MPN" "GRM155R61A475MEAAD"
			(at 0 0 0)
			(layer "B.Fab")
			(hide yes)
			(effects
				(font
					(size 1 1)
					(thickness 0.15)
				)
				(justify mirror)
			)
		)
		(property "Manufacturer" "Murata"
			(at 0 0 0)
			(layer "B.Fab")
			(hide yes)
			(effects
				(font
					(size 1 1)
					(thickness 0.15)
				)
				(justify mirror)
			)
		)
		(property "Val" "4u7"
			(at 0 0 0)
			(layer "B.Fab")
			(hide yes)
			(effects
				(font
					(size 1 1)
					(thickness 0.15)
				)
				(justify mirror)
			)
		)
		(property "Voltage" ""
			(at 0 0 0)
			(layer "B.Fab")
			(hide yes)
			(effects
				(font
					(size 1 1)
					(thickness 0.15)
				)
				(justify mirror)
			)
		)
		(sheetname "FPGA power")
		(sheetfile "fpga-power.kicad_sch")
		(attr smd)
		(fp_rect
			(start -0.94 0.47)
			(end 0.94 -0.47)
			(stroke
				(width 0.05)
				(type solid)
			)
			(fill no)
			(layer "B.CrtYd")
		)
		(fp_rect
			(start -0.499 0.249)
			(end 0.499 -0.249)
			(stroke
				(width 0.15)
				(type solid)
			)
			(fill no)
			(layer "B.Fab")
		)
		(pad "1" smd roundrect
			(at -0.484 0)
			(size 0.59 0.64)
			(layers "B.Cu" "B.Mask" "B.Paste")
			(roundrect_rratio 0.25)
			(net 460 "1V8_SYS")
			(pintype "passive")
		)
		(pad "2" smd roundrect
			(at 0.484 0)
			(size 0.59 0.64)
			(layers "B.Cu" "B.Mask" "B.Paste")
			(roundrect_rratio 0.25)
			(net 5 "GND")
			(pintype "passive")
		)
	)
	(footprint "antmicro-footprints:C_0402_1005Metric"
		(layer "B.Cu")
		(at 164.625 94 180)
		(descr "Capacitor SMD 0402")
		(tags "capacitor SMD 0402")
		(property "Reference" "C34"
			(at 0.725 -0.9 0)
			(layer "B.SilkS")
			(effects
				(font
					(size 0.7 0.7)
					(thickness 0.15)
				)
				(justify left bottom mirror)
			)
		)
		(property "Value" "C_4u7_0402"
			(at 0 -1.4 0)
			(layer "B.Fab")
			(effects
				(font
					(size 0.7 0.7)
					(thickness 0.15)
				)
				(justify left bottom mirror)
			)
		)
		(property "Description" " "
			(at 0 0 180)
			(layer "F.Fab")
			(hide yes)
			(effects
				(font
					(size 1.27 1.27)
					(thickness 0.15)
				)
			)
		)
		(property "Author" "Antmicro"
			(at 329.25 188 0)
			(layer "B.Fab")
			(hide yes)
			(effects
				(font
					(size 1 1)
					(thickness 0.15)
				)
				(justify mirror)
			)
		)
		(property "Dielectric" ""
			(at 329.25 188 0)
			(layer "B.Fab")
			(hide yes)
			(effects
				(font
					(size 1 1)
					(thickness 0.15)
				)
				(justify mirror)
			)
		)
		(property "License" "Apache-2.0"
			(at 329.25 188 0)
			(layer "B.Fab")
			(hide yes)
			(effects
				(font
					(size 1 1)
					(thickness 0.15)
				)
				(justify mirror)
			)
		)
		(property "MPN" "GRM155R61A475MEAAD"
			(at 329.25 188 0)
			(layer "B.Fab")
			(hide yes)
			(effects
				(font
					(size 1 1)
					(thickness 0.15)
				)
				(justify mirror)
			)
		)
		(property "Manufacturer" "Murata"
			(at 329.25 188 0)
			(layer "B.Fab")
			(hide yes)
			(effects
				(font
					(size 1 1)
					(thickness 0.15)
				)
				(justify mirror)
			)
		)
		(property "Val" "4u7"
			(at 329.25 188 0)
			(layer "B.Fab")
			(hide yes)
			(effects
				(font
					(size 1 1)
					(thickness 0.15)
				)
				(justify mirror)
			)
		)
		(property "Voltage" ""
			(at 329.25 188 0)
			(layer "B.Fab")
			(hide yes)
			(effects
				(font
					(size 1 1)
					(thickness 0.15)
				)
				(justify mirror)
			)
		)
		(sheetname "FPGA power")
		(sheetfile "fpga-power.kicad_sch")
		(attr smd)
		(fp_rect
			(start -0.94 0.47)
			(end 0.94 -0.47)
			(stroke
				(width 0.05)
				(type solid)
			)
			(fill no)
			(layer "B.CrtYd")
		)
		(fp_rect
			(start -0.499 0.249)
			(end 0.499 -0.249)
			(stroke
				(width 0.15)
				(type solid)
			)
			(fill no)
			(layer "B.Fab")
		)
		(pad "1" smd roundrect
			(at -0.484 0 180)
			(size 0.59 0.64)
			(layers "B.Cu" "B.Mask" "B.Paste")
			(roundrect_rratio 0.25)
			(net 460 "1V8_SYS")
			(pintype "passive")
		)
		(pad "2" smd roundrect
			(at 0.484 0 180)
			(size 0.59 0.64)
			(layers "B.Cu" "B.Mask" "B.Paste")
			(roundrect_rratio 0.25)
			(net 5 "GND")
			(pintype "passive")
		)
	)
	(footprint "antmicro-footprints:C_0603_1608Metric"
		(layer "B.Cu")
		(at 163.375 95.375 180)
		(descr "Capacitor SMD 0603")
		(tags "capacitor 0603")
		(property "Reference" "C38"
			(at -1.125 -1.325 0)
			(layer "B.SilkS")
			(effects
				(font
					(size 0.7 0.7)
					(thickness 0.15)
				)
				(justify left bottom mirror)
			)
		)
		(property "Value" "C_47u_0603"
			(at 0 -1.6 0)
			(layer "B.Fab")
			(effects
				(font
					(size 0.7 0.7)
					(thickness 0.15)
				)
				(justify left bottom mirror)
			)
		)
		(property "Description" " "
			(at 0 0 180)
			(layer "F.Fab")
			(hide yes)
			(effects
				(font
					(size 1.27 1.27)
					(thickness 0.15)
				)
			)
		)
		(property "Author" "Antmicro"
			(at 326.75 190.75 0)
			(layer "B.Fab")
			(hide yes)
			(effects
				(font
					(size 1 1)
					(thickness 0.15)
				)
				(justify mirror)
			)
		)
		(property "Dielectric" ""
			(at 326.75 190.75 0)
			(layer "B.Fab")
			(hide yes)
			(effects
				(font
					(size 1 1)
					(thickness 0.15)
				)
				(justify mirror)
			)
		)
		(property "License" "Apache-2.0"
			(at 326.75 190.75 0)
			(layer "B.Fab")
			(hide yes)
			(effects
				(font
					(size 1 1)
					(thickness 0.15)
				)
				(justify mirror)
			)
		)
		(property "MPN" "GRM188R60J476ME15D"
			(at 326.75 190.75 0)
			(layer "B.Fab")
			(hide yes)
			(effects
				(font
					(size 1 1)
					(thickness 0.15)
				)
				(justify mirror)
			)
		)
		(property "Manufacturer" "Murata"
			(at 326.75 190.75 0)
			(layer "B.Fab")
			(hide yes)
			(effects
				(font
					(size 1 1)
					(thickness 0.15)
				)
				(justify mirror)
			)
		)
		(property "Val" "47u"
			(at 326.75 190.75 0)
			(layer "B.Fab")
			(hide yes)
			(effects
				(font
					(size 1 1)
					(thickness 0.15)
				)
				(justify mirror)
			)
		)
		(property "Voltage" ""
			(at 326.75 190.75 0)
			(layer "B.Fab")
			(hide yes)
			(effects
				(font
					(size 1 1)
					(thickness 0.15)
				)
				(justify mirror)
			)
		)
		(sheetname "FPGA power")
		(sheetfile "fpga-power.kicad_sch")
		(attr smd)
		(fp_line
			(start -0.3 0.3)
			(end 0.3 0.3)
			(stroke
				(width 0.15)
				(type solid)
			)
			(layer "B.SilkS")
		)
		(fp_line
			(start -0.3 -0.3)
			(end 0.3 -0.3)
			(stroke
				(width 0.15)
				(type solid)
			)
			(layer "B.SilkS")
		)
		(fp_rect
			(start -1.24 0.7)
			(end 1.24 -0.7)
			(stroke
				(width 0.05)
				(type solid)
			)
			(fill no)
			(layer "B.CrtYd")
		)
		(fp_rect
			(start -0.8 0.4)
			(end 0.8 -0.4)
			(stroke
				(width 0.15)
				(type solid)
			)
			(fill no)
			(layer "B.Fab")
		)
		(pad "1" smd roundrect
			(at -0.7 0 180)
			(size 0.6 0.8)
			(layers "B.Cu" "B.Mask" "B.Paste")
			(roundrect_rratio 0.2)
			(net 460 "1V8_SYS")
			(pintype "passive")
		)
		(pad "2" smd roundrect
			(at 0.7 0 180)
			(size 0.6 0.8)
			(layers "B.Cu" "B.Mask" "B.Paste")
			(roundrect_rratio 0.2)
			(net 5 "GND")
			(pintype "passive")
		)
	)
	(footprint "antmicro-footprints:C_0603_1608Metric"
		(layer "B.Cu")
		(at 175.5 97.875)
		(descr "Capacitor SMD 0603")
		(tags "capacitor 0603")
		(property "Reference" "C42"
			(at 3.2 0.325 180)
			(layer "B.SilkS")
			(effects
				(font
					(size 0.7 0.7)
					(thickness 0.15)
				)
				(justify left bottom mirror)
			)
		)
		(property "Value" "C_47u_0603"
			(at 0 -1.6 180)
			(layer "B.Fab")
			(effects
				(font
					(size 0.7 0.7)
					(thickness 0.15)
				)
				(justify left bottom mirror)
			)
		)
		(property "Description" " "
			(at 0 0 0)
			(layer "F.Fab")
			(hide yes)
			(effects
				(font
					(size 1.27 1.27)
					(thickness 0.15)
				)
			)
		)
		(property "Author" "Antmicro"
			(at 0 0 0)
			(layer "B.Fab")
			(hide yes)
			(effects
				(font
					(size 1 1)
					(thickness 0.15)
				)
				(justify mirror)
			)
		)
		(property "Dielectric" ""
			(at 0 0 0)
			(layer "B.Fab")
			(hide yes)
			(effects
				(font
					(size 1 1)
					(thickness 0.15)
				)
				(justify mirror)
			)
		)
		(property "License" "Apache-2.0"
			(at 0 0 0)
			(layer "B.Fab")
			(hide yes)
			(effects
				(font
					(size 1 1)
					(thickness 0.15)
				)
				(justify mirror)
			)
		)
		(property "MPN" "GRM188R60J476ME15D"
			(at 0 0 0)
			(layer "B.Fab")
			(hide yes)
			(effects
				(font
					(size 1 1)
					(thickness 0.15)
				)
				(justify mirror)
			)
		)
		(property "Manufacturer" "Murata"
			(at 0 0 0)
			(layer "B.Fab")
			(hide yes)
			(effects
				(font
					(size 1 1)
					(thickness 0.15)
				)
				(justify mirror)
			)
		)
		(property "Val" "47u"
			(at 0 0 0)
			(layer "B.Fab")
			(hide yes)
			(effects
				(font
					(size 1 1)
					(thickness 0.15)
				)
				(justify mirror)
			)
		)
		(property "Voltage" ""
			(at 0 0 0)
			(layer "B.Fab")
			(hide yes)
			(effects
				(font
					(size 1 1)
					(thickness 0.15)
				)
				(justify mirror)
			)
		)
		(sheetname "FPGA power")
		(sheetfile "fpga-power.kicad_sch")
		(attr smd)
		(fp_line
			(start -0.3 -0.3)
			(end 0.3 -0.3)
			(stroke
				(width 0.15)
				(type solid)
			)
			(layer "B.SilkS")
		)
		(fp_line
			(start -0.3 0.3)
			(end 0.3 0.3)
			(stroke
				(width 0.15)
				(type solid)
			)
			(layer "B.SilkS")
		)
		(fp_rect
			(start -1.24 0.7)
			(end 1.24 -0.7)
			(stroke
				(width 0.05)
				(type solid)
			)
			(fill no)
			(layer "B.CrtYd")
		)
		(fp_rect
			(start -0.8 0.4)
			(end 0.8 -0.4)
			(stroke
				(width 0.15)
				(type solid)
			)
			(fill no)
			(layer "B.Fab")
		)
		(pad "1" smd roundrect
			(at -0.7 0)
			(size 0.6 0.8)
			(layers "B.Cu" "B.Mask" "B.Paste")
			(roundrect_rratio 0.2)
			(net 460 "1V8_SYS")
			(pintype "passive")
		)
		(pad "2" smd roundrect
			(at 0.7 0)
			(size 0.6 0.8)
			(layers "B.Cu" "B.Mask" "B.Paste")
			(roundrect_rratio 0.2)
			(net 5 "GND")
			(pintype "passive")
		)
	)
	(footprint "antmicro-footprints:C_0201"
		(layer "B.Cu")
		(at 168.25 87.625 90)
		(descr "Capacitor SMD 0201")
		(tags "capacitor SMD 0201")
		(property "Reference" "C39"
			(at 2.725 0.45 270)
			(layer "B.SilkS")
			(effects
				(font
					(size 0.7 0.7)
					(thickness 0.15)
				)
				(justify left bottom mirror)
			)
		)
		(property "Value" "C_100n_0201"
			(at 0 -1.4 270)
			(layer "B.Fab")
			(effects
				(font
					(size 0.7 0.7)
					(thickness 0.15)
				)
				(justify left bottom mirror)
			)
		)
		(property "Description" " "
			(at 0 0 90)
			(layer "F.Fab")
			(hide yes)
			(effects
				(font
					(size 1.27 1.27)
					(thickness 0.15)
				)
			)
		)
		(property "Author" "Antmicro"
			(at 255.875 -80.625 0)
			(layer "B.Fab")
			(hide yes)
			(effects
				(font
					(size 1 1)
					(thickness 0.15)
				)
				(justify mirror)
			)
		)
		(property "Dielectric" ""
			(at 255.875 -80.625 0)
			(layer "B.Fab")
			(hide yes)
			(effects
				(font
					(size 1 1)
					(thickness 0.15)
				)
				(justify mirror)
			)
		)
		(property "License" "Apache-2.0"
			(at 255.875 -80.625 0)
			(layer "B.Fab")
			(hide yes)
			(effects
				(font
					(size 1 1)
					(thickness 0.15)
				)
				(justify mirror)
			)
		)
		(property "MPN" "CC0201KRX6S5BB104"
			(at 255.875 -80.625 0)
			(layer "B.Fab")
			(hide yes)
			(effects
				(font
					(size 1 1)
					(thickness 0.15)
				)
				(justify mirror)
			)
		)
		(property "Manufacturer" "Yaego"
			(at 255.875 -80.625 0)
			(layer "B.Fab")
			(hide yes)
			(effects
				(font
					(size 1 1)
					(thickness 0.15)
				)
				(justify mirror)
			)
		)
		(property "Val" "100n"
			(at 255.875 -80.625 0)
			(layer "B.Fab")
			(hide yes)
			(effects
				(font
					(size 1 1)
					(thickness 0.15)
				)
				(justify mirror)
			)
		)
		(property "Voltage" ""
			(at 255.875 -80.625 0)
			(layer "B.Fab")
			(hide yes)
			(effects
				(font
					(size 1 1)
					(thickness 0.15)
				)
				(justify mirror)
			)
		)
		(sheetname "FPGA power")
		(sheetfile "fpga-power.kicad_sch")
		(attr smd)
		(fp_rect
			(start -0.72 0.38)
			(end 0.72 -0.38)
			(stroke
				(width 0.05)
				(type solid)
			)
			(fill no)
			(layer "B.CrtYd")
		)
		(fp_rect
			(start 0.3 -0.15)
			(end -0.301 0.149)
			(stroke
				(width 0.15)
				(type solid)
			)
			(fill no)
			(layer "B.Fab")
		)
		(pad "" smd roundrect
			(at -0.349 0.002 90)
			(size 0.318 0.36)
			(layers "B.Paste")
			(roundrect_rratio 0.25)
		)
		(pad "" smd roundrect
			(at 0.341 0.002 90)
			(size 0.318 0.36)
			(layers "B.Paste")
			(roundrect_rratio 0.25)
		)
		(pad "1" smd roundrect
			(at -0.321 0.002 90)
			(size 0.46 0.4)
			(layers "B.Cu" "B.Mask")
			(roundrect_rratio 0.25)
			(net 66 "VDDQ")
			(pintype "passive")
		)
		(pad "2" smd roundrect
			(at 0.32 0.002 90)
			(size 0.46 0.4)
			(layers "B.Cu" "B.Mask")
			(roundrect_rratio 0.25)
			(net 5 "GND")
			(pintype "passive")
		)
	)
	(footprint "antmicro-footprints:C_0201"
		(layer "B.Cu")
		(at 161.136328 87.597157 180)
		(descr "Capacitor SMD 0201")
		(tags "capacitor SMD 0201")
		(property "Reference" "C43"
			(at -1.263672 0.397157 0)
			(layer "B.SilkS")
			(effects
				(font
					(size 0.7 0.7)
					(thickness 0.15)
				)
				(justify left bottom mirror)
			)
		)
		(property "Value" "C_100n_0201"
			(at 0 -1.4 0)
			(layer "B.Fab")
			(effects
				(font
					(size 0.7 0.7)
					(thickness 0.15)
				)
				(justify left bottom mirror)
			)
		)
		(property "Description" " "
			(at 0 0 180)
			(layer "F.Fab")
			(hide yes)
			(effects
				(font
					(size 1.27 1.27)
					(thickness 0.15)
				)
			)
		)
		(property "Author" "Antmicro"
			(at 322.272656 175.194314 0)
			(layer "B.Fab")
			(hide yes)
			(effects
				(font
					(size 1 1)
					(thickness 0.15)
				)
				(justify mirror)
			)
		)
		(property "Dielectric" ""
			(at 322.272656 175.194314 0)
			(layer "B.Fab")
			(hide yes)
			(effects
				(font
					(size 1 1)
					(thickness 0.15)
				)
				(justify mirror)
			)
		)
		(property "License" "Apache-2.0"
			(at 322.272656 175.194314 0)
			(layer "B.Fab")
			(hide yes)
			(effects
				(font
					(size 1 1)
					(thickness 0.15)
				)
				(justify mirror)
			)
		)
		(property "MPN" "CC0201KRX6S5BB104"
			(at 322.272656 175.194314 0)
			(layer "B.Fab")
			(hide yes)
			(effects
				(font
					(size 1 1)
					(thickness 0.15)
				)
				(justify mirror)
			)
		)
		(property "Manufacturer" "Yaego"
			(at 322.272656 175.194314 0)
			(layer "B.Fab")
			(hide yes)
			(effects
				(font
					(size 1 1)
					(thickness 0.15)
				)
				(justify mirror)
			)
		)
		(property "Val" "100n"
			(at 322.272656 175.194314 0)
			(layer "B.Fab")
			(hide yes)
			(effects
				(font
					(size 1 1)
					(thickness 0.15)
				)
				(justify mirror)
			)
		)
		(property "Voltage" ""
			(at 322.272656 175.194314 0)
			(layer "B.Fab")
			(hide yes)
			(effects
				(font
					(size 1 1)
					(thickness 0.15)
				)
				(justify mirror)
			)
		)
		(sheetname "FPGA power")
		(sheetfile "fpga-power.kicad_sch")
		(attr smd)
		(fp_rect
			(start -0.72 0.38)
			(end 0.72 -0.38)
			(stroke
				(width 0.05)
				(type solid)
			)
			(fill no)
			(layer "B.CrtYd")
		)
		(fp_rect
			(start 0.3 -0.15)
			(end -0.301 0.149)
			(stroke
				(width 0.15)
				(type solid)
			)
			(fill no)
			(layer "B.Fab")
		)
		(pad "" smd roundrect
			(at -0.349 0.002 180)
			(size 0.318 0.36)
			(layers "B.Paste")
			(roundrect_rratio 0.25)
		)
		(pad "" smd roundrect
			(at 0.341 0.002 180)
			(size 0.318 0.36)
			(layers "B.Paste")
			(roundrect_rratio 0.25)
		)
		(pad "1" smd roundrect
			(at -0.321 0.002 180)
			(size 0.46 0.4)
			(layers "B.Cu" "B.Mask")
			(roundrect_rratio 0.25)
			(net 66 "VDDQ")
			(pintype "passive")
		)
		(pad "2" smd roundrect
			(at 0.32 0.002 180)
			(size 0.46 0.4)
			(layers "B.Cu" "B.Mask")
			(roundrect_rratio 0.25)
			(net 5 "GND")
			(pintype "passive")
		)
	)
	(footprint "antmicro-footprints:C_0201"
		(layer "B.Cu")
		(at 161.25 91.375 -90)
		(descr "Capacitor SMD 0201")
		(tags "capacitor SMD 0201")
		(property "Reference" "C47"
			(at 0.525 -0.35 90)
			(layer "B.SilkS")
			(effects
				(font
					(size 0.7 0.7)
					(thickness 0.15)
				)
				(justify left bottom mirror)
			)
		)
		(property "Value" "C_100n_0201"
			(at 0 -1.4 90)
			(layer "B.Fab")
			(effects
				(font
					(size 0.7 0.7)
					(thickness 0.15)
				)
				(justify left bottom mirror)
			)
		)
		(property "Description" " "
			(at 0 0 270)
			(layer "F.Fab")
			(hide yes)
			(effects
				(font
					(size 1.27 1.27)
					(thickness 0.15)
				)
			)
		)
		(property "Author" "Antmicro"
			(at 69.875 252.625 0)
			(layer "B.Fab")
			(hide yes)
			(effects
				(font
					(size 1 1)
					(thickness 0.15)
				)
				(justify mirror)
			)
		)
		(property "Dielectric" ""
			(at 69.875 252.625 0)
			(layer "B.Fab")
			(hide yes)
			(effects
				(font
					(size 1 1)
					(thickness 0.15)
				)
				(justify mirror)
			)
		)
		(property "License" "Apache-2.0"
			(at 69.875 252.625 0)
			(layer "B.Fab")
			(hide yes)
			(effects
				(font
					(size 1 1)
					(thickness 0.15)
				)
				(justify mirror)
			)
		)
		(property "MPN" "CC0201KRX6S5BB104"
			(at 69.875 252.625 0)
			(layer "B.Fab")
			(hide yes)
			(effects
				(font
					(size 1 1)
					(thickness 0.15)
				)
				(justify mirror)
			)
		)
		(property "Manufacturer" "Yaego"
			(at 69.875 252.625 0)
			(layer "B.Fab")
			(hide yes)
			(effects
				(font
					(size 1 1)
					(thickness 0.15)
				)
				(justify mirror)
			)
		)
		(property "Val" "100n"
			(at 69.875 252.625 0)
			(layer "B.Fab")
			(hide yes)
			(effects
				(font
					(size 1 1)
					(thickness 0.15)
				)
				(justify mirror)
			)
		)
		(property "Voltage" ""
			(at 69.875 252.625 0)
			(layer "B.Fab")
			(hide yes)
			(effects
				(font
					(size 1 1)
					(thickness 0.15)
				)
				(justify mirror)
			)
		)
		(sheetname "FPGA power")
		(sheetfile "fpga-power.kicad_sch")
		(attr smd)
		(fp_rect
			(start -0.72 0.38)
			(end 0.72 -0.38)
			(stroke
				(width 0.05)
				(type solid)
			)
			(fill no)
			(layer "B.CrtYd")
		)
		(fp_rect
			(start 0.3 -0.15)
			(end -0.301 0.149)
			(stroke
				(width 0.15)
				(type solid)
			)
			(fill no)
			(layer "B.Fab")
		)
		(pad "" smd roundrect
			(at -0.349 0.002 270)
			(size 0.318 0.36)
			(layers "B.Paste")
			(roundrect_rratio 0.25)
		)
		(pad "" smd roundrect
			(at 0.341 0.002 270)
			(size 0.318 0.36)
			(layers "B.Paste")
			(roundrect_rratio 0.25)
		)
		(pad "1" smd roundrect
			(at -0.321 0.002 270)
			(size 0.46 0.4)
			(layers "B.Cu" "B.Mask")
			(roundrect_rratio 0.25)
			(net 66 "VDDQ")
			(pintype "passive")
		)
		(pad "2" smd roundrect
			(at 0.32 0.002 270)
			(size 0.46 0.4)
			(layers "B.Cu" "B.Mask")
			(roundrect_rratio 0.25)
			(net 5 "GND")
			(pintype "passive")
		)
	)
	(footprint "antmicro-footprints:C_0201"
		(layer "B.Cu")
		(at 169 91.5)
		(descr "Capacitor SMD 0201")
		(tags "capacitor SMD 0201")
		(property "Reference" "C62"
			(at 2.5 -1.8 180)
			(layer "B.SilkS")
			(effects
				(font
					(size 0.7 0.7)
					(thickness 0.15)
				)
				(justify left bottom mirror)
			)
		)
		(property "Value" "C_100n_0201"
			(at 0 -1.4 180)
			(layer "B.Fab")
			(effects
				(font
					(size 0.7 0.7)
					(thickness 0.15)
				)
				(justify left bottom mirror)
			)
		)
		(property "Description" " "
			(at 0 0 0)
			(layer "F.Fab")
			(hide yes)
			(effects
				(font
					(size 1.27 1.27)
					(thickness 0.15)
				)
			)
		)
		(property "Author" "Antmicro"
			(at 0 0 0)
			(layer "B.Fab")
			(hide yes)
			(effects
				(font
					(size 1 1)
					(thickness 0.15)
				)
				(justify mirror)
			)
		)
		(property "Dielectric" ""
			(at 0 0 0)
			(layer "B.Fab")
			(hide yes)
			(effects
				(font
					(size 1 1)
					(thickness 0.15)
				)
				(justify mirror)
			)
		)
		(property "License" "Apache-2.0"
			(at 0 0 0)
			(layer "B.Fab")
			(hide yes)
			(effects
				(font
					(size 1 1)
					(thickness 0.15)
				)
				(justify mirror)
			)
		)
		(property "MPN" "CC0201KRX6S5BB104"
			(at 0 0 0)
			(layer "B.Fab")
			(hide yes)
			(effects
				(font
					(size 1 1)
					(thickness 0.15)
				)
				(justify mirror)
			)
		)
		(property "Manufacturer" "Yaego"
			(at 0 0 0)
			(layer "B.Fab")
			(hide yes)
			(effects
				(font
					(size 1 1)
					(thickness 0.15)
				)
				(justify mirror)
			)
		)
		(property "Val" "100n"
			(at 0 0 0)
			(layer "B.Fab")
			(hide yes)
			(effects
				(font
					(size 1 1)
					(thickness 0.15)
				)
				(justify mirror)
			)
		)
		(property "Voltage" ""
			(at 0 0 0)
			(layer "B.Fab")
			(hide yes)
			(effects
				(font
					(size 1 1)
					(thickness 0.15)
				)
				(justify mirror)
			)
		)
		(sheetname "FPGA power")
		(sheetfile "fpga-power.kicad_sch")
		(attr smd)
		(fp_rect
			(start -0.72 0.38)
			(end 0.72 -0.38)
			(stroke
				(width 0.05)
				(type solid)
			)
			(fill no)
			(layer "B.CrtYd")
		)
		(fp_rect
			(start 0.3 -0.15)
			(end -0.301 0.149)
			(stroke
				(width 0.15)
				(type solid)
			)
			(fill no)
			(layer "B.Fab")
		)
		(pad "" smd roundrect
			(at -0.349 0.002)
			(size 0.318 0.36)
			(layers "B.Paste")
			(roundrect_rratio 0.25)
		)
		(pad "" smd roundrect
			(at 0.341 0.002)
			(size 0.318 0.36)
			(layers "B.Paste")
			(roundrect_rratio 0.25)
		)
		(pad "1" smd roundrect
			(at -0.321 0.002)
			(size 0.46 0.4)
			(layers "B.Cu" "B.Mask")
			(roundrect_rratio 0.25)
			(net 465 "1V0_SYS")
			(pintype "passive")
		)
		(pad "2" smd roundrect
			(at 0.32 0.002)
			(size 0.46 0.4)
			(layers "B.Cu" "B.Mask")
			(roundrect_rratio 0.25)
			(net 5 "GND")
			(pintype "passive")
		)
	)
	(footprint "antmicro-footprints:C_0201"
		(layer "B.Cu")
		(at 170.375 100.75)
		(descr "Capacitor SMD 0201")
		(tags "capacitor SMD 0201")
		(property "Reference" "C66"
			(at 1.425 1.15 180)
			(layer "B.SilkS")
			(effects
				(font
					(size 0.7 0.7)
					(thickness 0.15)
				)
				(justify left bottom mirror)
			)
		)
		(property "Value" "C_100n_0201"
			(at 0 -1.4 180)
			(layer "B.Fab")
			(effects
				(font
					(size 0.7 0.7)
					(thickness 0.15)
				)
				(justify left bottom mirror)
			)
		)
		(property "Description" " "
			(at 0 0 0)
			(layer "F.Fab")
			(hide yes)
			(effects
				(font
					(size 1.27 1.27)
					(thickness 0.15)
				)
			)
		)
		(property "Author" "Antmicro"
			(at 0 0 0)
			(layer "B.Fab")
			(hide yes)
			(effects
				(font
					(size 1 1)
					(thickness 0.15)
				)
				(justify mirror)
			)
		)
		(property "Dielectric" ""
			(at 0 0 0)
			(layer "B.Fab")
			(hide yes)
			(effects
				(font
					(size 1 1)
					(thickness 0.15)
				)
				(justify mirror)
			)
		)
		(property "License" "Apache-2.0"
			(at 0 0 0)
			(layer "B.Fab")
			(hide yes)
			(effects
				(font
					(size 1 1)
					(thickness 0.15)
				)
				(justify mirror)
			)
		)
		(property "MPN" "CC0201KRX6S5BB104"
			(at 0 0 0)
			(layer "B.Fab")
			(hide yes)
			(effects
				(font
					(size 1 1)
					(thickness 0.15)
				)
				(justify mirror)
			)
		)
		(property "Manufacturer" "Yaego"
			(at 0 0 0)
			(layer "B.Fab")
			(hide yes)
			(effects
				(font
					(size 1 1)
					(thickness 0.15)
				)
				(justify mirror)
			)
		)
		(property "Val" "100n"
			(at 0 0 0)
			(layer "B.Fab")
			(hide yes)
			(effects
				(font
					(size 1 1)
					(thickness 0.15)
				)
				(justify mirror)
			)
		)
		(property "Voltage" ""
			(at 0 0 0)
			(layer "B.Fab")
			(hide yes)
			(effects
				(font
					(size 1 1)
					(thickness 0.15)
				)
				(justify mirror)
			)
		)
		(sheetname "FPGA power")
		(sheetfile "fpga-power.kicad_sch")
		(attr smd)
		(fp_rect
			(start -0.72 0.38)
			(end 0.72 -0.38)
			(stroke
				(width 0.05)
				(type solid)
			)
			(fill no)
			(layer "B.CrtYd")
		)
		(fp_rect
			(start 0.3 -0.15)
			(end -0.301 0.149)
			(stroke
				(width 0.15)
				(type solid)
			)
			(fill no)
			(layer "B.Fab")
		)
		(pad "" smd roundrect
			(at -0.349 0.002)
			(size 0.318 0.36)
			(layers "B.Paste")
			(roundrect_rratio 0.25)
		)
		(pad "" smd roundrect
			(at 0.341 0.002)
			(size 0.318 0.36)
			(layers "B.Paste")
			(roundrect_rratio 0.25)
		)
		(pad "1" smd roundrect
			(at -0.321 0.002)
			(size 0.46 0.4)
			(layers "B.Cu" "B.Mask")
			(roundrect_rratio 0.25)
			(net 465 "1V0_SYS")
			(pintype "passive")
		)
		(pad "2" smd roundrect
			(at 0.32 0.002)
			(size 0.46 0.4)
			(layers "B.Cu" "B.Mask")
			(roundrect_rratio 0.25)
			(net 5 "GND")
			(pintype "passive")
		)
	)
	(footprint "antmicro-footprints:C_0201"
		(layer "B.Cu")
		(at 165.625 87.625)
		(descr "Capacitor SMD 0201")
		(tags "capacitor SMD 0201")
		(property "Reference" "C35"
			(at 1.075 -0.325 180)
			(layer "B.SilkS")
			(effects
				(font
					(size 0.7 0.7)
					(thickness 0.15)
				)
				(justify left bottom mirror)
			)
		)
		(property "Value" "C_100n_0201"
			(at 0 -1.4 180)
			(layer "B.Fab")
			(effects
				(font
					(size 0.7 0.7)
					(thickness 0.15)
				)
				(justify left bottom mirror)
			)
		)
		(property "Description" " "
			(at 0 0 0)
			(layer "F.Fab")
			(hide yes)
			(effects
				(font
					(size 1.27 1.27)
					(thickness 0.15)
				)
			)
		)
		(property "Author" "Antmicro"
			(at 0 0 0)
			(layer "B.Fab")
			(hide yes)
			(effects
				(font
					(size 1 1)
					(thickness 0.15)
				)
				(justify mirror)
			)
		)
		(property "Dielectric" ""
			(at 0 0 0)
			(layer "B.Fab")
			(hide yes)
			(effects
				(font
					(size 1 1)
					(thickness 0.15)
				)
				(justify mirror)
			)
		)
		(property "License" "Apache-2.0"
			(at 0 0 0)
			(layer "B.Fab")
			(hide yes)
			(effects
				(font
					(size 1 1)
					(thickness 0.15)
				)
				(justify mirror)
			)
		)
		(property "MPN" "CC0201KRX6S5BB104"
			(at 0 0 0)
			(layer "B.Fab")
			(hide yes)
			(effects
				(font
					(size 1 1)
					(thickness 0.15)
				)
				(justify mirror)
			)
		)
		(property "Manufacturer" "Yaego"
			(at 0 0 0)
			(layer "B.Fab")
			(hide yes)
			(effects
				(font
					(size 1 1)
					(thickness 0.15)
				)
				(justify mirror)
			)
		)
		(property "Val" "100n"
			(at 0 0 0)
			(layer "B.Fab")
			(hide yes)
			(effects
				(font
					(size 1 1)
					(thickness 0.15)
				)
				(justify mirror)
			)
		)
		(property "Voltage" ""
			(at 0 0 0)
			(layer "B.Fab")
			(hide yes)
			(effects
				(font
					(size 1 1)
					(thickness 0.15)
				)
				(justify mirror)
			)
		)
		(sheetname "FPGA power")
		(sheetfile "fpga-power.kicad_sch")
		(attr smd)
		(fp_rect
			(start -0.72 0.38)
			(end 0.72 -0.38)
			(stroke
				(width 0.05)
				(type solid)
			)
			(fill no)
			(layer "B.CrtYd")
		)
		(fp_rect
			(start 0.3 -0.15)
			(end -0.301 0.149)
			(stroke
				(width 0.15)
				(type solid)
			)
			(fill no)
			(layer "B.Fab")
		)
		(pad "" smd roundrect
			(at -0.349 0.002)
			(size 0.318 0.36)
			(layers "B.Paste")
			(roundrect_rratio 0.25)
		)
		(pad "" smd roundrect
			(at 0.341 0.002)
			(size 0.318 0.36)
			(layers "B.Paste")
			(roundrect_rratio 0.25)
		)
		(pad "1" smd roundrect
			(at -0.321 0.002)
			(size 0.46 0.4)
			(layers "B.Cu" "B.Mask")
			(roundrect_rratio 0.25)
			(net 66 "VDDQ")
			(pintype "passive")
		)
		(pad "2" smd roundrect
			(at 0.32 0.002)
			(size 0.46 0.4)
			(layers "B.Cu" "B.Mask")
			(roundrect_rratio 0.25)
			(net 5 "GND")
			(pintype "passive")
		)
	)
	(footprint "antmicro-footprints:C_0201"
		(layer "B.Cu")
		(at 166 89.875)
		(descr "Capacitor SMD 0201")
		(tags "capacitor SMD 0201")
		(property "Reference" "C55"
			(at 0.8 -0.375 180)
			(layer "B.SilkS")
			(effects
				(font
					(size 0.7 0.7)
					(thickness 0.15)
				)
				(justify left bottom mirror)
			)
		)
		(property "Value" "C_100n_0201"
			(at 0 -1.4 180)
			(layer "B.Fab")
			(effects
				(font
					(size 0.7 0.7)
					(thickness 0.15)
				)
				(justify left bottom mirror)
			)
		)
		(property "Description" " "
			(at 0 0 0)
			(layer "F.Fab")
			(hide yes)
			(effects
				(font
					(size 1.27 1.27)
					(thickness 0.15)
				)
			)
		)
		(property "Author" "Antmicro"
			(at 0 0 0)
			(layer "B.Fab")
			(hide yes)
			(effects
				(font
					(size 1 1)
					(thickness 0.15)
				)
				(justify mirror)
			)
		)
		(property "Dielectric" ""
			(at 0 0 0)
			(layer "B.Fab")
			(hide yes)
			(effects
				(font
					(size 1 1)
					(thickness 0.15)
				)
				(justify mirror)
			)
		)
		(property "License" "Apache-2.0"
			(at 0 0 0)
			(layer "B.Fab")
			(hide yes)
			(effects
				(font
					(size 1 1)
					(thickness 0.15)
				)
				(justify mirror)
			)
		)
		(property "MPN" "CC0201KRX6S5BB104"
			(at 0 0 0)
			(layer "B.Fab")
			(hide yes)
			(effects
				(font
					(size 1 1)
					(thickness 0.15)
				)
				(justify mirror)
			)
		)
		(property "Manufacturer" "Yaego"
			(at 0 0 0)
			(layer "B.Fab")
			(hide yes)
			(effects
				(font
					(size 1 1)
					(thickness 0.15)
				)
				(justify mirror)
			)
		)
		(property "Val" "100n"
			(at 0 0 0)
			(layer "B.Fab")
			(hide yes)
			(effects
				(font
					(size 1 1)
					(thickness 0.15)
				)
				(justify mirror)
			)
		)
		(property "Voltage" ""
			(at 0 0 0)
			(layer "B.Fab")
			(hide yes)
			(effects
				(font
					(size 1 1)
					(thickness 0.15)
				)
				(justify mirror)
			)
		)
		(sheetname "FPGA power")
		(sheetfile "fpga-power.kicad_sch")
		(attr smd)
		(fp_rect
			(start -0.72 0.38)
			(end 0.72 -0.38)
			(stroke
				(width 0.05)
				(type solid)
			)
			(fill no)
			(layer "B.CrtYd")
		)
		(fp_rect
			(start 0.3 -0.15)
			(end -0.301 0.149)
			(stroke
				(width 0.15)
				(type solid)
			)
			(fill no)
			(layer "B.Fab")
		)
		(pad "" smd roundrect
			(at -0.349 0.002)
			(size 0.318 0.36)
			(layers "B.Paste")
			(roundrect_rratio 0.25)
		)
		(pad "" smd roundrect
			(at 0.341 0.002)
			(size 0.318 0.36)
			(layers "B.Paste")
			(roundrect_rratio 0.25)
		)
		(pad "1" smd roundrect
			(at -0.321 0.002)
			(size 0.46 0.4)
			(layers "B.Cu" "B.Mask")
			(roundrect_rratio 0.25)
			(net 66 "VDDQ")
			(pintype "passive")
		)
		(pad "2" smd roundrect
			(at 0.32 0.002)
			(size 0.46 0.4)
			(layers "B.Cu" "B.Mask")
			(roundrect_rratio 0.25)
			(net 5 "GND")
			(pintype "passive")
		)
	)
	(footprint "antmicro-footprints:C_0201"
		(layer "B.Cu")
		(at 162.375 93.5 -90)
		(descr "Capacitor SMD 0201")
		(tags "capacitor SMD 0201")
		(property "Reference" "C61"
			(at -1.6 -1.125 90)
			(layer "B.SilkS")
			(effects
				(font
					(size 0.7 0.7)
					(thickness 0.15)
				)
				(justify left bottom mirror)
			)
		)
		(property "Value" "C_100n_0201"
			(at 0 -1.4 90)
			(layer "B.Fab")
			(effects
				(font
					(size 0.7 0.7)
					(thickness 0.15)
				)
				(justify left bottom mirror)
			)
		)
		(property "Description" " "
			(at 0 0 270)
			(layer "F.Fab")
			(hide yes)
			(effects
				(font
					(size 1.27 1.27)
					(thickness 0.15)
				)
			)
		)
		(property "Author" "Antmicro"
			(at 68.875 255.875 0)
			(layer "B.Fab")
			(hide yes)
			(effects
				(font
					(size 1 1)
					(thickness 0.15)
				)
				(justify mirror)
			)
		)
		(property "Dielectric" ""
			(at 68.875 255.875 0)
			(layer "B.Fab")
			(hide yes)
			(effects
				(font
					(size 1 1)
					(thickness 0.15)
				)
				(justify mirror)
			)
		)
		(property "License" "Apache-2.0"
			(at 68.875 255.875 0)
			(layer "B.Fab")
			(hide yes)
			(effects
				(font
					(size 1 1)
					(thickness 0.15)
				)
				(justify mirror)
			)
		)
		(property "MPN" "CC0201KRX6S5BB104"
			(at 68.875 255.875 0)
			(layer "B.Fab")
			(hide yes)
			(effects
				(font
					(size 1 1)
					(thickness 0.15)
				)
				(justify mirror)
			)
		)
		(property "Manufacturer" "Yaego"
			(at 68.875 255.875 0)
			(layer "B.Fab")
			(hide yes)
			(effects
				(font
					(size 1 1)
					(thickness 0.15)
				)
				(justify mirror)
			)
		)
		(property "Val" "100n"
			(at 68.875 255.875 0)
			(layer "B.Fab")
			(hide yes)
			(effects
				(font
					(size 1 1)
					(thickness 0.15)
				)
				(justify mirror)
			)
		)
		(property "Voltage" ""
			(at 68.875 255.875 0)
			(layer "B.Fab")
			(hide yes)
			(effects
				(font
					(size 1 1)
					(thickness 0.15)
				)
				(justify mirror)
			)
		)
		(sheetname "FPGA power")
		(sheetfile "fpga-power.kicad_sch")
		(attr smd)
		(fp_rect
			(start -0.72 0.38)
			(end 0.72 -0.38)
			(stroke
				(width 0.05)
				(type solid)
			)
			(fill no)
			(layer "B.CrtYd")
		)
		(fp_rect
			(start 0.3 -0.15)
			(end -0.301 0.149)
			(stroke
				(width 0.15)
				(type solid)
			)
			(fill no)
			(layer "B.Fab")
		)
		(pad "" smd roundrect
			(at -0.349 0.002 270)
			(size 0.318 0.36)
			(layers "B.Paste")
			(roundrect_rratio 0.25)
		)
		(pad "" smd roundrect
			(at 0.341 0.002 270)
			(size 0.318 0.36)
			(layers "B.Paste")
			(roundrect_rratio 0.25)
		)
		(pad "1" smd roundrect
			(at -0.321 0.002 270)
			(size 0.46 0.4)
			(layers "B.Cu" "B.Mask")
			(roundrect_rratio 0.25)
			(net 66 "VDDQ")
			(pintype "passive")
		)
		(pad "2" smd roundrect
			(at 0.32 0.002 270)
			(size 0.46 0.4)
			(layers "B.Cu" "B.Mask")
			(roundrect_rratio 0.25)
			(net 5 "GND")
			(pintype "passive")
		)
	)
	(footprint "antmicro-footprints:R_0402_1005Metric"
		(layer "B.Cu")
		(at 180.1885 117.015757)
		(descr "Resistor SMD 0402")
		(tags "resistor SMD 0402")
		(property "Reference" "R56"
			(at -0.7885 0.384243 180)
			(layer "B.SilkS")
			(effects
				(font
					(size 0.7 0.7)
					(thickness 0.15)
				)
				(justify left bottom mirror)
			)
		)
		(property "Value" "R_4k7_0402"
			(at 0 -1.4 180)
			(layer "B.Fab")
			(effects
				(font
					(size 0.7 0.7)
					(thickness 0.15)
				)
				(justify left bottom mirror)
			)
		)
		(property "Description" "4k7 resistor in 0402 package with 1% tolerance"
			(at 0 0 0)
			(layer "F.Fab")
			(hide yes)
			(effects
				(font
					(size 1.27 1.27)
					(thickness 0.15)
				)
			)
		)
		(property "Author" "Antmicro"
			(at 0 0 0)
			(layer "B.Fab")
			(hide yes)
			(effects
				(font
					(size 1 1)
					(thickness 0.15)
				)
				(justify mirror)
			)
		)
		(property "License" "Apache-2.0"
			(at 0 0 0)
			(layer "B.Fab")
			(hide yes)
			(effects
				(font
					(size 1 1)
					(thickness 0.15)
				)
				(justify mirror)
			)
		)
		(property "MPN" "CR0402-FX-4701GLF"
			(at 0 0 0)
			(layer "B.Fab")
			(hide yes)
			(effects
				(font
					(size 1 1)
					(thickness 0.15)
				)
				(justify mirror)
			)
		)
		(property "Manufacturer" "Bourns"
			(at 0 0 0)
			(layer "B.Fab")
			(hide yes)
			(effects
				(font
					(size 1 1)
					(thickness 0.15)
				)
				(justify mirror)
			)
		)
		(property "Tolerance" "1%"
			(at 0 0 0)
			(layer "B.Fab")
			(hide yes)
			(effects
				(font
					(size 1 1)
					(thickness 0.15)
				)
				(justify mirror)
			)
		)
		(property "Val" "4k7"
			(at 0 0 0)
			(layer "B.Fab")
			(hide yes)
			(effects
				(font
					(size 1 1)
					(thickness 0.15)
				)
				(justify mirror)
			)
		)
		(sheetname "Config SPI flash")
		(sheetfile "config-spi.kicad_sch")
		(attr smd)
		(fp_rect
			(start -0.93 0.47)
			(end 0.93 -0.47)
			(stroke
				(width 0.05)
				(type solid)
			)
			(fill no)
			(layer "B.CrtYd")
		)
		(fp_rect
			(start -0.5 0.25)
			(end 0.5 -0.25)
			(stroke
				(width 0.15)
				(type solid)
			)
			(fill no)
			(layer "B.Fab")
		)
		(pad "1" smd roundrect
			(at -0.485 0)
			(size 0.59 0.64)
			(layers "B.Cu" "B.Mask" "B.Paste")
			(roundrect_rratio 0.25)
			(net 459 "3V3_SYS")
			(pintype "passive")
		)
		(pad "2" smd roundrect
			(at 0.485 0)
			(size 0.59 0.64)
			(layers "B.Cu" "B.Mask" "B.Paste")
			(roundrect_rratio 0.25)
			(net 18 "QSPI_DQ3")
			(pintype "passive")
		)
	)
	(footprint "antmicro-footprints:R_0402_1005Metric"
		(layer "B.Cu")
		(at 168.822 118.285757 180)
		(descr "Resistor SMD 0402")
		(tags "resistor SMD 0402")
		(property "Reference" "R59"
			(at -2.978 -0.454243 0)
			(layer "B.SilkS")
			(effects
				(font
					(size 0.7 0.7)
					(thickness 0.15)
				)
				(justify left bottom mirror)
			)
		)
		(property "Value" "R_4k7_0402"
			(at 0 -1.4 0)
			(layer "B.Fab")
			(effects
				(font
					(size 0.7 0.7)
					(thickness 0.15)
				)
				(justify left bottom mirror)
			)
		)
		(property "Description" "4k7 resistor in 0402 package with 1% tolerance"
			(at 0 0 180)
			(layer "F.Fab")
			(hide yes)
			(effects
				(font
					(size 1.27 1.27)
					(thickness 0.15)
				)
			)
		)
		(property "Author" "Antmicro"
			(at 337.644 236.571514 0)
			(layer "B.Fab")
			(hide yes)
			(effects
				(font
					(size 1 1)
					(thickness 0.15)
				)
				(justify mirror)
			)
		)
		(property "License" "Apache-2.0"
			(at 337.644 236.571514 0)
			(layer "B.Fab")
			(hide yes)
			(effects
				(font
					(size 1 1)
					(thickness 0.15)
				)
				(justify mirror)
			)
		)
		(property "MPN" "CR0402-FX-4701GLF"
			(at 337.644 236.571514 0)
			(layer "B.Fab")
			(hide yes)
			(effects
				(font
					(size 1 1)
					(thickness 0.15)
				)
				(justify mirror)
			)
		)
		(property "Manufacturer" "Bourns"
			(at 337.644 236.571514 0)
			(layer "B.Fab")
			(hide yes)
			(effects
				(font
					(size 1 1)
					(thickness 0.15)
				)
				(justify mirror)
			)
		)
		(property "Tolerance" "1%"
			(at 337.644 236.571514 0)
			(layer "B.Fab")
			(hide yes)
			(effects
				(font
					(size 1 1)
					(thickness 0.15)
				)
				(justify mirror)
			)
		)
		(property "Val" "4k7"
			(at 337.644 236.571514 0)
			(layer "B.Fab")
			(hide yes)
			(effects
				(font
					(size 1 1)
					(thickness 0.15)
				)
				(justify mirror)
			)
		)
		(sheetname "Config SPI flash")
		(sheetfile "config-spi.kicad_sch")
		(attr smd)
		(fp_rect
			(start -0.93 0.47)
			(end 0.93 -0.47)
			(stroke
				(width 0.05)
				(type solid)
			)
			(fill no)
			(layer "B.CrtYd")
		)
		(fp_rect
			(start -0.5 0.25)
			(end 0.5 -0.25)
			(stroke
				(width 0.15)
				(type solid)
			)
			(fill no)
			(layer "B.Fab")
		)
		(pad "1" smd roundrect
			(at -0.485 0 180)
			(size 0.59 0.64)
			(layers "B.Cu" "B.Mask" "B.Paste")
			(roundrect_rratio 0.25)
			(net 459 "3V3_SYS")
			(pintype "passive")
		)
		(pad "2" smd roundrect
			(at 0.485 0 180)
			(size 0.59 0.64)
			(layers "B.Cu" "B.Mask" "B.Paste")
			(roundrect_rratio 0.25)
			(net 17 "QSPI_DQ2")
			(pintype "passive")
		)
	)
	(footprint "antmicro-footprints:C_0201"
		(layer "B.Cu")
		(at 163.125 97 180)
		(descr "Capacitor SMD 0201")
		(tags "capacitor SMD 0201")
		(property "Reference" "C65"
			(at 0.525 -0.4 0)
			(layer "B.SilkS")
			(effects
				(font
					(size 0.7 0.7)
					(thickness 0.15)
				)
				(justify left bottom mirror)
			)
		)
		(property "Value" "C_100n_0201"
			(at 0 -1.4 0)
			(layer "B.Fab")
			(effects
				(font
					(size 0.7 0.7)
					(thickness 0.15)
				)
				(justify left bottom mirror)
			)
		)
		(property "Description" " "
			(at 0 0 180)
			(layer "F.Fab")
			(hide yes)
			(effects
				(font
					(size 1.27 1.27)
					(thickness 0.15)
				)
			)
		)
		(property "Author" "Antmicro"
			(at 326.25 194 0)
			(layer "B.Fab")
			(hide yes)
			(effects
				(font
					(size 1 1)
					(thickness 0.15)
				)
				(justify mirror)
			)
		)
		(property "Dielectric" ""
			(at 326.25 194 0)
			(layer "B.Fab")
			(hide yes)
			(effects
				(font
					(size 1 1)
					(thickness 0.15)
				)
				(justify mirror)
			)
		)
		(property "License" "Apache-2.0"
			(at 326.25 194 0)
			(layer "B.Fab")
			(hide yes)
			(effects
				(font
					(size 1 1)
					(thickness 0.15)
				)
				(justify mirror)
			)
		)
		(property "MPN" "CC0201KRX6S5BB104"
			(at 326.25 194 0)
			(layer "B.Fab")
			(hide yes)
			(effects
				(font
					(size 1 1)
					(thickness 0.15)
				)
				(justify mirror)
			)
		)
		(property "Manufacturer" "Yaego"
			(at 326.25 194 0)
			(layer "B.Fab")
			(hide yes)
			(effects
				(font
					(size 1 1)
					(thickness 0.15)
				)
				(justify mirror)
			)
		)
		(property "Val" "100n"
			(at 326.25 194 0)
			(layer "B.Fab")
			(hide yes)
			(effects
				(font
					(size 1 1)
					(thickness 0.15)
				)
				(justify mirror)
			)
		)
		(property "Voltage" ""
			(at 326.25 194 0)
			(layer "B.Fab")
			(hide yes)
			(effects
				(font
					(size 1 1)
					(thickness 0.15)
				)
				(justify mirror)
			)
		)
		(sheetname "FPGA power")
		(sheetfile "fpga-power.kicad_sch")
		(attr smd)
		(fp_rect
			(start -0.72 0.38)
			(end 0.72 -0.38)
			(stroke
				(width 0.05)
				(type solid)
			)
			(fill no)
			(layer "B.CrtYd")
		)
		(fp_rect
			(start 0.3 -0.15)
			(end -0.301 0.149)
			(stroke
				(width 0.15)
				(type solid)
			)
			(fill no)
			(layer "B.Fab")
		)
		(pad "" smd roundrect
			(at -0.349 0.002 180)
			(size 0.318 0.36)
			(layers "B.Paste")
			(roundrect_rratio 0.25)
		)
		(pad "" smd roundrect
			(at 0.341 0.002 180)
			(size 0.318 0.36)
			(layers "B.Paste")
			(roundrect_rratio 0.25)
		)
		(pad "1" smd roundrect
			(at -0.321 0.002 180)
			(size 0.46 0.4)
			(layers "B.Cu" "B.Mask")
			(roundrect_rratio 0.25)
			(net 66 "VDDQ")
			(pintype "passive")
		)
		(pad "2" smd roundrect
			(at 0.32 0.002 180)
			(size 0.46 0.4)
			(layers "B.Cu" "B.Mask")
			(roundrect_rratio 0.25)
			(net 5 "GND")
			(pintype "passive")
		)
	)
	(footprint "antmicro-footprints:C_0201"
		(layer "B.Cu")
		(at 161 98 180)
		(descr "Capacitor SMD 0201")
		(tags "capacitor SMD 0201")
		(property "Reference" "C69"
			(at 0.5 -0.4 0)
			(layer "B.SilkS")
			(effects
				(font
					(size 0.7 0.7)
					(thickness 0.15)
				)
				(justify left bottom mirror)
			)
		)
		(property "Value" "C_100n_0201"
			(at 0 -1.4 0)
			(layer "B.Fab")
			(effects
				(font
					(size 0.7 0.7)
					(thickness 0.15)
				)
				(justify left bottom mirror)
			)
		)
		(property "Description" " "
			(at 0 0 180)
			(layer "F.Fab")
			(hide yes)
			(effects
				(font
					(size 1.27 1.27)
					(thickness 0.15)
				)
			)
		)
		(property "Author" "Antmicro"
			(at 322 196 0)
			(layer "B.Fab")
			(hide yes)
			(effects
				(font
					(size 1 1)
					(thickness 0.15)
				)
				(justify mirror)
			)
		)
		(property "Dielectric" ""
			(at 322 196 0)
			(layer "B.Fab")
			(hide yes)
			(effects
				(font
					(size 1 1)
					(thickness 0.15)
				)
				(justify mirror)
			)
		)
		(property "License" "Apache-2.0"
			(at 322 196 0)
			(layer "B.Fab")
			(hide yes)
			(effects
				(font
					(size 1 1)
					(thickness 0.15)
				)
				(justify mirror)
			)
		)
		(property "MPN" "CC0201KRX6S5BB104"
			(at 322 196 0)
			(layer "B.Fab")
			(hide yes)
			(effects
				(font
					(size 1 1)
					(thickness 0.15)
				)
				(justify mirror)
			)
		)
		(property "Manufacturer" "Yaego"
			(at 322 196 0)
			(layer "B.Fab")
			(hide yes)
			(effects
				(font
					(size 1 1)
					(thickness 0.15)
				)
				(justify mirror)
			)
		)
		(property "Val" "100n"
			(at 322 196 0)
			(layer "B.Fab")
			(hide yes)
			(effects
				(font
					(size 1 1)
					(thickness 0.15)
				)
				(justify mirror)
			)
		)
		(property "Voltage" ""
			(at 322 196 0)
			(layer "B.Fab")
			(hide yes)
			(effects
				(font
					(size 1 1)
					(thickness 0.15)
				)
				(justify mirror)
			)
		)
		(sheetname "FPGA power")
		(sheetfile "fpga-power.kicad_sch")
		(attr smd)
		(fp_rect
			(start -0.72 0.38)
			(end 0.72 -0.38)
			(stroke
				(width 0.05)
				(type solid)
			)
			(fill no)
			(layer "B.CrtYd")
		)
		(fp_rect
			(start 0.3 -0.15)
			(end -0.301 0.149)
			(stroke
				(width 0.15)
				(type solid)
			)
			(fill no)
			(layer "B.Fab")
		)
		(pad "" smd roundrect
			(at -0.349 0.002 180)
			(size 0.318 0.36)
			(layers "B.Paste")
			(roundrect_rratio 0.25)
		)
		(pad "" smd roundrect
			(at 0.341 0.002 180)
			(size 0.318 0.36)
			(layers "B.Paste")
			(roundrect_rratio 0.25)
		)
		(pad "1" smd roundrect
			(at -0.321 0.002 180)
			(size 0.46 0.4)
			(layers "B.Cu" "B.Mask")
			(roundrect_rratio 0.25)
			(net 66 "VDDQ")
			(pintype "passive")
		)
		(pad "2" smd roundrect
			(at 0.32 0.002 180)
			(size 0.46 0.4)
			(layers "B.Cu" "B.Mask")
			(roundrect_rratio 0.25)
			(net 5 "GND")
			(pintype "passive")
		)
	)
	(footprint "antmicro-footprints:C_0201"
		(layer "B.Cu")
		(at 167.5 85.875 -90)
		(descr "Capacitor SMD 0201")
		(tags "capacitor SMD 0201")
		(property "Reference" "C73"
			(at -2.675 -0.3 90)
			(layer "B.SilkS")
			(effects
				(font
					(size 0.7 0.7)
					(thickness 0.15)
				)
				(justify left bottom mirror)
			)
		)
		(property "Value" "C_100n_0201"
			(at 0 -1.4 90)
			(layer "B.Fab")
			(effects
				(font
					(size 0.7 0.7)
					(thickness 0.15)
				)
				(justify left bottom mirror)
			)
		)
		(property "Description" " "
			(at 0 0 270)
			(layer "F.Fab")
			(hide yes)
			(effects
				(font
					(size 1.27 1.27)
					(thickness 0.15)
				)
			)
		)
		(property "Author" "Antmicro"
			(at 81.625 253.375 0)
			(layer "B.Fab")
			(hide yes)
			(effects
				(font
					(size 1 1)
					(thickness 0.15)
				)
				(justify mirror)
			)
		)
		(property "Dielectric" ""
			(at 81.625 253.375 0)
			(layer "B.Fab")
			(hide yes)
			(effects
				(font
					(size 1 1)
					(thickness 0.15)
				)
				(justify mirror)
			)
		)
		(property "License" "Apache-2.0"
			(at 81.625 253.375 0)
			(layer "B.Fab")
			(hide yes)
			(effects
				(font
					(size 1 1)
					(thickness 0.15)
				)
				(justify mirror)
			)
		)
		(property "MPN" "CC0201KRX6S5BB104"
			(at 81.625 253.375 0)
			(layer "B.Fab")
			(hide yes)
			(effects
				(font
					(size 1 1)
					(thickness 0.15)
				)
				(justify mirror)
			)
		)
		(property "Manufacturer" "Yaego"
			(at 81.625 253.375 0)
			(layer "B.Fab")
			(hide yes)
			(effects
				(font
					(size 1 1)
					(thickness 0.15)
				)
				(justify mirror)
			)
		)
		(property "Val" "100n"
			(at 81.625 253.375 0)
			(layer "B.Fab")
			(hide yes)
			(effects
				(font
					(size 1 1)
					(thickness 0.15)
				)
				(justify mirror)
			)
		)
		(property "Voltage" ""
			(at 81.625 253.375 0)
			(layer "B.Fab")
			(hide yes)
			(effects
				(font
					(size 1 1)
					(thickness 0.15)
				)
				(justify mirror)
			)
		)
		(sheetname "FPGA power")
		(sheetfile "fpga-power.kicad_sch")
		(attr smd)
		(fp_rect
			(start -0.72 0.38)
			(end 0.72 -0.38)
			(stroke
				(width 0.05)
				(type solid)
			)
			(fill no)
			(layer "B.CrtYd")
		)
		(fp_rect
			(start 0.3 -0.15)
			(end -0.301 0.149)
			(stroke
				(width 0.15)
				(type solid)
			)
			(fill no)
			(layer "B.Fab")
		)
		(pad "" smd roundrect
			(at -0.349 0.002 270)
			(size 0.318 0.36)
			(layers "B.Paste")
			(roundrect_rratio 0.25)
		)
		(pad "" smd roundrect
			(at 0.341 0.002 270)
			(size 0.318 0.36)
			(layers "B.Paste")
			(roundrect_rratio 0.25)
		)
		(pad "1" smd roundrect
			(at -0.321 0.002 270)
			(size 0.46 0.4)
			(layers "B.Cu" "B.Mask")
			(roundrect_rratio 0.25)
			(net 66 "VDDQ")
			(pintype "passive")
		)
		(pad "2" smd roundrect
			(at 0.32 0.002 270)
			(size 0.46 0.4)
			(layers "B.Cu" "B.Mask")
			(roundrect_rratio 0.25)
			(net 5 "GND")
			(pintype "passive")
		)
	)
	(footprint "antmicro-footprints:C_0201"
		(layer "B.Cu")
		(at 167.5 100.625)
		(descr "Capacitor SMD 0201")
		(tags "capacitor SMD 0201")
		(property "Reference" "C78"
			(at 0.85 -0.275 180)
			(layer "B.SilkS")
			(effects
				(font
					(size 0.7 0.7)
					(thickness 0.15)
				)
				(justify left bottom mirror)
			)
		)
		(property "Value" "C_100n_0201"
			(at 0 -1.4 180)
			(layer "B.Fab")
			(effects
				(font
					(size 0.7 0.7)
					(thickness 0.15)
				)
				(justify left bottom mirror)
			)
		)
		(property "Description" " "
			(at 0 0 0)
			(layer "F.Fab")
			(hide yes)
			(effects
				(font
					(size 1.27 1.27)
					(thickness 0.15)
				)
			)
		)
		(property "Author" "Antmicro"
			(at 0 0 0)
			(layer "B.Fab")
			(hide yes)
			(effects
				(font
					(size 1 1)
					(thickness 0.15)
				)
				(justify mirror)
			)
		)
		(property "Dielectric" ""
			(at 0 0 0)
			(layer "B.Fab")
			(hide yes)
			(effects
				(font
					(size 1 1)
					(thickness 0.15)
				)
				(justify mirror)
			)
		)
		(property "License" "Apache-2.0"
			(at 0 0 0)
			(layer "B.Fab")
			(hide yes)
			(effects
				(font
					(size 1 1)
					(thickness 0.15)
				)
				(justify mirror)
			)
		)
		(property "MPN" "CC0201KRX6S5BB104"
			(at 0 0 0)
			(layer "B.Fab")
			(hide yes)
			(effects
				(font
					(size 1 1)
					(thickness 0.15)
				)
				(justify mirror)
			)
		)
		(property "Manufacturer" "Yaego"
			(at 0 0 0)
			(layer "B.Fab")
			(hide yes)
			(effects
				(font
					(size 1 1)
					(thickness 0.15)
				)
				(justify mirror)
			)
		)
		(property "Val" "100n"
			(at 0 0 0)
			(layer "B.Fab")
			(hide yes)
			(effects
				(font
					(size 1 1)
					(thickness 0.15)
				)
				(justify mirror)
			)
		)
		(property "Voltage" ""
			(at 0 0 0)
			(layer "B.Fab")
			(hide yes)
			(effects
				(font
					(size 1 1)
					(thickness 0.15)
				)
				(justify mirror)
			)
		)
		(sheetname "FPGA power")
		(sheetfile "fpga-power.kicad_sch")
		(attr smd)
		(fp_rect
			(start -0.72 0.38)
			(end 0.72 -0.38)
			(stroke
				(width 0.05)
				(type solid)
			)
			(fill no)
			(layer "B.CrtYd")
		)
		(fp_rect
			(start 0.3 -0.15)
			(end -0.301 0.149)
			(stroke
				(width 0.15)
				(type solid)
			)
			(fill no)
			(layer "B.Fab")
		)
		(pad "" smd roundrect
			(at -0.349 0.002)
			(size 0.318 0.36)
			(layers "B.Paste")
			(roundrect_rratio 0.25)
		)
		(pad "" smd roundrect
			(at 0.341 0.002)
			(size 0.318 0.36)
			(layers "B.Paste")
			(roundrect_rratio 0.25)
		)
		(pad "1" smd roundrect
			(at -0.321 0.002)
			(size 0.46 0.4)
			(layers "B.Cu" "B.Mask")
			(roundrect_rratio 0.25)
			(net 465 "1V0_SYS")
			(pintype "passive")
		)
		(pad "2" smd roundrect
			(at 0.32 0.002)
			(size 0.46 0.4)
			(layers "B.Cu" "B.Mask")
			(roundrect_rratio 0.25)
			(net 5 "GND")
			(pintype "passive")
		)
	)
	(footprint "antmicro-footprints:R_0402_1005Metric"
		(layer "B.Cu")
		(at 168.822 115.745757 180)
		(descr "Resistor SMD 0402")
		(tags "resistor SMD 0402")
		(property "Reference" "R53"
			(at -2.978 -0.454243 0)
			(layer "B.SilkS")
			(effects
				(font
					(size 0.7 0.7)
					(thickness 0.15)
				)
				(justify left bottom mirror)
			)
		)
		(property "Value" "R_2k2_0402"
			(at 0 -1.4 0)
			(layer "B.Fab")
			(effects
				(font
					(size 0.7 0.7)
					(thickness 0.15)
				)
				(justify left bottom mirror)
			)
		)
		(property "Description" "2k2 resistor in 0402 package with 1% tolerance"
			(at 0 0 180)
			(layer "F.Fab")
			(hide yes)
			(effects
				(font
					(size 1.27 1.27)
					(thickness 0.15)
				)
			)
		)
		(property "Author" "Antmicro"
			(at 337.644 231.491514 0)
			(layer "B.Fab")
			(hide yes)
			(effects
				(font
					(size 1 1)
					(thickness 0.15)
				)
				(justify mirror)
			)
		)
		(property "License" "Apache-2.0"
			(at 337.644 231.491514 0)
			(layer "B.Fab")
			(hide yes)
			(effects
				(font
					(size 1 1)
					(thickness 0.15)
				)
				(justify mirror)
			)
		)
		(property "MPN" "CR0402-FX-2201GLF"
			(at 337.644 231.491514 0)
			(layer "B.Fab")
			(hide yes)
			(effects
				(font
					(size 1 1)
					(thickness 0.15)
				)
				(justify mirror)
			)
		)
		(property "Manufacturer" "Bourns"
			(at 337.644 231.491514 0)
			(layer "B.Fab")
			(hide yes)
			(effects
				(font
					(size 1 1)
					(thickness 0.15)
				)
				(justify mirror)
			)
		)
		(property "Tolerance" "1%"
			(at 337.644 231.491514 0)
			(layer "B.Fab")
			(hide yes)
			(effects
				(font
					(size 1 1)
					(thickness 0.15)
				)
				(justify mirror)
			)
		)
		(property "Val" "2k2"
			(at 337.644 231.491514 0)
			(layer "B.Fab")
			(hide yes)
			(effects
				(font
					(size 1 1)
					(thickness 0.15)
				)
				(justify mirror)
			)
		)
		(sheetname "Config SPI flash")
		(sheetfile "config-spi.kicad_sch")
		(attr smd)
		(fp_rect
			(start -0.93 0.47)
			(end 0.93 -0.47)
			(stroke
				(width 0.05)
				(type solid)
			)
			(fill no)
			(layer "B.CrtYd")
		)
		(fp_rect
			(start -0.5 0.25)
			(end 0.5 -0.25)
			(stroke
				(width 0.15)
				(type solid)
			)
			(fill no)
			(layer "B.Fab")
		)
		(pad "1" smd roundrect
			(at -0.485 0 180)
			(size 0.59 0.64)
			(layers "B.Cu" "B.Mask" "B.Paste")
			(roundrect_rratio 0.25)
			(net 459 "3V3_SYS")
			(pintype "passive")
		)
		(pad "2" smd roundrect
			(at 0.485 0 180)
			(size 0.59 0.64)
			(layers "B.Cu" "B.Mask" "B.Paste")
			(roundrect_rratio 0.25)
			(net 212 "FCS_B")
			(pintype "passive")
		)
	)
	(footprint "antmicro-footprints:C_0402_1005Metric"
		(layer "B.Cu")
		(at 174.5 92 90)
		(descr "Capacitor SMD 0402")
		(tags "capacitor SMD 0402")
		(property "Reference" "C28"
			(at 3.6 1 270)
			(layer "B.SilkS")
			(effects
				(font
					(size 0.7 0.7)
					(thickness 0.15)
				)
				(justify left bottom mirror)
			)
		)
		(property "Value" "C_4u7_0402"
			(at 0 -1.4 270)
			(layer "B.Fab")
			(effects
				(font
					(size 0.7 0.7)
					(thickness 0.15)
				)
				(justify left bottom mirror)
			)
		)
		(property "Description" " "
			(at 0 0 90)
			(layer "F.Fab")
			(hide yes)
			(effects
				(font
					(size 1.27 1.27)
					(thickness 0.15)
				)
			)
		)
		(property "Author" "Antmicro"
			(at 266.5 -82.5 0)
			(layer "B.Fab")
			(hide yes)
			(effects
				(font
					(size 1 1)
					(thickness 0.15)
				)
				(justify mirror)
			)
		)
		(property "Dielectric" ""
			(at 266.5 -82.5 0)
			(layer "B.Fab")
			(hide yes)
			(effects
				(font
					(size 1 1)
					(thickness 0.15)
				)
				(justify mirror)
			)
		)
		(property "License" "Apache-2.0"
			(at 266.5 -82.5 0)
			(layer "B.Fab")
			(hide yes)
			(effects
				(font
					(size 1 1)
					(thickness 0.15)
				)
				(justify mirror)
			)
		)
		(property "MPN" "GRM155R61A475MEAAD"
			(at 266.5 -82.5 0)
			(layer "B.Fab")
			(hide yes)
			(effects
				(font
					(size 1 1)
					(thickness 0.15)
				)
				(justify mirror)
			)
		)
		(property "Manufacturer" "Murata"
			(at 266.5 -82.5 0)
			(layer "B.Fab")
			(hide yes)
			(effects
				(font
					(size 1 1)
					(thickness 0.15)
				)
				(justify mirror)
			)
		)
		(property "Val" "4u7"
			(at 266.5 -82.5 0)
			(layer "B.Fab")
			(hide yes)
			(effects
				(font
					(size 1 1)
					(thickness 0.15)
				)
				(justify mirror)
			)
		)
		(property "Voltage" ""
			(at 266.5 -82.5 0)
			(layer "B.Fab")
			(hide yes)
			(effects
				(font
					(size 1 1)
					(thickness 0.15)
				)
				(justify mirror)
			)
		)
		(sheetname "FPGA power")
		(sheetfile "fpga-power.kicad_sch")
		(attr smd)
		(fp_rect
			(start -0.94 0.47)
			(end 0.94 -0.47)
			(stroke
				(width 0.05)
				(type solid)
			)
			(fill no)
			(layer "B.CrtYd")
		)
		(fp_rect
			(start -0.499 0.249)
			(end 0.499 -0.249)
			(stroke
				(width 0.15)
				(type solid)
			)
			(fill no)
			(layer "B.Fab")
		)
		(pad "1" smd roundrect
			(at -0.484 0 90)
			(size 0.59 0.64)
			(layers "B.Cu" "B.Mask" "B.Paste")
			(roundrect_rratio 0.25)
			(net 459 "3V3_SYS")
			(pintype "passive")
		)
		(pad "2" smd roundrect
			(at 0.484 0 90)
			(size 0.59 0.64)
			(layers "B.Cu" "B.Mask" "B.Paste")
			(roundrect_rratio 0.25)
			(net 5 "GND")
			(pintype "passive")
		)
	)
	(footprint "antmicro-footprints:C_0402_1005Metric"
		(layer "B.Cu")
		(at 176 91.5 180)
		(descr "Capacitor SMD 0402")
		(tags "capacitor SMD 0402")
		(property "Reference" "C32"
			(at -2.9 -0.4 0)
			(layer "B.SilkS")
			(effects
				(font
					(size 0.7 0.7)
					(thickness 0.15)
				)
				(justify left bottom mirror)
			)
		)
		(property "Value" "C_4u7_0402"
			(at 0 -1.4 0)
			(layer "B.Fab")
			(effects
				(font
					(size 0.7 0.7)
					(thickness 0.15)
				)
				(justify left bottom mirror)
			)
		)
		(property "Description" " "
			(at 0 0 180)
			(layer "F.Fab")
			(hide yes)
			(effects
				(font
					(size 1.27 1.27)
					(thickness 0.15)
				)
			)
		)
		(property "Author" "Antmicro"
			(at 352 183 0)
			(layer "B.Fab")
			(hide yes)
			(effects
				(font
					(size 1 1)
					(thickness 0.15)
				)
				(justify mirror)
			)
		)
		(property "Dielectric" ""
			(at 352 183 0)
			(layer "B.Fab")
			(hide yes)
			(effects
				(font
					(size 1 1)
					(thickness 0.15)
				)
				(justify mirror)
			)
		)
		(property "License" "Apache-2.0"
			(at 352 183 0)
			(layer "B.Fab")
			(hide yes)
			(effects
				(font
					(size 1 1)
					(thickness 0.15)
				)
				(justify mirror)
			)
		)
		(property "MPN" "GRM155R61A475MEAAD"
			(at 352 183 0)
			(layer "B.Fab")
			(hide yes)
			(effects
				(font
					(size 1 1)
					(thickness 0.15)
				)
				(justify mirror)
			)
		)
		(property "Manufacturer" "Murata"
			(at 352 183 0)
			(layer "B.Fab")
			(hide yes)
			(effects
				(font
					(size 1 1)
					(thickness 0.15)
				)
				(justify mirror)
			)
		)
		(property "Val" "4u7"
			(at 352 183 0)
			(layer "B.Fab")
			(hide yes)
			(effects
				(font
					(size 1 1)
					(thickness 0.15)
				)
				(justify mirror)
			)
		)
		(property "Voltage" ""
			(at 352 183 0)
			(layer "B.Fab")
			(hide yes)
			(effects
				(font
					(size 1 1)
					(thickness 0.15)
				)
				(justify mirror)
			)
		)
		(sheetname "FPGA power")
		(sheetfile "fpga-power.kicad_sch")
		(attr smd)
		(fp_rect
			(start -0.94 0.47)
			(end 0.94 -0.47)
			(stroke
				(width 0.05)
				(type solid)
			)
			(fill no)
			(layer "B.CrtYd")
		)
		(fp_rect
			(start -0.499 0.249)
			(end 0.499 -0.249)
			(stroke
				(width 0.15)
				(type solid)
			)
			(fill no)
			(layer "B.Fab")
		)
		(pad "1" smd roundrect
			(at -0.484 0 180)
			(size 0.59 0.64)
			(layers "B.Cu" "B.Mask" "B.Paste")
			(roundrect_rratio 0.25)
			(net 459 "3V3_SYS")
			(pintype "passive")
		)
		(pad "2" smd roundrect
			(at 0.484 0 180)
			(size 0.59 0.64)
			(layers "B.Cu" "B.Mask" "B.Paste")
			(roundrect_rratio 0.25)
			(net 5 "GND")
			(pintype "passive")
		)
	)
	(footprint "antmicro-footprints:C_0402_1005Metric"
		(layer "B.Cu")
		(at 176.875 94.75 180)
		(descr "Capacitor SMD 0402")
		(tags "capacitor SMD 0402")
		(property "Reference" "C36"
			(at -1.125 0.45 0)
			(layer "B.SilkS")
			(effects
				(font
					(size 0.7 0.7)
					(thickness 0.15)
				)
				(justify left bottom mirror)
			)
		)
		(property "Value" "C_4u7_0402"
			(at 0 -1.4 0)
			(layer "B.Fab")
			(effects
				(font
					(size 0.7 0.7)
					(thickness 0.15)
				)
				(justify left bottom mirror)
			)
		)
		(property "Description" " "
			(at 0 0 180)
			(layer "F.Fab")
			(hide yes)
			(effects
				(font
					(size 1.27 1.27)
					(thickness 0.15)
				)
			)
		)
		(property "Author" "Antmicro"
			(at 353.75 189.5 0)
			(layer "B.Fab")
			(hide yes)
			(effects
				(font
					(size 1 1)
					(thickness 0.15)
				)
				(justify mirror)
			)
		)
		(property "Dielectric" ""
			(at 353.75 189.5 0)
			(layer "B.Fab")
			(hide yes)
			(effects
				(font
					(size 1 1)
					(thickness 0.15)
				)
				(justify mirror)
			)
		)
		(property "License" "Apache-2.0"
			(at 353.75 189.5 0)
			(layer "B.Fab")
			(hide yes)
			(effects
				(font
					(size 1 1)
					(thickness 0.15)
				)
				(justify mirror)
			)
		)
		(property "MPN" "GRM155R61A475MEAAD"
			(at 353.75 189.5 0)
			(layer "B.Fab")
			(hide yes)
			(effects
				(font
					(size 1 1)
					(thickness 0.15)
				)
				(justify mirror)
			)
		)
		(property "Manufacturer" "Murata"
			(at 353.75 189.5 0)
			(layer "B.Fab")
			(hide yes)
			(effects
				(font
					(size 1 1)
					(thickness 0.15)
				)
				(justify mirror)
			)
		)
		(property "Val" "4u7"
			(at 353.75 189.5 0)
			(layer "B.Fab")
			(hide yes)
			(effects
				(font
					(size 1 1)
					(thickness 0.15)
				)
				(justify mirror)
			)
		)
		(property "Voltage" ""
			(at 353.75 189.5 0)
			(layer "B.Fab")
			(hide yes)
			(effects
				(font
					(size 1 1)
					(thickness 0.15)
				)
				(justify mirror)
			)
		)
		(sheetname "FPGA power")
		(sheetfile "fpga-power.kicad_sch")
		(attr smd)
		(fp_rect
			(start -0.94 0.47)
			(end 0.94 -0.47)
			(stroke
				(width 0.05)
				(type solid)
			)
			(fill no)
			(layer "B.CrtYd")
		)
		(fp_rect
			(start -0.499 0.249)
			(end 0.499 -0.249)
			(stroke
				(width 0.15)
				(type solid)
			)
			(fill no)
			(layer "B.Fab")
		)
		(pad "1" smd roundrect
			(at -0.484 0 180)
			(size 0.59 0.64)
			(layers "B.Cu" "B.Mask" "B.Paste")
			(roundrect_rratio 0.25)
			(net 459 "3V3_SYS")
			(pintype "passive")
		)
		(pad "2" smd roundrect
			(at 0.484 0 180)
			(size 0.59 0.64)
			(layers "B.Cu" "B.Mask" "B.Paste")
			(roundrect_rratio 0.25)
			(net 5 "GND")
			(pintype "passive")
		)
	)
	(footprint "antmicro-footprints:C_0402_1005Metric"
		(layer "B.Cu")
		(at 177.5 99.125 180)
		(descr "Capacitor SMD 0402")
		(tags "capacitor SMD 0402")
		(property "Reference" "C40"
			(at -1.1 -1.275 0)
			(layer "B.SilkS")
			(effects
				(font
					(size 0.7 0.7)
					(thickness 0.15)
				)
				(justify left bottom mirror)
			)
		)
		(property "Value" "C_4u7_0402"
			(at 0 -1.4 0)
			(layer "B.Fab")
			(effects
				(font
					(size 0.7 0.7)
					(thickness 0.15)
				)
				(justify left bottom mirror)
			)
		)
		(property "Description" " "
			(at 0 0 180)
			(layer "F.Fab")
			(hide yes)
			(effects
				(font
					(size 1.27 1.27)
					(thickness 0.15)
				)
			)
		)
		(property "Author" "Antmicro"
			(at 355 198.25 0)
			(layer "B.Fab")
			(hide yes)
			(effects
				(font
					(size 1 1)
					(thickness 0.15)
				)
				(justify mirror)
			)
		)
		(property "Dielectric" ""
			(at 355 198.25 0)
			(layer "B.Fab")
			(hide yes)
			(effects
				(font
					(size 1 1)
					(thickness 0.15)
				)
				(justify mirror)
			)
		)
		(property "License" "Apache-2.0"
			(at 355 198.25 0)
			(layer "B.Fab")
			(hide yes)
			(effects
				(font
					(size 1 1)
					(thickness 0.15)
				)
				(justify mirror)
			)
		)
		(property "MPN" "GRM155R61A475MEAAD"
			(at 355 198.25 0)
			(layer "B.Fab")
			(hide yes)
			(effects
				(font
					(size 1 1)
					(thickness 0.15)
				)
				(justify mirror)
			)
		)
		(property "Manufacturer" "Murata"
			(at 355 198.25 0)
			(layer "B.Fab")
			(hide yes)
			(effects
				(font
					(size 1 1)
					(thickness 0.15)
				)
				(justify mirror)
			)
		)
		(property "Val" "4u7"
			(at 355 198.25 0)
			(layer "B.Fab")
			(hide yes)
			(effects
				(font
					(size 1 1)
					(thickness 0.15)
				)
				(justify mirror)
			)
		)
		(property "Voltage" ""
			(at 355 198.25 0)
			(layer "B.Fab")
			(hide yes)
			(effects
				(font
					(size 1 1)
					(thickness 0.15)
				)
				(justify mirror)
			)
		)
		(sheetname "FPGA power")
		(sheetfile "fpga-power.kicad_sch")
		(attr smd)
		(fp_rect
			(start -0.94 0.47)
			(end 0.94 -0.47)
			(stroke
				(width 0.05)
				(type solid)
			)
			(fill no)
			(layer "B.CrtYd")
		)
		(fp_rect
			(start -0.499 0.249)
			(end 0.499 -0.249)
			(stroke
				(width 0.15)
				(type solid)
			)
			(fill no)
			(layer "B.Fab")
		)
		(pad "1" smd roundrect
			(at -0.484 0 180)
			(size 0.59 0.64)
			(layers "B.Cu" "B.Mask" "B.Paste")
			(roundrect_rratio 0.25)
			(net 459 "3V3_SYS")
			(pintype "passive")
		)
		(pad "2" smd roundrect
			(at 0.484 0 180)
			(size 0.59 0.64)
			(layers "B.Cu" "B.Mask" "B.Paste")
			(roundrect_rratio 0.25)
			(net 5 "GND")
			(pintype "passive")
		)
	)
	(footprint "antmicro-footprints:C_0402_1005Metric"
		(layer "B.Cu")
		(at 177.036328 101.997157 90)
		(descr "Capacitor SMD 0402")
		(tags "capacitor SMD 0402")
		(property "Reference" "C46"
			(at 1.097157 1.263672 270)
			(layer "B.SilkS")
			(effects
				(font
					(size 0.7 0.7)
					(thickness 0.15)
				)
				(justify left bottom mirror)
			)
		)
		(property "Value" "C_4u7_0402"
			(at 0 -1.4 270)
			(layer "B.Fab")
			(effects
				(font
					(size 0.7 0.7)
					(thickness 0.15)
				)
				(justify left bottom mirror)
			)
		)
		(property "Description" " "
			(at 0 0 90)
			(layer "F.Fab")
			(hide yes)
			(effects
				(font
					(size 1.27 1.27)
					(thickness 0.15)
				)
			)
		)
		(property "Author" "Antmicro"
			(at 279.033485 -75.039171 0)
			(layer "B.Fab")
			(hide yes)
			(effects
				(font
					(size 1 1)
					(thickness 0.15)
				)
				(justify mirror)
			)
		)
		(property "Dielectric" ""
			(at 279.033485 -75.039171 0)
			(layer "B.Fab")
			(hide yes)
			(effects
				(font
					(size 1 1)
					(thickness 0.15)
				)
				(justify mirror)
			)
		)
		(property "License" "Apache-2.0"
			(at 279.033485 -75.039171 0)
			(layer "B.Fab")
			(hide yes)
			(effects
				(font
					(size 1 1)
					(thickness 0.15)
				)
				(justify mirror)
			)
		)
		(property "MPN" "GRM155R61A475MEAAD"
			(at 279.033485 -75.039171 0)
			(layer "B.Fab")
			(hide yes)
			(effects
				(font
					(size 1 1)
					(thickness 0.15)
				)
				(justify mirror)
			)
		)
		(property "Manufacturer" "Murata"
			(at 279.033485 -75.039171 0)
			(layer "B.Fab")
			(hide yes)
			(effects
				(font
					(size 1 1)
					(thickness 0.15)
				)
				(justify mirror)
			)
		)
		(property "Val" "4u7"
			(at 279.033485 -75.039171 0)
			(layer "B.Fab")
			(hide yes)
			(effects
				(font
					(size 1 1)
					(thickness 0.15)
				)
				(justify mirror)
			)
		)
		(property "Voltage" ""
			(at 279.033485 -75.039171 0)
			(layer "B.Fab")
			(hide yes)
			(effects
				(font
					(size 1 1)
					(thickness 0.15)
				)
				(justify mirror)
			)
		)
		(sheetname "FPGA power")
		(sheetfile "fpga-power.kicad_sch")
		(attr smd)
		(fp_rect
			(start -0.94 0.47)
			(end 0.94 -0.47)
			(stroke
				(width 0.05)
				(type solid)
			)
			(fill no)
			(layer "B.CrtYd")
		)
		(fp_rect
			(start -0.499 0.249)
			(end 0.499 -0.249)
			(stroke
				(width 0.15)
				(type solid)
			)
			(fill no)
			(layer "B.Fab")
		)
		(pad "1" smd roundrect
			(at -0.484 0 90)
			(size 0.59 0.64)
			(layers "B.Cu" "B.Mask" "B.Paste")
			(roundrect_rratio 0.25)
			(net 459 "3V3_SYS")
			(pintype "passive")
		)
		(pad "2" smd roundrect
			(at 0.484 0 90)
			(size 0.59 0.64)
			(layers "B.Cu" "B.Mask" "B.Paste")
			(roundrect_rratio 0.25)
			(net 5 "GND")
			(pintype "passive")
		)
	)
	(footprint "antmicro-footprints:C_0402_1005Metric"
		(layer "B.Cu")
		(at 174.5 99.875 180)
		(descr "Capacitor SMD 0402")
		(tags "capacitor SMD 0402")
		(property "Reference" "C50"
			(at -1.1 -1.225 0)
			(layer "B.SilkS")
			(effects
				(font
					(size 0.7 0.7)
					(thickness 0.15)
				)
				(justify left bottom mirror)
			)
		)
		(property "Value" "C_4u7_0402"
			(at 0 -1.4 0)
			(layer "B.Fab")
			(effects
				(font
					(size 0.7 0.7)
					(thickness 0.15)
				)
				(justify left bottom mirror)
			)
		)
		(property "Description" " "
			(at 0 0 180)
			(layer "F.Fab")
			(hide yes)
			(effects
				(font
					(size 1.27 1.27)
					(thickness 0.15)
				)
			)
		)
		(property "Author" "Antmicro"
			(at 349 199.75 0)
			(layer "B.Fab")
			(hide yes)
			(effects
				(font
					(size 1 1)
					(thickness 0.15)
				)
				(justify mirror)
			)
		)
		(property "Dielectric" ""
			(at 349 199.75 0)
			(layer "B.Fab")
			(hide yes)
			(effects
				(font
					(size 1 1)
					(thickness 0.15)
				)
				(justify mirror)
			)
		)
		(property "License" "Apache-2.0"
			(at 349 199.75 0)
			(layer "B.Fab")
			(hide yes)
			(effects
				(font
					(size 1 1)
					(thickness 0.15)
				)
				(justify mirror)
			)
		)
		(property "MPN" "GRM155R61A475MEAAD"
			(at 349 199.75 0)
			(layer "B.Fab")
			(hide yes)
			(effects
				(font
					(size 1 1)
					(thickness 0.15)
				)
				(justify mirror)
			)
		)
		(property "Manufacturer" "Murata"
			(at 349 199.75 0)
			(layer "B.Fab")
			(hide yes)
			(effects
				(font
					(size 1 1)
					(thickness 0.15)
				)
				(justify mirror)
			)
		)
		(property "Val" "4u7"
			(at 349 199.75 0)
			(layer "B.Fab")
			(hide yes)
			(effects
				(font
					(size 1 1)
					(thickness 0.15)
				)
				(justify mirror)
			)
		)
		(property "Voltage" ""
			(at 349 199.75 0)
			(layer "B.Fab")
			(hide yes)
			(effects
				(font
					(size 1 1)
					(thickness 0.15)
				)
				(justify mirror)
			)
		)
		(sheetname "FPGA power")
		(sheetfile "fpga-power.kicad_sch")
		(attr smd)
		(fp_rect
			(start -0.94 0.47)
			(end 0.94 -0.47)
			(stroke
				(width 0.05)
				(type solid)
			)
			(fill no)
			(layer "B.CrtYd")
		)
		(fp_rect
			(start -0.499 0.249)
			(end 0.499 -0.249)
			(stroke
				(width 0.15)
				(type solid)
			)
			(fill no)
			(layer "B.Fab")
		)
		(pad "1" smd roundrect
			(at -0.484 0 180)
			(size 0.59 0.64)
			(layers "B.Cu" "B.Mask" "B.Paste")
			(roundrect_rratio 0.25)
			(net 459 "3V3_SYS")
			(pintype "passive")
		)
		(pad "2" smd roundrect
			(at 0.484 0 180)
			(size 0.59 0.64)
			(layers "B.Cu" "B.Mask" "B.Paste")
			(roundrect_rratio 0.25)
			(net 5 "GND")
			(pintype "passive")
		)
	)
	(footprint "antmicro-footprints:C_0402_1005Metric"
		(layer "B.Cu")
		(at 173.5 101.75)
		(descr "Capacitor SMD 0402")
		(tags "capacitor SMD 0402")
		(property "Reference" "C54"
			(at 3 0.45 180)
			(layer "B.SilkS")
			(effects
				(font
					(size 0.7 0.7)
					(thickness 0.15)
				)
				(justify left bottom mirror)
			)
		)
		(property "Value" "C_4u7_0402"
			(at 0 -1.4 180)
			(layer "B.Fab")
			(effects
				(font
					(size 0.7 0.7)
					(thickness 0.15)
				)
				(justify left bottom mirror)
			)
		)
		(property "Description" " "
			(at 0 0 0)
			(layer "F.Fab")
			(hide yes)
			(effects
				(font
					(size 1.27 1.27)
					(thickness 0.15)
				)
			)
		)
		(property "Author" "Antmicro"
			(at 0 0 0)
			(layer "B.Fab")
			(hide yes)
			(effects
				(font
					(size 1 1)
					(thickness 0.15)
				)
				(justify mirror)
			)
		)
		(property "Dielectric" ""
			(at 0 0 0)
			(layer "B.Fab")
			(hide yes)
			(effects
				(font
					(size 1 1)
					(thickness 0.15)
				)
				(justify mirror)
			)
		)
		(property "License" "Apache-2.0"
			(at 0 0 0)
			(layer "B.Fab")
			(hide yes)
			(effects
				(font
					(size 1 1)
					(thickness 0.15)
				)
				(justify mirror)
			)
		)
		(property "MPN" "GRM155R61A475MEAAD"
			(at 0 0 0)
			(layer "B.Fab")
			(hide yes)
			(effects
				(font
					(size 1 1)
					(thickness 0.15)
				)
				(justify mirror)
			)
		)
		(property "Manufacturer" "Murata"
			(at 0 0 0)
			(layer "B.Fab")
			(hide yes)
			(effects
				(font
					(size 1 1)
					(thickness 0.15)
				)
				(justify mirror)
			)
		)
		(property "Val" "4u7"
			(at 0 0 0)
			(layer "B.Fab")
			(hide yes)
			(effects
				(font
					(size 1 1)
					(thickness 0.15)
				)
				(justify mirror)
			)
		)
		(property "Voltage" ""
			(at 0 0 0)
			(layer "B.Fab")
			(hide yes)
			(effects
				(font
					(size 1 1)
					(thickness 0.15)
				)
				(justify mirror)
			)
		)
		(sheetname "FPGA power")
		(sheetfile "fpga-power.kicad_sch")
		(attr smd)
		(fp_rect
			(start -0.94 0.47)
			(end 0.94 -0.47)
			(stroke
				(width 0.05)
				(type solid)
			)
			(fill no)
			(layer "B.CrtYd")
		)
		(fp_rect
			(start -0.499 0.249)
			(end 0.499 -0.249)
			(stroke
				(width 0.15)
				(type solid)
			)
			(fill no)
			(layer "B.Fab")
		)
		(pad "1" smd roundrect
			(at -0.484 0)
			(size 0.59 0.64)
			(layers "B.Cu" "B.Mask" "B.Paste")
			(roundrect_rratio 0.25)
			(net 459 "3V3_SYS")
			(pintype "passive")
		)
		(pad "2" smd roundrect
			(at 0.484 0)
			(size 0.59 0.64)
			(layers "B.Cu" "B.Mask" "B.Paste")
			(roundrect_rratio 0.25)
			(net 5 "GND")
			(pintype "passive")
		)
	)
	(footprint "antmicro-footprints:C_0402_1005Metric"
		(layer "B.Cu")
		(at 174.5 103.125)
		(descr "Capacitor SMD 0402")
		(tags "capacitor SMD 0402")
		(property "Reference" "C58"
			(at 1.1 1.275 180)
			(layer "B.SilkS")
			(effects
				(font
					(size 0.7 0.7)
					(thickness 0.15)
				)
				(justify left bottom mirror)
			)
		)
		(property "Value" "C_4u7_0402"
			(at 0 -1.4 180)
			(layer "B.Fab")
			(effects
				(font
					(size 0.7 0.7)
					(thickness 0.15)
				)
				(justify left bottom mirror)
			)
		)
		(property "Description" " "
			(at 0 0 0)
			(layer "F.Fab")
			(hide yes)
			(effects
				(font
					(size 1.27 1.27)
					(thickness 0.15)
				)
			)
		)
		(property "Author" "Antmicro"
			(at 0 0 0)
			(layer "B.Fab")
			(hide yes)
			(effects
				(font
					(size 1 1)
					(thickness 0.15)
				)
				(justify mirror)
			)
		)
		(property "Dielectric" ""
			(at 0 0 0)
			(layer "B.Fab")
			(hide yes)
			(effects
				(font
					(size 1 1)
					(thickness 0.15)
				)
				(justify mirror)
			)
		)
		(property "License" "Apache-2.0"
			(at 0 0 0)
			(layer "B.Fab")
			(hide yes)
			(effects
				(font
					(size 1 1)
					(thickness 0.15)
				)
				(justify mirror)
			)
		)
		(property "MPN" "GRM155R61A475MEAAD"
			(at 0 0 0)
			(layer "B.Fab")
			(hide yes)
			(effects
				(font
					(size 1 1)
					(thickness 0.15)
				)
				(justify mirror)
			)
		)
		(property "Manufacturer" "Murata"
			(at 0 0 0)
			(layer "B.Fab")
			(hide yes)
			(effects
				(font
					(size 1 1)
					(thickness 0.15)
				)
				(justify mirror)
			)
		)
		(property "Val" "4u7"
			(at 0 0 0)
			(layer "B.Fab")
			(hide yes)
			(effects
				(font
					(size 1 1)
					(thickness 0.15)
				)
				(justify mirror)
			)
		)
		(property "Voltage" ""
			(at 0 0 0)
			(layer "B.Fab")
			(hide yes)
			(effects
				(font
					(size 1 1)
					(thickness 0.15)
				)
				(justify mirror)
			)
		)
		(sheetname "FPGA power")
		(sheetfile "fpga-power.kicad_sch")
		(attr smd)
		(fp_rect
			(start -0.94 0.47)
			(end 0.94 -0.47)
			(stroke
				(width 0.05)
				(type solid)
			)
			(fill no)
			(layer "B.CrtYd")
		)
		(fp_rect
			(start -0.499 0.249)
			(end 0.499 -0.249)
			(stroke
				(width 0.15)
				(type solid)
			)
			(fill no)
			(layer "B.Fab")
		)
		(pad "1" smd roundrect
			(at -0.484 0)
			(size 0.59 0.64)
			(layers "B.Cu" "B.Mask" "B.Paste")
			(roundrect_rratio 0.25)
			(net 459 "3V3_SYS")
			(pintype "passive")
		)
		(pad "2" smd roundrect
			(at 0.484 0)
			(size 0.59 0.64)
			(layers "B.Cu" "B.Mask" "B.Paste")
			(roundrect_rratio 0.25)
			(net 5 "GND")
			(pintype "passive")
		)
	)
	(footprint "antmicro-footprints:C_0402_1005Metric"
		(layer "B.Cu")
		(at 170.5 102.75)
		(descr "Capacitor SMD 0402")
		(tags "capacitor SMD 0402")
		(property "Reference" "C64"
			(at 1.1 1.25 180)
			(layer "B.SilkS")
			(effects
				(font
					(size 0.7 0.7)
					(thickness 0.15)
				)
				(justify left bottom mirror)
			)
		)
		(property "Value" "C_4u7_0402"
			(at 0 -1.4 180)
			(layer "B.Fab")
			(effects
				(font
					(size 0.7 0.7)
					(thickness 0.15)
				)
				(justify left bottom mirror)
			)
		)
		(property "Description" " "
			(at 0 0 0)
			(layer "F.Fab")
			(hide yes)
			(effects
				(font
					(size 1.27 1.27)
					(thickness 0.15)
				)
			)
		)
		(property "Author" "Antmicro"
			(at 0 0 0)
			(layer "B.Fab")
			(hide yes)
			(effects
				(font
					(size 1 1)
					(thickness 0.15)
				)
				(justify mirror)
			)
		)
		(property "Dielectric" ""
			(at 0 0 0)
			(layer "B.Fab")
			(hide yes)
			(effects
				(font
					(size 1 1)
					(thickness 0.15)
				)
				(justify mirror)
			)
		)
		(property "License" "Apache-2.0"
			(at 0 0 0)
			(layer "B.Fab")
			(hide yes)
			(effects
				(font
					(size 1 1)
					(thickness 0.15)
				)
				(justify mirror)
			)
		)
		(property "MPN" "GRM155R61A475MEAAD"
			(at 0 0 0)
			(layer "B.Fab")
			(hide yes)
			(effects
				(font
					(size 1 1)
					(thickness 0.15)
				)
				(justify mirror)
			)
		)
		(property "Manufacturer" "Murata"
			(at 0 0 0)
			(layer "B.Fab")
			(hide yes)
			(effects
				(font
					(size 1 1)
					(thickness 0.15)
				)
				(justify mirror)
			)
		)
		(property "Val" "4u7"
			(at 0 0 0)
			(layer "B.Fab")
			(hide yes)
			(effects
				(font
					(size 1 1)
					(thickness 0.15)
				)
				(justify mirror)
			)
		)
		(property "Voltage" ""
			(at 0 0 0)
			(layer "B.Fab")
			(hide yes)
			(effects
				(font
					(size 1 1)
					(thickness 0.15)
				)
				(justify mirror)
			)
		)
		(sheetname "FPGA power")
		(sheetfile "fpga-power.kicad_sch")
		(attr smd)
		(fp_rect
			(start -0.94 0.47)
			(end 0.94 -0.47)
			(stroke
				(width 0.05)
				(type solid)
			)
			(fill no)
			(layer "B.CrtYd")
		)
		(fp_rect
			(start -0.499 0.249)
			(end 0.499 -0.249)
			(stroke
				(width 0.15)
				(type solid)
			)
			(fill no)
			(layer "B.Fab")
		)
		(pad "1" smd roundrect
			(at -0.484 0)
			(size 0.59 0.64)
			(layers "B.Cu" "B.Mask" "B.Paste")
			(roundrect_rratio 0.25)
			(net 459 "3V3_SYS")
			(pintype "passive")
		)
		(pad "2" smd roundrect
			(at 0.484 0)
			(size 0.59 0.64)
			(layers "B.Cu" "B.Mask" "B.Paste")
			(roundrect_rratio 0.25)
			(net 5 "GND")
			(pintype "passive")
		)
	)
	(footprint "antmicro-footprints:C_0402_1005Metric"
		(layer "B.Cu")
		(at 167.5 102.125)
		(descr "Capacitor SMD 0402")
		(tags "capacitor SMD 0402")
		(property "Reference" "C68"
			(at 1.1 1.175 180)
			(layer "B.SilkS")
			(effects
				(font
					(size 0.7 0.7)
					(thickness 0.15)
				)
				(justify left bottom mirror)
			)
		)
		(property "Value" "C_4u7_0402"
			(at 0 -1.4 180)
			(layer "B.Fab")
			(effects
				(font
					(size 0.7 0.7)
					(thickness 0.15)
				)
				(justify left bottom mirror)
			)
		)
		(property "Description" " "
			(at 0 0 0)
			(layer "F.Fab")
			(hide yes)
			(effects
				(font
					(size 1.27 1.27)
					(thickness 0.15)
				)
			)
		)
		(property "Author" "Antmicro"
			(at 0 0 0)
			(layer "B.Fab")
			(hide yes)
			(effects
				(font
					(size 1 1)
					(thickness 0.15)
				)
				(justify mirror)
			)
		)
		(property "Dielectric" ""
			(at 0 0 0)
			(layer "B.Fab")
			(hide yes)
			(effects
				(font
					(size 1 1)
					(thickness 0.15)
				)
				(justify mirror)
			)
		)
		(property "License" "Apache-2.0"
			(at 0 0 0)
			(layer "B.Fab")
			(hide yes)
			(effects
				(font
					(size 1 1)
					(thickness 0.15)
				)
				(justify mirror)
			)
		)
		(property "MPN" "GRM155R61A475MEAAD"
			(at 0 0 0)
			(layer "B.Fab")
			(hide yes)
			(effects
				(font
					(size 1 1)
					(thickness 0.15)
				)
				(justify mirror)
			)
		)
		(property "Manufacturer" "Murata"
			(at 0 0 0)
			(layer "B.Fab")
			(hide yes)
			(effects
				(font
					(size 1 1)
					(thickness 0.15)
				)
				(justify mirror)
			)
		)
		(property "Val" "4u7"
			(at 0 0 0)
			(layer "B.Fab")
			(hide yes)
			(effects
				(font
					(size 1 1)
					(thickness 0.15)
				)
				(justify mirror)
			)
		)
		(property "Voltage" ""
			(at 0 0 0)
			(layer "B.Fab")
			(hide yes)
			(effects
				(font
					(size 1 1)
					(thickness 0.15)
				)
				(justify mirror)
			)
		)
		(sheetname "FPGA power")
		(sheetfile "fpga-power.kicad_sch")
		(attr smd)
		(fp_rect
			(start -0.94 0.47)
			(end 0.94 -0.47)
			(stroke
				(width 0.05)
				(type solid)
			)
			(fill no)
			(layer "B.CrtYd")
		)
		(fp_rect
			(start -0.499 0.249)
			(end 0.499 -0.249)
			(stroke
				(width 0.15)
				(type solid)
			)
			(fill no)
			(layer "B.Fab")
		)
		(pad "1" smd roundrect
			(at -0.484 0)
			(size 0.59 0.64)
			(layers "B.Cu" "B.Mask" "B.Paste")
			(roundrect_rratio 0.25)
			(net 459 "3V3_SYS")
			(pintype "passive")
		)
		(pad "2" smd roundrect
			(at 0.484 0)
			(size 0.59 0.64)
			(layers "B.Cu" "B.Mask" "B.Paste")
			(roundrect_rratio 0.25)
			(net 5 "GND")
			(pintype "passive")
		)
	)
	(footprint "antmicro-footprints:C_0402_1005Metric"
		(layer "B.Cu")
		(at 164.875 102.5 90)
		(descr "Capacitor SMD 0402")
		(tags "capacitor SMD 0402")
		(property "Reference" "C72"
			(at 1.1 -0.475 270)
			(layer "B.SilkS")
			(effects
				(font
					(size 0.7 0.7)
					(thickness 0.15)
				)
				(justify left bottom mirror)
			)
		)
		(property "Value" "C_4u7_0402"
			(at 0 -1.4 270)
			(layer "B.Fab")
			(effects
				(font
					(size 0.7 0.7)
					(thickness 0.15)
				)
				(justify left bottom mirror)
			)
		)
		(property "Description" " "
			(at 0 0 90)
			(layer "F.Fab")
			(hide yes)
			(effects
				(font
					(size 1.27 1.27)
					(thickness 0.15)
				)
			)
		)
		(property "Author" "Antmicro"
			(at 267.375 -62.375 0)
			(layer "B.Fab")
			(hide yes)
			(effects
				(font
					(size 1 1)
					(thickness 0.15)
				)
				(justify mirror)
			)
		)
		(property "Dielectric" ""
			(at 267.375 -62.375 0)
			(layer "B.Fab")
			(hide yes)
			(effects
				(font
					(size 1 1)
					(thickness 0.15)
				)
				(justify mirror)
			)
		)
		(property "License" "Apache-2.0"
			(at 267.375 -62.375 0)
			(layer "B.Fab")
			(hide yes)
			(effects
				(font
					(size 1 1)
					(thickness 0.15)
				)
				(justify mirror)
			)
		)
		(property "MPN" "GRM155R61A475MEAAD"
			(at 267.375 -62.375 0)
			(layer "B.Fab")
			(hide yes)
			(effects
				(font
					(size 1 1)
					(thickness 0.15)
				)
				(justify mirror)
			)
		)
		(property "Manufacturer" "Murata"
			(at 267.375 -62.375 0)
			(layer "B.Fab")
			(hide yes)
			(effects
				(font
					(size 1 1)
					(thickness 0.15)
				)
				(justify mirror)
			)
		)
		(property "Val" "4u7"
			(at 267.375 -62.375 0)
			(layer "B.Fab")
			(hide yes)
			(effects
				(font
					(size 1 1)
					(thickness 0.15)
				)
				(justify mirror)
			)
		)
		(property "Voltage" ""
			(at 267.375 -62.375 0)
			(layer "B.Fab")
			(hide yes)
			(effects
				(font
					(size 1 1)
					(thickness 0.15)
				)
				(justify mirror)
			)
		)
		(sheetname "FPGA power")
		(sheetfile "fpga-power.kicad_sch")
		(attr smd)
		(fp_rect
			(start -0.94 0.47)
			(end 0.94 -0.47)
			(stroke
				(width 0.05)
				(type solid)
			)
			(fill no)
			(layer "B.CrtYd")
		)
		(fp_rect
			(start -0.499 0.249)
			(end 0.499 -0.249)
			(stroke
				(width 0.15)
				(type solid)
			)
			(fill no)
			(layer "B.Fab")
		)
		(pad "1" smd roundrect
			(at -0.484 0 90)
			(size 0.59 0.64)
			(layers "B.Cu" "B.Mask" "B.Paste")
			(roundrect_rratio 0.25)
			(net 459 "3V3_SYS")
			(pintype "passive")
		)
		(pad "2" smd roundrect
			(at 0.484 0 90)
			(size 0.59 0.64)
			(layers "B.Cu" "B.Mask" "B.Paste")
			(roundrect_rratio 0.25)
			(net 5 "GND")
			(pintype "passive")
		)
	)
	(footprint "antmicro-footprints:C_0402_1005Metric"
		(layer "B.Cu")
		(at 166.5 104.125 180)
		(descr "Capacitor SMD 0402")
		(tags "capacitor SMD 0402")
		(property "Reference" "C77"
			(at -1.1 -1.275 0)
			(layer "B.SilkS")
			(effects
				(font
					(size 0.7 0.7)
					(thickness 0.15)
				)
				(justify left bottom mirror)
			)
		)
		(property "Value" "C_4u7_0402"
			(at 0 -1.4 0)
			(layer "B.Fab")
			(effects
				(font
					(size 0.7 0.7)
					(thickness 0.15)
				)
				(justify left bottom mirror)
			)
		)
		(property "Description" " "
			(at 0 0 180)
			(layer "F.Fab")
			(hide yes)
			(effects
				(font
					(size 1.27 1.27)
					(thickness 0.15)
				)
			)
		)
		(property "Author" "Antmicro"
			(at 333 208.25 0)
			(layer "B.Fab")
			(hide yes)
			(effects
				(font
					(size 1 1)
					(thickness 0.15)
				)
				(justify mirror)
			)
		)
		(property "Dielectric" ""
			(at 333 208.25 0)
			(layer "B.Fab")
			(hide yes)
			(effects
				(font
					(size 1 1)
					(thickness 0.15)
				)
				(justify mirror)
			)
		)
		(property "License" "Apache-2.0"
			(at 333 208.25 0)
			(layer "B.Fab")
			(hide yes)
			(effects
				(font
					(size 1 1)
					(thickness 0.15)
				)
				(justify mirror)
			)
		)
		(property "MPN" "GRM155R61A475MEAAD"
			(at 333 208.25 0)
			(layer "B.Fab")
			(hide yes)
			(effects
				(font
					(size 1 1)
					(thickness 0.15)
				)
				(justify mirror)
			)
		)
		(property "Manufacturer" "Murata"
			(at 333 208.25 0)
			(layer "B.Fab")
			(hide yes)
			(effects
				(font
					(size 1 1)
					(thickness 0.15)
				)
				(justify mirror)
			)
		)
		(property "Val" "4u7"
			(at 333 208.25 0)
			(layer "B.Fab")
			(hide yes)
			(effects
				(font
					(size 1 1)
					(thickness 0.15)
				)
				(justify mirror)
			)
		)
		(property "Voltage" ""
			(at 333 208.25 0)
			(layer "B.Fab")
			(hide yes)
			(effects
				(font
					(size 1 1)
					(thickness 0.15)
				)
				(justify mirror)
			)
		)
		(sheetname "FPGA power")
		(sheetfile "fpga-power.kicad_sch")
		(attr smd)
		(fp_rect
			(start -0.94 0.47)
			(end 0.94 -0.47)
			(stroke
				(width 0.05)
				(type solid)
			)
			(fill no)
			(layer "B.CrtYd")
		)
		(fp_rect
			(start -0.499 0.249)
			(end 0.499 -0.249)
			(stroke
				(width 0.15)
				(type solid)
			)
			(fill no)
			(layer "B.Fab")
		)
		(pad "1" smd roundrect
			(at -0.484 0 180)
			(size 0.59 0.64)
			(layers "B.Cu" "B.Mask" "B.Paste")
			(roundrect_rratio 0.25)
			(net 459 "3V3_SYS")
			(pintype "passive")
		)
		(pad "2" smd roundrect
			(at 0.484 0 180)
			(size 0.59 0.64)
			(layers "B.Cu" "B.Mask" "B.Paste")
			(roundrect_rratio 0.25)
			(net 5 "GND")
			(pintype "passive")
		)
	)
	(footprint "antmicro-footprints:C_0402_1005Metric"
		(layer "B.Cu")
		(at 160.5 101.125)
		(descr "Capacitor SMD 0402")
		(tags "capacitor SMD 0402")
		(property "Reference" "C79"
			(at -0.8 0.375 180)
			(layer "B.SilkS")
			(effects
				(font
					(size 0.7 0.7)
					(thickness 0.15)
				)
				(justify left bottom mirror)
			)
		)
		(property "Value" "C_4u7_0402"
			(at 0 -1.4 180)
			(layer "B.Fab")
			(effects
				(font
					(size 0.7 0.7)
					(thickness 0.15)
				)
				(justify left bottom mirror)
			)
		)
		(property "Description" " "
			(at 0 0 0)
			(layer "F.Fab")
			(hide yes)
			(effects
				(font
					(size 1.27 1.27)
					(thickness 0.15)
				)
			)
		)
		(property "Author" "Antmicro"
			(at 0 0 0)
			(layer "B.Fab")
			(hide yes)
			(effects
				(font
					(size 1 1)
					(thickness 0.15)
				)
				(justify mirror)
			)
		)
		(property "Dielectric" ""
			(at 0 0 0)
			(layer "B.Fab")
			(hide yes)
			(effects
				(font
					(size 1 1)
					(thickness 0.15)
				)
				(justify mirror)
			)
		)
		(property "License" "Apache-2.0"
			(at 0 0 0)
			(layer "B.Fab")
			(hide yes)
			(effects
				(font
					(size 1 1)
					(thickness 0.15)
				)
				(justify mirror)
			)
		)
		(property "MPN" "GRM155R61A475MEAAD"
			(at 0 0 0)
			(layer "B.Fab")
			(hide yes)
			(effects
				(font
					(size 1 1)
					(thickness 0.15)
				)
				(justify mirror)
			)
		)
		(property "Manufacturer" "Murata"
			(at 0 0 0)
			(layer "B.Fab")
			(hide yes)
			(effects
				(font
					(size 1 1)
					(thickness 0.15)
				)
				(justify mirror)
			)
		)
		(property "Val" "4u7"
			(at 0 0 0)
			(layer "B.Fab")
			(hide yes)
			(effects
				(font
					(size 1 1)
					(thickness 0.15)
				)
				(justify mirror)
			)
		)
		(property "Voltage" ""
			(at 0 0 0)
			(layer "B.Fab")
			(hide yes)
			(effects
				(font
					(size 1 1)
					(thickness 0.15)
				)
				(justify mirror)
			)
		)
		(sheetname "FPGA power")
		(sheetfile "fpga-power.kicad_sch")
		(attr smd)
		(fp_rect
			(start -0.94 0.47)
			(end 0.94 -0.47)
			(stroke
				(width 0.05)
				(type solid)
			)
			(fill no)
			(layer "B.CrtYd")
		)
		(fp_rect
			(start -0.499 0.249)
			(end 0.499 -0.249)
			(stroke
				(width 0.15)
				(type solid)
			)
			(fill no)
			(layer "B.Fab")
		)
		(pad "1" smd roundrect
			(at -0.484 0)
			(size 0.59 0.64)
			(layers "B.Cu" "B.Mask" "B.Paste")
			(roundrect_rratio 0.25)
			(net 459 "3V3_SYS")
			(pintype "passive")
		)
		(pad "2" smd roundrect
			(at 0.484 0)
			(size 0.59 0.64)
			(layers "B.Cu" "B.Mask" "B.Paste")
			(roundrect_rratio 0.25)
			(net 5 "GND")
			(pintype "passive")
		)
	)
	(footprint "antmicro-footprints:C_0402_1005Metric"
		(layer "B.Cu")
		(at 159.1564 99.1362)
		(descr "Capacitor SMD 0402")
		(tags "capacitor SMD 0402")
		(property "Reference" "C82"
			(at -0.7564 0.3638 180)
			(layer "B.SilkS")
			(effects
				(font
					(size 0.7 0.7)
					(thickness 0.15)
				)
				(justify left bottom mirror)
			)
		)
		(property "Value" "C_4u7_0402"
			(at 0 -1.4 180)
			(layer "B.Fab")
			(effects
				(font
					(size 0.7 0.7)
					(thickness 0.15)
				)
				(justify left bottom mirror)
			)
		)
		(property "Description" " "
			(at 0 0 0)
			(layer "F.Fab")
			(hide yes)
			(effects
				(font
					(size 1.27 1.27)
					(thickness 0.15)
				)
			)
		)
		(property "Author" "Antmicro"
			(at 0 0 0)
			(layer "B.Fab")
			(hide yes)
			(effects
				(font
					(size 1 1)
					(thickness 0.15)
				)
				(justify mirror)
			)
		)
		(property "Dielectric" ""
			(at 0 0 0)
			(layer "B.Fab")
			(hide yes)
			(effects
				(font
					(size 1 1)
					(thickness 0.15)
				)
				(justify mirror)
			)
		)
		(property "License" "Apache-2.0"
			(at 0 0 0)
			(layer "B.Fab")
			(hide yes)
			(effects
				(font
					(size 1 1)
					(thickness 0.15)
				)
				(justify mirror)
			)
		)
		(property "MPN" "GRM155R61A475MEAAD"
			(at 0 0 0)
			(layer "B.Fab")
			(hide yes)
			(effects
				(font
					(size 1 1)
					(thickness 0.15)
				)
				(justify mirror)
			)
		)
		(property "Manufacturer" "Murata"
			(at 0 0 0)
			(layer "B.Fab")
			(hide yes)
			(effects
				(font
					(size 1 1)
					(thickness 0.15)
				)
				(justify mirror)
			)
		)
		(property "Val" "4u7"
			(at 0 0 0)
			(layer "B.Fab")
			(hide yes)
			(effects
				(font
					(size 1 1)
					(thickness 0.15)
				)
				(justify mirror)
			)
		)
		(property "Voltage" ""
			(at 0 0 0)
			(layer "B.Fab")
			(hide yes)
			(effects
				(font
					(size 1 1)
					(thickness 0.15)
				)
				(justify mirror)
			)
		)
		(sheetname "FPGA power")
		(sheetfile "fpga-power.kicad_sch")
		(attr smd)
		(fp_rect
			(start -0.94 0.47)
			(end 0.94 -0.47)
			(stroke
				(width 0.05)
				(type solid)
			)
			(fill no)
			(layer "B.CrtYd")
		)
		(fp_rect
			(start -0.499 0.249)
			(end 0.499 -0.249)
			(stroke
				(width 0.15)
				(type solid)
			)
			(fill no)
			(layer "B.Fab")
		)
		(pad "1" smd roundrect
			(at -0.484 0)
			(size 0.59 0.64)
			(layers "B.Cu" "B.Mask" "B.Paste")
			(roundrect_rratio 0.25)
			(net 459 "3V3_SYS")
			(pintype "passive")
		)
		(pad "2" smd roundrect
			(at 0.484 0)
			(size 0.59 0.64)
			(layers "B.Cu" "B.Mask" "B.Paste")
			(roundrect_rratio 0.25)
			(net 5 "GND")
			(pintype "passive")
		)
	)
	(footprint "antmicro-footprints:C_0402_1005Metric"
		(layer "B.Cu")
		(at 159.5 103.125 180)
		(descr "Capacitor SMD 0402")
		(tags "capacitor SMD 0402")
		(property "Reference" "C85"
			(at 0.8 -0.375 0)
			(layer "B.SilkS")
			(effects
				(font
					(size 0.7 0.7)
					(thickness 0.15)
				)
				(justify left bottom mirror)
			)
		)
		(property "Value" "C_4u7_0402"
			(at 0 -1.4 0)
			(layer "B.Fab")
			(effects
				(font
					(size 0.7 0.7)
					(thickness 0.15)
				)
				(justify left bottom mirror)
			)
		)
		(property "Description" " "
			(at 0 0 180)
			(layer "F.Fab")
			(hide yes)
			(effects
				(font
					(size 1.27 1.27)
					(thickness 0.15)
				)
			)
		)
		(property "Author" "Antmicro"
			(at 319 206.25 0)
			(layer "B.Fab")
			(hide yes)
			(effects
				(font
					(size 1 1)
					(thickness 0.15)
				)
				(justify mirror)
			)
		)
		(property "Dielectric" ""
			(at 319 206.25 0)
			(layer "B.Fab")
			(hide yes)
			(effects
				(font
					(size 1 1)
					(thickness 0.15)
				)
				(justify mirror)
			)
		)
		(property "License" "Apache-2.0"
			(at 319 206.25 0)
			(layer "B.Fab")
			(hide yes)
			(effects
				(font
					(size 1 1)
					(thickness 0.15)
				)
				(justify mirror)
			)
		)
		(property "MPN" "GRM155R61A475MEAAD"
			(at 319 206.25 0)
			(layer "B.Fab")
			(hide yes)
			(effects
				(font
					(size 1 1)
					(thickness 0.15)
				)
				(justify mirror)
			)
		)
		(property "Manufacturer" "Murata"
			(at 319 206.25 0)
			(layer "B.Fab")
			(hide yes)
			(effects
				(font
					(size 1 1)
					(thickness 0.15)
				)
				(justify mirror)
			)
		)
		(property "Val" "4u7"
			(at 319 206.25 0)
			(layer "B.Fab")
			(hide yes)
			(effects
				(font
					(size 1 1)
					(thickness 0.15)
				)
				(justify mirror)
			)
		)
		(property "Voltage" ""
			(at 319 206.25 0)
			(layer "B.Fab")
			(hide yes)
			(effects
				(font
					(size 1 1)
					(thickness 0.15)
				)
				(justify mirror)
			)
		)
		(sheetname "FPGA power")
		(sheetfile "fpga-power.kicad_sch")
		(attr smd)
		(fp_rect
			(start -0.94 0.47)
			(end 0.94 -0.47)
			(stroke
				(width 0.05)
				(type solid)
			)
			(fill no)
			(layer "B.CrtYd")
		)
		(fp_rect
			(start -0.499 0.249)
			(end 0.499 -0.249)
			(stroke
				(width 0.15)
				(type solid)
			)
			(fill no)
			(layer "B.Fab")
		)
		(pad "1" smd roundrect
			(at -0.484 0 180)
			(size 0.59 0.64)
			(layers "B.Cu" "B.Mask" "B.Paste")
			(roundrect_rratio 0.25)
			(net 459 "3V3_SYS")
			(pintype "passive")
		)
		(pad "2" smd roundrect
			(at 0.484 0 180)
			(size 0.59 0.64)
			(layers "B.Cu" "B.Mask" "B.Paste")
			(roundrect_rratio 0.25)
			(net 5 "GND")
			(pintype "passive")
		)
	)
	(footprint "antmicro-footprints:C_0402_1005Metric"
		(layer "B.Cu")
		(at 163.5 105.125 180)
		(descr "Capacitor SMD 0402")
		(tags "capacitor SMD 0402")
		(property "Reference" "C87"
			(at -1.2 -1.275 0)
			(layer "B.SilkS")
			(effects
				(font
					(size 0.7 0.7)
					(thickness 0.15)
				)
				(justify left bottom mirror)
			)
		)
		(property "Value" "C_4u7_0402"
			(at 0 -1.4 0)
			(layer "B.Fab")
			(effects
				(font
					(size 0.7 0.7)
					(thickness 0.15)
				)
				(justify left bottom mirror)
			)
		)
		(property "Description" " "
			(at 0 0 180)
			(layer "F.Fab")
			(hide yes)
			(effects
				(font
					(size 1.27 1.27)
					(thickness 0.15)
				)
			)
		)
		(property "Author" "Antmicro"
			(at 327 210.25 0)
			(layer "B.Fab")
			(hide yes)
			(effects
				(font
					(size 1 1)
					(thickness 0.15)
				)
				(justify mirror)
			)
		)
		(property "Dielectric" ""
			(at 327 210.25 0)
			(layer "B.Fab")
			(hide yes)
			(effects
				(font
					(size 1 1)
					(thickness 0.15)
				)
				(justify mirror)
			)
		)
		(property "License" "Apache-2.0"
			(at 327 210.25 0)
			(layer "B.Fab")
			(hide yes)
			(effects
				(font
					(size 1 1)
					(thickness 0.15)
				)
				(justify mirror)
			)
		)
		(property "MPN" "GRM155R61A475MEAAD"
			(at 327 210.25 0)
			(layer "B.Fab")
			(hide yes)
			(effects
				(font
					(size 1 1)
					(thickness 0.15)
				)
				(justify mirror)
			)
		)
		(property "Manufacturer" "Murata"
			(at 327 210.25 0)
			(layer "B.Fab")
			(hide yes)
			(effects
				(font
					(size 1 1)
					(thickness 0.15)
				)
				(justify mirror)
			)
		)
		(property "Val" "4u7"
			(at 327 210.25 0)
			(layer "B.Fab")
			(hide yes)
			(effects
				(font
					(size 1 1)
					(thickness 0.15)
				)
				(justify mirror)
			)
		)
		(property "Voltage" ""
			(at 327 210.25 0)
			(layer "B.Fab")
			(hide yes)
			(effects
				(font
					(size 1 1)
					(thickness 0.15)
				)
				(justify mirror)
			)
		)
		(sheetname "FPGA power")
		(sheetfile "fpga-power.kicad_sch")
		(attr smd)
		(fp_rect
			(start -0.94 0.47)
			(end 0.94 -0.47)
			(stroke
				(width 0.05)
				(type solid)
			)
			(fill no)
			(layer "B.CrtYd")
		)
		(fp_rect
			(start -0.499 0.249)
			(end 0.499 -0.249)
			(stroke
				(width 0.15)
				(type solid)
			)
			(fill no)
			(layer "B.Fab")
		)
		(pad "1" smd roundrect
			(at -0.484 0 180)
			(size 0.59 0.64)
			(layers "B.Cu" "B.Mask" "B.Paste")
			(roundrect_rratio 0.25)
			(net 459 "3V3_SYS")
			(pintype "passive")
		)
		(pad "2" smd roundrect
			(at 0.484 0 180)
			(size 0.59 0.64)
			(layers "B.Cu" "B.Mask" "B.Paste")
			(roundrect_rratio 0.25)
			(net 5 "GND")
			(pintype "passive")
		)
	)
	(footprint "antmicro-footprints:C_0402_1005Metric"
		(layer "B.Cu")
		(at 178.586328 106.974306)
		(descr "Capacitor SMD 0402")
		(tags "capacitor SMD 0402")
		(property "Reference" "C91"
			(at 1.113672 1.225694 180)
			(layer "B.SilkS")
			(effects
				(font
					(size 0.7 0.7)
					(thickness 0.15)
				)
				(justify left bottom mirror)
			)
		)
		(property "Value" "C_4u7_0402"
			(at 0 -1.4 180)
			(layer "B.Fab")
			(effects
				(font
					(size 0.7 0.7)
					(thickness 0.15)
				)
				(justify left bottom mirror)
			)
		)
		(property "Description" " "
			(at 0 0 0)
			(layer "F.Fab")
			(hide yes)
			(effects
				(font
					(size 1.27 1.27)
					(thickness 0.15)
				)
			)
		)
		(property "Author" "Antmicro"
			(at 0 0 0)
			(layer "B.Fab")
			(hide yes)
			(effects
				(font
					(size 1 1)
					(thickness 0.15)
				)
				(justify mirror)
			)
		)
		(property "Dielectric" ""
			(at 0 0 0)
			(layer "B.Fab")
			(hide yes)
			(effects
				(font
					(size 1 1)
					(thickness 0.15)
				)
				(justify mirror)
			)
		)
		(property "License" "Apache-2.0"
			(at 0 0 0)
			(layer "B.Fab")
			(hide yes)
			(effects
				(font
					(size 1 1)
					(thickness 0.15)
				)
				(justify mirror)
			)
		)
		(property "MPN" "GRM155R61A475MEAAD"
			(at 0 0 0)
			(layer "B.Fab")
			(hide yes)
			(effects
				(font
					(size 1 1)
					(thickness 0.15)
				)
				(justify mirror)
			)
		)
		(property "Manufacturer" "Murata"
			(at 0 0 0)
			(layer "B.Fab")
			(hide yes)
			(effects
				(font
					(size 1 1)
					(thickness 0.15)
				)
				(justify mirror)
			)
		)
		(property "Val" "4u7"
			(at 0 0 0)
			(layer "B.Fab")
			(hide yes)
			(effects
				(font
					(size 1 1)
					(thickness 0.15)
				)
				(justify mirror)
			)
		)
		(property "Voltage" ""
			(at 0 0 0)
			(layer "B.Fab")
			(hide yes)
			(effects
				(font
					(size 1 1)
					(thickness 0.15)
				)
				(justify mirror)
			)
		)
		(sheetname "FPGA power")
		(sheetfile "fpga-power.kicad_sch")
		(attr smd)
		(fp_rect
			(start -0.94 0.47)
			(end 0.94 -0.47)
			(stroke
				(width 0.05)
				(type solid)
			)
			(fill no)
			(layer "B.CrtYd")
		)
		(fp_rect
			(start -0.499 0.249)
			(end 0.499 -0.249)
			(stroke
				(width 0.15)
				(type solid)
			)
			(fill no)
			(layer "B.Fab")
		)
		(pad "1" smd roundrect
			(at -0.484 0)
			(size 0.59 0.64)
			(layers "B.Cu" "B.Mask" "B.Paste")
			(roundrect_rratio 0.25)
			(net 459 "3V3_SYS")
			(pintype "passive")
		)
		(pad "2" smd roundrect
			(at 0.484 0)
			(size 0.59 0.64)
			(layers "B.Cu" "B.Mask" "B.Paste")
			(roundrect_rratio 0.25)
			(net 5 "GND")
			(pintype "passive")
		)
	)
	(footprint "antmicro-footprints:C_0402_1005Metric"
		(layer "B.Cu")
		(at 170.75 93 180)
		(descr "Capacitor SMD 0402")
		(tags "capacitor SMD 0402")
		(property "Reference" "C84"
			(at -1.15 0.4 0)
			(layer "B.SilkS")
			(effects
				(font
					(size 0.7 0.7)
					(thickness 0.15)
				)
				(justify left bottom mirror)
			)
		)
		(property "Value" "C_4u7_0402"
			(at 0 -1.4 0)
			(layer "B.Fab")
			(effects
				(font
					(size 0.7 0.7)
					(thickness 0.15)
				)
				(justify left bottom mirror)
			)
		)
		(property "Description" " "
			(at 0 0 180)
			(layer "F.Fab")
			(hide yes)
			(effects
				(font
					(size 1.27 1.27)
					(thickness 0.15)
				)
			)
		)
		(property "Author" "Antmicro"
			(at 341.5 186 0)
			(layer "B.Fab")
			(hide yes)
			(effects
				(font
					(size 1 1)
					(thickness 0.15)
				)
				(justify mirror)
			)
		)
		(property "Dielectric" ""
			(at 341.5 186 0)
			(layer "B.Fab")
			(hide yes)
			(effects
				(font
					(size 1 1)
					(thickness 0.15)
				)
				(justify mirror)
			)
		)
		(property "License" "Apache-2.0"
			(at 341.5 186 0)
			(layer "B.Fab")
			(hide yes)
			(effects
				(font
					(size 1 1)
					(thickness 0.15)
				)
				(justify mirror)
			)
		)
		(property "MPN" "GRM155R61A475MEAAD"
			(at 341.5 186 0)
			(layer "B.Fab")
			(hide yes)
			(effects
				(font
					(size 1 1)
					(thickness 0.15)
				)
				(justify mirror)
			)
		)
		(property "Manufacturer" "Murata"
			(at 341.5 186 0)
			(layer "B.Fab")
			(hide yes)
			(effects
				(font
					(size 1 1)
					(thickness 0.15)
				)
				(justify mirror)
			)
		)
		(property "Val" "4u7"
			(at 341.5 186 0)
			(layer "B.Fab")
			(hide yes)
			(effects
				(font
					(size 1 1)
					(thickness 0.15)
				)
				(justify mirror)
			)
		)
		(property "Voltage" ""
			(at 341.5 186 0)
			(layer "B.Fab")
			(hide yes)
			(effects
				(font
					(size 1 1)
					(thickness 0.15)
				)
				(justify mirror)
			)
		)
		(sheetname "FPGA power")
		(sheetfile "fpga-power.kicad_sch")
		(attr smd)
		(fp_rect
			(start -0.94 0.47)
			(end 0.94 -0.47)
			(stroke
				(width 0.05)
				(type solid)
			)
			(fill no)
			(layer "B.CrtYd")
		)
		(fp_rect
			(start -0.499 0.249)
			(end 0.499 -0.249)
			(stroke
				(width 0.15)
				(type solid)
			)
			(fill no)
			(layer "B.Fab")
		)
		(pad "1" smd roundrect
			(at -0.484 0 180)
			(size 0.59 0.64)
			(layers "B.Cu" "B.Mask" "B.Paste")
			(roundrect_rratio 0.25)
			(net 465 "1V0_SYS")
			(pintype "passive")
		)
		(pad "2" smd roundrect
			(at 0.484 0 180)
			(size 0.59 0.64)
			(layers "B.Cu" "B.Mask" "B.Paste")
			(roundrect_rratio 0.25)
			(net 5 "GND")
			(pintype "passive")
		)
	)
	(footprint "antmicro-footprints:C_0201"
		(layer "B.Cu")
		(at 169.036328 92.367157 180)
		(descr "Capacitor SMD 0201")
		(tags "capacitor SMD 0201")
		(property "Reference" "C56"
			(at -2.463672 1.767157 0)
			(layer "B.SilkS")
			(effects
				(font
					(size 0.7 0.7)
					(thickness 0.15)
				)
				(justify left bottom mirror)
			)
		)
		(property "Value" "C_100n_0201"
			(at 0 -1.4 0)
			(layer "B.Fab")
			(effects
				(font
					(size 0.7 0.7)
					(thickness 0.15)
				)
				(justify left bottom mirror)
			)
		)
		(property "Description" " "
			(at 0 0 180)
			(layer "F.Fab")
			(hide yes)
			(effects
				(font
					(size 1.27 1.27)
					(thickness 0.15)
				)
			)
		)
		(property "Author" "Antmicro"
			(at 338.072656 184.734314 0)
			(layer "B.Fab")
			(hide yes)
			(effects
				(font
					(size 1 1)
					(thickness 0.15)
				)
				(justify mirror)
			)
		)
		(property "Dielectric" ""
			(at 338.072656 184.734314 0)
			(layer "B.Fab")
			(hide yes)
			(effects
				(font
					(size 1 1)
					(thickness 0.15)
				)
				(justify mirror)
			)
		)
		(property "License" "Apache-2.0"
			(at 338.072656 184.734314 0)
			(layer "B.Fab")
			(hide yes)
			(effects
				(font
					(size 1 1)
					(thickness 0.15)
				)
				(justify mirror)
			)
		)
		(property "MPN" "CC0201KRX6S5BB104"
			(at 338.072656 184.734314 0)
			(layer "B.Fab")
			(hide yes)
			(effects
				(font
					(size 1 1)
					(thickness 0.15)
				)
				(justify mirror)
			)
		)
		(property "Manufacturer" "Yaego"
			(at 338.072656 184.734314 0)
			(layer "B.Fab")
			(hide yes)
			(effects
				(font
					(size 1 1)
					(thickness 0.15)
				)
				(justify mirror)
			)
		)
		(property "Val" "100n"
			(at 338.072656 184.734314 0)
			(layer "B.Fab")
			(hide yes)
			(effects
				(font
					(size 1 1)
					(thickness 0.15)
				)
				(justify mirror)
			)
		)
		(property "Voltage" ""
			(at 338.072656 184.734314 0)
			(layer "B.Fab")
			(hide yes)
			(effects
				(font
					(size 1 1)
					(thickness 0.15)
				)
				(justify mirror)
			)
		)
		(sheetname "FPGA power")
		(sheetfile "fpga-power.kicad_sch")
		(attr smd)
		(fp_rect
			(start -0.72 0.38)
			(end 0.72 -0.38)
			(stroke
				(width 0.05)
				(type solid)
			)
			(fill no)
			(layer "B.CrtYd")
		)
		(fp_rect
			(start 0.3 -0.15)
			(end -0.301 0.149)
			(stroke
				(width 0.15)
				(type solid)
			)
			(fill no)
			(layer "B.Fab")
		)
		(pad "" smd roundrect
			(at -0.349 0.002 180)
			(size 0.318 0.36)
			(layers "B.Paste")
			(roundrect_rratio 0.25)
		)
		(pad "" smd roundrect
			(at 0.341 0.002 180)
			(size 0.318 0.36)
			(layers "B.Paste")
			(roundrect_rratio 0.25)
		)
		(pad "1" smd roundrect
			(at -0.321 0.002 180)
			(size 0.46 0.4)
			(layers "B.Cu" "B.Mask")
			(roundrect_rratio 0.25)
			(net 465 "1V0_SYS")
			(pintype "passive")
		)
		(pad "2" smd roundrect
			(at 0.32 0.002 180)
			(size 0.46 0.4)
			(layers "B.Cu" "B.Mask")
			(roundrect_rratio 0.25)
			(net 5 "GND")
			(pintype "passive")
		)
	)
	(footprint "antmicro-footprints:C_0201"
		(layer "B.Cu")
		(at 160.036328 91.497157)
		(descr "Capacitor SMD 0201")
		(tags "capacitor SMD 0201")
		(property "Reference" "C51"
			(at -0.536328 0.402843 180)
			(layer "B.SilkS")
			(effects
				(font
					(size 0.7 0.7)
					(thickness 0.15)
				)
				(justify left bottom mirror)
			)
		)
		(property "Value" "C_100n_0201"
			(at 0 -1.4 180)
			(layer "B.Fab")
			(effects
				(font
					(size 0.7 0.7)
					(thickness 0.15)
				)
				(justify left bottom mirror)
			)
		)
		(property "Description" " "
			(at 0 0 0)
			(layer "F.Fab")
			(hide yes)
			(effects
				(font
					(size 1.27 1.27)
					(thickness 0.15)
				)
			)
		)
		(property "Author" "Antmicro"
			(at 0 0 0)
			(layer "B.Fab")
			(hide yes)
			(effects
				(font
					(size 1 1)
					(thickness 0.15)
				)
				(justify mirror)
			)
		)
		(property "Dielectric" ""
			(at 0 0 0)
			(layer "B.Fab")
			(hide yes)
			(effects
				(font
					(size 1 1)
					(thickness 0.15)
				)
				(justify mirror)
			)
		)
		(property "License" "Apache-2.0"
			(at 0 0 0)
			(layer "B.Fab")
			(hide yes)
			(effects
				(font
					(size 1 1)
					(thickness 0.15)
				)
				(justify mirror)
			)
		)
		(property "MPN" "CC0201KRX6S5BB104"
			(at 0 0 0)
			(layer "B.Fab")
			(hide yes)
			(effects
				(font
					(size 1 1)
					(thickness 0.15)
				)
				(justify mirror)
			)
		)
		(property "Manufacturer" "Yaego"
			(at 0 0 0)
			(layer "B.Fab")
			(hide yes)
			(effects
				(font
					(size 1 1)
					(thickness 0.15)
				)
				(justify mirror)
			)
		)
		(property "Val" "100n"
			(at 0 0 0)
			(layer "B.Fab")
			(hide yes)
			(effects
				(font
					(size 1 1)
					(thickness 0.15)
				)
				(justify mirror)
			)
		)
		(property "Voltage" ""
			(at 0 0 0)
			(layer "B.Fab")
			(hide yes)
			(effects
				(font
					(size 1 1)
					(thickness 0.15)
				)
				(justify mirror)
			)
		)
		(sheetname "FPGA power")
		(sheetfile "fpga-power.kicad_sch")
		(attr smd)
		(fp_rect
			(start -0.72 0.38)
			(end 0.72 -0.38)
			(stroke
				(width 0.05)
				(type solid)
			)
			(fill no)
			(layer "B.CrtYd")
		)
		(fp_rect
			(start 0.3 -0.15)
			(end -0.301 0.149)
			(stroke
				(width 0.15)
				(type solid)
			)
			(fill no)
			(layer "B.Fab")
		)
		(pad "" smd roundrect
			(at -0.349 0.002)
			(size 0.318 0.36)
			(layers "B.Paste")
			(roundrect_rratio 0.25)
		)
		(pad "" smd roundrect
			(at 0.341 0.002)
			(size 0.318 0.36)
			(layers "B.Paste")
			(roundrect_rratio 0.25)
		)
		(pad "1" smd roundrect
			(at -0.321 0.002)
			(size 0.46 0.4)
			(layers "B.Cu" "B.Mask")
			(roundrect_rratio 0.25)
			(net 66 "VDDQ")
			(pintype "passive")
		)
		(pad "2" smd roundrect
			(at 0.32 0.002)
			(size 0.46 0.4)
			(layers "B.Cu" "B.Mask")
			(roundrect_rratio 0.25)
			(net 5 "GND")
			(pintype "passive")
		)
	)
	(footprint "antmicro-footprints:C_0201"
		(layer "B.Cu")
		(at 171.511328 95.622157 180)
		(descr "Capacitor SMD 0201")
		(tags "capacitor SMD 0201")
		(property "Reference" "C29"
			(at -1.088672 0.322157 0)
			(layer "B.SilkS")
			(effects
				(font
					(size 0.7 0.7)
					(thickness 0.15)
				)
				(justify left bottom mirror)
			)
		)
		(property "Value" "C_100n_0201"
			(at 0 -1.4 0)
			(layer "B.Fab")
			(effects
				(font
					(size 0.7 0.7)
					(thickness 0.15)
				)
				(justify left bottom mirror)
			)
		)
		(property "Description" " "
			(at 0 0 180)
			(layer "F.Fab")
			(hide yes)
			(effects
				(font
					(size 1.27 1.27)
					(thickness 0.15)
				)
			)
		)
		(property "Author" "Antmicro"
			(at 343.022656 191.244314 0)
			(layer "B.Fab")
			(hide yes)
			(effects
				(font
					(size 1 1)
					(thickness 0.15)
				)
				(justify mirror)
			)
		)
		(property "Dielectric" ""
			(at 343.022656 191.244314 0)
			(layer "B.Fab")
			(hide yes)
			(effects
				(font
					(size 1 1)
					(thickness 0.15)
				)
				(justify mirror)
			)
		)
		(property "License" "Apache-2.0"
			(at 343.022656 191.244314 0)
			(layer "B.Fab")
			(hide yes)
			(effects
				(font
					(size 1 1)
					(thickness 0.15)
				)
				(justify mirror)
			)
		)
		(property "MPN" "CC0201KRX6S5BB104"
			(at 343.022656 191.244314 0)
			(layer "B.Fab")
			(hide yes)
			(effects
				(font
					(size 1 1)
					(thickness 0.15)
				)
				(justify mirror)
			)
		)
		(property "Manufacturer" "Yaego"
			(at 343.022656 191.244314 0)
			(layer "B.Fab")
			(hide yes)
			(effects
				(font
					(size 1 1)
					(thickness 0.15)
				)
				(justify mirror)
			)
		)
		(property "Val" "100n"
			(at 343.022656 191.244314 0)
			(layer "B.Fab")
			(hide yes)
			(effects
				(font
					(size 1 1)
					(thickness 0.15)
				)
				(justify mirror)
			)
		)
		(property "Voltage" ""
			(at 343.022656 191.244314 0)
			(layer "B.Fab")
			(hide yes)
			(effects
				(font
					(size 1 1)
					(thickness 0.15)
				)
				(justify mirror)
			)
		)
		(sheetname "FPGA power")
		(sheetfile "fpga-power.kicad_sch")
		(attr smd)
		(fp_rect
			(start -0.72 0.38)
			(end 0.72 -0.38)
			(stroke
				(width 0.05)
				(type solid)
			)
			(fill no)
			(layer "B.CrtYd")
		)
		(fp_rect
			(start 0.3 -0.15)
			(end -0.301 0.149)
			(stroke
				(width 0.15)
				(type solid)
			)
			(fill no)
			(layer "B.Fab")
		)
		(pad "" smd roundrect
			(at -0.349 0.002 180)
			(size 0.318 0.36)
			(layers "B.Paste")
			(roundrect_rratio 0.25)
		)
		(pad "" smd roundrect
			(at 0.341 0.002 180)
			(size 0.318 0.36)
			(layers "B.Paste")
			(roundrect_rratio 0.25)
		)
		(pad "1" smd roundrect
			(at -0.321 0.002 180)
			(size 0.46 0.4)
			(layers "B.Cu" "B.Mask")
			(roundrect_rratio 0.25)
			(net 465 "1V0_SYS")
			(pintype "passive")
		)
		(pad "2" smd roundrect
			(at 0.32 0.002 180)
			(size 0.46 0.4)
			(layers "B.Cu" "B.Mask")
			(roundrect_rratio 0.25)
			(net 5 "GND")
			(pintype "passive")
		)
	)
	(footprint "antmicro-footprints:C_0402_1005Metric"
		(layer "B.Cu")
		(at 173.25 95.75)
		(descr "Capacitor SMD 0402")
		(tags "capacitor SMD 0402")
		(property "Reference" "C83"
			(at 1.35 -0.45 180)
			(layer "B.SilkS")
			(effects
				(font
					(size 0.7 0.7)
					(thickness 0.15)
				)
				(justify left bottom mirror)
			)
		)
		(property "Value" "C_4u7_0402"
			(at 0 -1.4 180)
			(layer "B.Fab")
			(effects
				(font
					(size 0.7 0.7)
					(thickness 0.15)
				)
				(justify left bottom mirror)
			)
		)
		(property "Description" " "
			(at 0 0 0)
			(layer "F.Fab")
			(hide yes)
			(effects
				(font
					(size 1.27 1.27)
					(thickness 0.15)
				)
			)
		)
		(property "Author" "Antmicro"
			(at 0 0 0)
			(layer "B.Fab")
			(hide yes)
			(effects
				(font
					(size 1 1)
					(thickness 0.15)
				)
				(justify mirror)
			)
		)
		(property "Dielectric" ""
			(at 0 0 0)
			(layer "B.Fab")
			(hide yes)
			(effects
				(font
					(size 1 1)
					(thickness 0.15)
				)
				(justify mirror)
			)
		)
		(property "License" "Apache-2.0"
			(at 0 0 0)
			(layer "B.Fab")
			(hide yes)
			(effects
				(font
					(size 1 1)
					(thickness 0.15)
				)
				(justify mirror)
			)
		)
		(property "MPN" "GRM155R61A475MEAAD"
			(at 0 0 0)
			(layer "B.Fab")
			(hide yes)
			(effects
				(font
					(size 1 1)
					(thickness 0.15)
				)
				(justify mirror)
			)
		)
		(property "Manufacturer" "Murata"
			(at 0 0 0)
			(layer "B.Fab")
			(hide yes)
			(effects
				(font
					(size 1 1)
					(thickness 0.15)
				)
				(justify mirror)
			)
		)
		(property "Val" "4u7"
			(at 0 0 0)
			(layer "B.Fab")
			(hide yes)
			(effects
				(font
					(size 1 1)
					(thickness 0.15)
				)
				(justify mirror)
			)
		)
		(property "Voltage" ""
			(at 0 0 0)
			(layer "B.Fab")
			(hide yes)
			(effects
				(font
					(size 1 1)
					(thickness 0.15)
				)
				(justify mirror)
			)
		)
		(sheetname "FPGA power")
		(sheetfile "fpga-power.kicad_sch")
		(attr smd)
		(fp_rect
			(start -0.94 0.47)
			(end 0.94 -0.47)
			(stroke
				(width 0.05)
				(type solid)
			)
			(fill no)
			(layer "B.CrtYd")
		)
		(fp_rect
			(start -0.499 0.249)
			(end 0.499 -0.249)
			(stroke
				(width 0.15)
				(type solid)
			)
			(fill no)
			(layer "B.Fab")
		)
		(pad "1" smd roundrect
			(at -0.484 0)
			(size 0.59 0.64)
			(layers "B.Cu" "B.Mask" "B.Paste")
			(roundrect_rratio 0.25)
			(net 465 "1V0_SYS")
			(pintype "passive")
		)
		(pad "2" smd roundrect
			(at 0.484 0)
			(size 0.59 0.64)
			(layers "B.Cu" "B.Mask" "B.Paste")
			(roundrect_rratio 0.25)
			(net 5 "GND")
			(pintype "passive")
		)
	)
	(footprint "antmicro-footprints:C_0201"
		(layer "B.Cu")
		(at 172.736328 99.497157 90)
		(descr "Capacitor SMD 0201")
		(tags "capacitor SMD 0201")
		(property "Reference" "C37"
			(at 1.097157 -0.336328 270)
			(layer "B.SilkS")
			(effects
				(font
					(size 0.7 0.7)
					(thickness 0.15)
				)
				(justify left bottom mirror)
			)
		)
		(property "Value" "C_100n_0201"
			(at 0 -1.4 270)
			(layer "B.Fab")
			(effects
				(font
					(size 0.7 0.7)
					(thickness 0.15)
				)
				(justify left bottom mirror)
			)
		)
		(property "Description" " "
			(at 0 0 90)
			(layer "F.Fab")
			(hide yes)
			(effects
				(font
					(size 1.27 1.27)
					(thickness 0.15)
				)
			)
		)
		(property "Author" "Antmicro"
			(at 272.233485 -73.239171 0)
			(layer "B.Fab")
			(hide yes)
			(effects
				(font
					(size 1 1)
					(thickness 0.15)
				)
				(justify mirror)
			)
		)
		(property "Dielectric" ""
			(at 272.233485 -73.239171 0)
			(layer "B.Fab")
			(hide yes)
			(effects
				(font
					(size 1 1)
					(thickness 0.15)
				)
				(justify mirror)
			)
		)
		(property "License" "Apache-2.0"
			(at 272.233485 -73.239171 0)
			(layer "B.Fab")
			(hide yes)
			(effects
				(font
					(size 1 1)
					(thickness 0.15)
				)
				(justify mirror)
			)
		)
		(property "MPN" "CC0201KRX6S5BB104"
			(at 272.233485 -73.239171 0)
			(layer "B.Fab")
			(hide yes)
			(effects
				(font
					(size 1 1)
					(thickness 0.15)
				)
				(justify mirror)
			)
		)
		(property "Manufacturer" "Yaego"
			(at 272.233485 -73.239171 0)
			(layer "B.Fab")
			(hide yes)
			(effects
				(font
					(size 1 1)
					(thickness 0.15)
				)
				(justify mirror)
			)
		)
		(property "Val" "100n"
			(at 272.233485 -73.239171 0)
			(layer "B.Fab")
			(hide yes)
			(effects
				(font
					(size 1 1)
					(thickness 0.15)
				)
				(justify mirror)
			)
		)
		(property "Voltage" ""
			(at 272.233485 -73.239171 0)
			(layer "B.Fab")
			(hide yes)
			(effects
				(font
					(size 1 1)
					(thickness 0.15)
				)
				(justify mirror)
			)
		)
		(sheetname "FPGA power")
		(sheetfile "fpga-power.kicad_sch")
		(attr smd)
		(fp_rect
			(start -0.72 0.38)
			(end 0.72 -0.38)
			(stroke
				(width 0.05)
				(type solid)
			)
			(fill no)
			(layer "B.CrtYd")
		)
		(fp_rect
			(start 0.3 -0.15)
			(end -0.301 0.149)
			(stroke
				(width 0.15)
				(type solid)
			)
			(fill no)
			(layer "B.Fab")
		)
		(pad "" smd roundrect
			(at -0.349 0.002 90)
			(size 0.318 0.36)
			(layers "B.Paste")
			(roundrect_rratio 0.25)
		)
		(pad "" smd roundrect
			(at 0.341 0.002 90)
			(size 0.318 0.36)
			(layers "B.Paste")
			(roundrect_rratio 0.25)
		)
		(pad "1" smd roundrect
			(at -0.321 0.002 90)
			(size 0.46 0.4)
			(layers "B.Cu" "B.Mask")
			(roundrect_rratio 0.25)
			(net 465 "1V0_SYS")
			(pintype "passive")
		)
		(pad "2" smd roundrect
			(at 0.32 0.002 90)
			(size 0.46 0.4)
			(layers "B.Cu" "B.Mask")
			(roundrect_rratio 0.25)
			(net 5 "GND")
			(pintype "passive")
		)
	)
	(footprint "antmicro-footprints:C_0402_1005Metric"
		(layer "B.Cu")
		(at 167.75 90.497157 90)
		(descr "Capacitor SMD 0402")
		(tags "capacitor SMD 0402")
		(property "Reference" "C24"
			(at 2.997157 0.15 270)
			(layer "B.SilkS")
			(effects
				(font
					(size 0.7 0.7)
					(thickness 0.15)
				)
				(justify left bottom mirror)
			)
		)
		(property "Value" "C_470n_0402"
			(at 0 -1.4 270)
			(layer "B.Fab")
			(effects
				(font
					(size 0.7 0.7)
					(thickness 0.15)
				)
				(justify left bottom mirror)
			)
		)
		(property "Description" " "
			(at 0 0 90)
			(layer "F.Fab")
			(hide yes)
			(effects
				(font
					(size 1.27 1.27)
					(thickness 0.15)
				)
			)
		)
		(property "Author" "Antmicro"
			(at 258.247157 -77.252843 0)
			(layer "B.Fab")
			(hide yes)
			(effects
				(font
					(size 1 1)
					(thickness 0.15)
				)
				(justify mirror)
			)
		)
		(property "Dielectric" ""
			(at 258.247157 -77.252843 0)
			(layer "B.Fab")
			(hide yes)
			(effects
				(font
					(size 1 1)
					(thickness 0.15)
				)
				(justify mirror)
			)
		)
		(property "License" "Apache-2.0"
			(at 258.247157 -77.252843 0)
			(layer "B.Fab")
			(hide yes)
			(effects
				(font
					(size 1 1)
					(thickness 0.15)
				)
				(justify mirror)
			)
		)
		(property "MPN" "C1005X5R1E474M050BB"
			(at 258.247157 -77.252843 0)
			(layer "B.Fab")
			(hide yes)
			(effects
				(font
					(size 1 1)
					(thickness 0.15)
				)
				(justify mirror)
			)
		)
		(property "Manufacturer" "TDK"
			(at 258.247157 -77.252843 0)
			(layer "B.Fab")
			(hide yes)
			(effects
				(font
					(size 1 1)
					(thickness 0.15)
				)
				(justify mirror)
			)
		)
		(property "Val" "470n"
			(at 258.247157 -77.252843 0)
			(layer "B.Fab")
			(hide yes)
			(effects
				(font
					(size 1 1)
					(thickness 0.15)
				)
				(justify mirror)
			)
		)
		(property "Voltage" ""
			(at 258.247157 -77.252843 0)
			(layer "B.Fab")
			(hide yes)
			(effects
				(font
					(size 1 1)
					(thickness 0.15)
				)
				(justify mirror)
			)
		)
		(sheetname "FPGA power")
		(sheetfile "fpga-power.kicad_sch")
		(attr smd)
		(fp_rect
			(start -0.94 0.47)
			(end 0.94 -0.47)
			(stroke
				(width 0.05)
				(type solid)
			)
			(fill no)
			(layer "B.CrtYd")
		)
		(fp_rect
			(start -0.499 0.249)
			(end 0.499 -0.249)
			(stroke
				(width 0.15)
				(type solid)
			)
			(fill no)
			(layer "B.Fab")
		)
		(pad "1" smd roundrect
			(at -0.484 0 90)
			(size 0.59 0.64)
			(layers "B.Cu" "B.Mask" "B.Paste")
			(roundrect_rratio 0.25)
			(net 459 "3V3_SYS")
			(pintype "passive")
		)
		(pad "2" smd roundrect
			(at 0.484 0 90)
			(size 0.59 0.64)
			(layers "B.Cu" "B.Mask" "B.Paste")
			(roundrect_rratio 0.25)
			(net 5 "GND")
			(pintype "passive")
		)
	)
	(footprint "antmicro-footprints:MicroSD_Amphenol_1140084168"
		(layer "B.Cu")
		(at 174.770666 127.719218 180)
		(property "Reference" "J3"
			(at -6.6 6.5 0)
			(layer "B.SilkS")
			(effects
				(font
					(size 0.7 0.7)
					(thickness 0.15)
				)
				(justify left bottom mirror)
			)
		)
		(property "Value" "MicroSD_1140084168"
			(at -6.9 -11.4 0)
			(layer "B.Fab")
			(effects
				(font
					(size 0.7 0.7)
					(thickness 0.15)
				)
				(justify left bottom mirror)
			)
		)
		(property "Description" "Micro SD Right Angle, PCB Mount"
			(at 0 0 180)
			(layer "F.Fab")
			(hide yes)
			(effects
				(font
					(size 1.27 1.27)
					(thickness 0.15)
				)
			)
		)
		(property "Author" "Antmicro"
			(at 349.541332 255.438436 0)
			(layer "B.Fab")
			(hide yes)
			(effects
				(font
					(size 1 1)
					(thickness 0.15)
				)
				(justify mirror)
			)
		)
		(property "License" "Apache-2.0"
			(at 349.541332 255.438436 0)
			(layer "B.Fab")
			(hide yes)
			(effects
				(font
					(size 1 1)
					(thickness 0.15)
				)
				(justify mirror)
			)
		)
		(property "MPN" "1140084168"
			(at 349.541332 255.438436 0)
			(layer "B.Fab")
			(hide yes)
			(effects
				(font
					(size 1 1)
					(thickness 0.15)
				)
				(justify mirror)
			)
		)
		(property "Manufacturer" "Amphenol"
			(at 349.541332 255.438436 0)
			(layer "B.Fab")
			(hide yes)
			(effects
				(font
					(size 1 1)
					(thickness 0.15)
				)
				(justify mirror)
			)
		)
		(sheetname "Interfaces")
		(sheetfile "interfaces.kicad_sch")
		(attr smd)
		(fp_line
			(start 6.2 6.1)
			(end 6.1 6.1)
			(stroke
				(width 0.15)
				(type solid)
			)
			(layer "B.SilkS")
		)
		(fp_line
			(start 6.2 4)
			(end 6.2 6.1)
			(stroke
				(width 0.15)
				(type solid)
			)
			(layer "B.SilkS")
		)
		(fp_line
			(start 6.2 -4.2)
			(end 6.2 2.2)
			(stroke
				(width 0.15)
				(type solid)
			)
			(layer "B.SilkS")
		)
		(fp_line
			(start 4.8 6.1)
			(end -6.3 6.1)
			(stroke
				(width 0.15)
				(type solid)
			)
			(layer "B.SilkS")
		)
		(fp_line
			(start -6.3 6.1)
			(end -6.3 4.7)
			(stroke
				(width 0.15)
				(type solid)
			)
			(layer "B.SilkS")
		)
		(fp_line
			(start -6.3 1.6)
			(end -6.3 -4.2)
			(stroke
				(width 0.15)
				(type solid)
			)
			(layer "B.SilkS")
		)
		(fp_rect
			(start -6.5 6.3)
			(end 6.4 -6.2)
			(stroke
				(width 0.05)
				(type solid)
			)
			(fill no)
			(layer "B.CrtYd")
		)
		(fp_line
			(start 5.4 -8.9)
			(end 4.6 -8.7)
			(stroke
				(width 0.12)
				(type solid)
			)
			(layer "B.Fab")
		)
		(fp_line
			(start 5.4 -9.2)
			(end 4.6 -9)
			(stroke
				(width 0.12)
				(type solid)
			)
			(layer "B.Fab")
		)
		(fp_line
			(start 5.4 -9.5)
			(end 5.4 -5.8)
			(stroke
				(width 0.12)
				(type solid)
			)
			(layer "B.Fab")
		)
		(fp_line
			(start 4.9 -10)
			(end -5.1 -10)
			(stroke
				(width 0.12)
				(type solid)
			)
			(layer "B.Fab")
		)
		(fp_line
			(start 4.6 -8.7)
			(end 2.9 -8.4)
			(stroke
				(width 0.12)
				(type solid)
			)
			(layer "B.Fab")
		)
		(fp_line
			(start 4.6 -9)
			(end 2.9 -8.7)
			(stroke
				(width 0.12)
				(type solid)
			)
			(layer "B.Fab")
		)
		(fp_line
			(start 2.9 -8.4)
			(end 2.1 -8.3)
			(stroke
				(width 0.12)
				(type solid)
			)
			(layer "B.Fab")
		)
		(fp_line
			(start 2.9 -8.7)
			(end 2.1 -8.6)
			(stroke
				(width 0.12)
				(type solid)
			)
			(layer "B.Fab")
		)
		(fp_line
			(start 2.1 -8.3)
			(end 0.8 -8.2)
			(stroke
				(width 0.12)
				(type solid)
			)
			(layer "B.Fab")
		)
		(fp_line
			(start 2.1 -8.6)
			(end 0.8 -8.5)
			(stroke
				(width 0.12)
				(type solid)
			)
			(layer "B.Fab")
		)
		(fp_line
			(start 0.8 -8.2)
			(end -1 -8.2)
			(stroke
				(width 0.12)
				(type solid)
			)
			(layer "B.Fab")
		)
		(fp_line
			(start 0.8 -8.5)
			(end -1 -8.5)
			(stroke
				(width 0.12)
				(type solid)
			)
			(layer "B.Fab")
		)
		(fp_line
			(start -1 -8.2)
			(end -2.3 -8.3)
			(stroke
				(width 0.12)
				(type solid)
			)
			(layer "B.Fab")
		)
		(fp_line
			(start -1 -8.5)
			(end -2.3 -8.6)
			(stroke
				(width 0.12)
				(type solid)
			)
			(layer "B.Fab")
		)
		(fp_line
			(start -2.3 -8.3)
			(end -3.8 -8.5)
			(stroke
				(width 0.12)
				(type solid)
			)
			(layer "B.Fab")
		)
		(fp_line
			(start -2.3 -8.6)
			(end -3.8 -8.8)
			(stroke
				(width 0.12)
				(type solid)
			)
			(layer "B.Fab")
		)
		(fp_line
			(start -3.8 -8.5)
			(end -5.1 -8.8)
			(stroke
				(width 0.12)
				(type solid)
			)
			(layer "B.Fab")
		)
		(fp_line
			(start -3.8 -8.8)
			(end -5.1 -9.1)
			(stroke
				(width 0.12)
				(type solid)
			)
			(layer "B.Fab")
		)
		(fp_line
			(start -5.1 -8.8)
			(end -5.6 -8.9)
			(stroke
				(width 0.12)
				(type solid)
			)
			(layer "B.Fab")
		)
		(fp_line
			(start -5.1 -9.1)
			(end -5.6 -9.2)
			(stroke
				(width 0.12)
				(type solid)
			)
			(layer "B.Fab")
		)
		(fp_line
			(start -5.6 -5.8)
			(end -5.6 -9.5)
			(stroke
				(width 0.12)
				(type solid)
			)
			(layer "B.Fab")
		)
		(fp_rect
			(start -6 5.8)
			(end 5.999 -5.799)
			(stroke
				(width 0.1)
				(type solid)
			)
			(fill no)
			(layer "B.Fab")
		)
		(fp_arc
			(start 4.9 -10)
			(mid 5.253553 -9.853553)
			(end 5.4 -9.5)
			(stroke
				(width 0.12)
				(type solid)
			)
			(layer "B.Fab")
		)
		(fp_arc
			(start -5.6 -9.5)
			(mid -5.453553 -9.853553)
			(end -5.1 -10)
			(stroke
				(width 0.12)
				(type solid)
			)
			(layer "B.Fab")
		)
		(pad "1" smd rect
			(at 3.124 -5.254)
			(size 0.7 1.75)
			(layers "B.Cu" "B.Mask" "B.Paste")
			(net 197 "SD_DAT2")
			(pinfunction "DAT2")
			(pintype "bidirectional")
		)
		(pad "2" smd rect
			(at 2.024 -5.254)
			(size 0.7 1.75)
			(layers "B.Cu" "B.Mask" "B.Paste")
			(net 196 "SD_DAT3")
			(pinfunction "CD/DAT3")
			(pintype "bidirectional")
		)
		(pad "3" smd rect
			(at 0.925 -5.254)
			(size 0.7 1.75)
			(layers "B.Cu" "B.Mask" "B.Paste")
			(net 195 "SD_CMD")
			(pinfunction "CMD")
			(pintype "bidirectional")
		)
		(pad "4" smd rect
			(at -0.176 -5.254)
			(size 0.7 1.75)
			(layers "B.Cu" "B.Mask" "B.Paste")
			(net 459 "3V3_SYS")
			(pinfunction "VDD")
			(pintype "power_in")
		)
		(pad "5" smd rect
			(at -1.276 -5.254)
			(size 0.7 1.75)
			(layers "B.Cu" "B.Mask" "B.Paste")
			(net 194 "SD_CLK")
			(pinfunction "CLK")
			(pintype "output")
		)
		(pad "6" smd rect
			(at -2.375 -5.254)
			(size 0.7 1.75)
			(layers "B.Cu" "B.Mask" "B.Paste")
			(net 5 "GND")
			(pinfunction "VSS")
			(pintype "power_in")
		)
		(pad "7" smd rect
			(at -3.476 -5.254)
			(size 0.7 1.75)
			(layers "B.Cu" "B.Mask" "B.Paste")
			(net 193 "SD_DAT0")
			(pinfunction "DAT0")
			(pintype "bidirectional")
		)
		(pad "8" smd rect
			(at -4.576 -5.254)
			(size 0.7 1.75)
			(layers "B.Cu" "B.Mask" "B.Paste")
			(net 192 "SD_DAT1")
			(pinfunction "DAT1")
			(pintype "bidirectional")
		)
		(pad "9" smd rect
			(at -5.675 4.05 180)
			(size 1.4 1)
			(layers "B.Cu" "B.Mask" "B.Paste")
			(net 85 "Net-(J3-CD1)")
			(pinfunction "CD1")
			(pintype "passive")
		)
		(pad "10" smd rect
			(at 5.424 5.531 90)
			(size 1.4 1)
			(layers "B.Cu" "B.Mask" "B.Paste")
			(net 5 "GND")
			(pinfunction "CD2")
			(pintype "passive")
		)
		(pad "SH" smd rect
			(at -5.976 2.48 90)
			(size 1.5 0.8)
			(layers "B.Cu" "B.Mask" "B.Paste")
			(net 5 "GND")
			(pinfunction "Shell")
			(pintype "passive")
		)
		(pad "SH" smd rect
			(at -5.776 -5.129 180)
			(size 1.3 1.5)
			(layers "B.Cu" "B.Mask" "B.Paste")
			(net 5 "GND")
			(pinfunction "Shell")
			(pintype "passive")
		)
		(pad "SH" smd rect
			(at 5.575 -5.129 180)
			(size 1.5 1.5)
			(layers "B.Cu" "B.Mask" "B.Paste")
			(net 5 "GND")
			(pinfunction "Shell")
			(pintype "passive")
		)
		(pad "SH" smd rect
			(at 5.874 3.13 90)
			(size 1.5 0.8)
			(layers "B.Cu" "B.Mask" "B.Paste")
			(net 5 "GND")
			(pinfunction "Shell")
			(pintype "passive")
		)
	)
	(footprint "antmicro-footprints:C_0402_1005Metric"
		(layer "B.Cu")
		(at 153.4922 94.742 180)
		(descr "Capacitor SMD 0402")
		(tags "capacitor SMD 0402")
		(property "Reference" "C2"
			(at -0.8078 0.542 0)
			(layer "B.SilkS")
			(effects
				(font
					(size 0.7 0.7)
					(thickness 0.15)
				)
				(justify left bottom mirror)
			)
		)
		(property "Value" "C_100n_6V3_0402"
			(at 0 -1.4 0)
			(layer "B.Fab")
			(effects
				(font
					(size 0.7 0.7)
					(thickness 0.15)
				)
				(justify left bottom mirror)
			)
		)
		(property "Description" " "
			(at 0 0 180)
			(layer "F.Fab")
			(hide yes)
			(effects
				(font
					(size 1.27 1.27)
					(thickness 0.15)
				)
			)
		)
		(property "Author" "Antmicro"
			(at 306.9844 189.484 0)
			(layer "B.Fab")
			(hide yes)
			(effects
				(font
					(size 1 1)
					(thickness 0.15)
				)
				(justify mirror)
			)
		)
		(property "Dielectric" ""
			(at 306.9844 189.484 0)
			(layer "B.Fab")
			(hide yes)
			(effects
				(font
					(size 1 1)
					(thickness 0.15)
				)
				(justify mirror)
			)
		)
		(property "License" "Apache-2.0"
			(at 306.9844 189.484 0)
			(layer "B.Fab")
			(hide yes)
			(effects
				(font
					(size 1 1)
					(thickness 0.15)
				)
				(justify mirror)
			)
		)
		(property "MPN" "0402X104K6R3CT"
			(at 306.9844 189.484 0)
			(layer "B.Fab")
			(hide yes)
			(effects
				(font
					(size 1 1)
					(thickness 0.15)
				)
				(justify mirror)
			)
		)
		(property "Manufacturer" "Walsin"
			(at 306.9844 189.484 0)
			(layer "B.Fab")
			(hide yes)
			(effects
				(font
					(size 1 1)
					(thickness 0.15)
				)
				(justify mirror)
			)
		)
		(property "Val" "100n"
			(at 306.9844 189.484 0)
			(layer "B.Fab")
			(hide yes)
			(effects
				(font
					(size 1 1)
					(thickness 0.15)
				)
				(justify mirror)
			)
		)
		(property "Voltage" ""
			(at 306.9844 189.484 0)
			(layer "B.Fab")
			(hide yes)
			(effects
				(font
					(size 1 1)
					(thickness 0.15)
				)
				(justify mirror)
			)
		)
		(sheetname "HyperRAM")
		(sheetfile "hyperram.kicad_sch")
		(attr smd)
		(fp_rect
			(start -0.94 0.47)
			(end 0.94 -0.47)
			(stroke
				(width 0.05)
				(type solid)
			)
			(fill no)
			(layer "B.CrtYd")
		)
		(fp_rect
			(start -0.499 0.249)
			(end 0.499 -0.249)
			(stroke
				(width 0.15)
				(type solid)
			)
			(fill no)
			(layer "B.Fab")
		)
		(pad "1" smd roundrect
			(at -0.484 0 180)
			(size 0.59 0.64)
			(layers "B.Cu" "B.Mask" "B.Paste")
			(roundrect_rratio 0.25)
			(net 459 "3V3_SYS")
			(pintype "passive")
		)
		(pad "2" smd roundrect
			(at 0.484 0 180)
			(size 0.59 0.64)
			(layers "B.Cu" "B.Mask" "B.Paste")
			(roundrect_rratio 0.25)
			(net 5 "GND")
			(pintype "passive")
		)
	)
	(footprint "antmicro-footprints:C_0402_1005Metric"
		(layer "B.Cu")
		(at 150.2156 99.2632 90)
		(descr "Capacitor SMD 0402")
		(tags "capacitor SMD 0402")
		(property "Reference" "C3"
			(at 0.7632 -0.5156 270)
			(layer "B.SilkS")
			(effects
				(font
					(size 0.7 0.7)
					(thickness 0.15)
				)
				(justify left bottom mirror)
			)
		)
		(property "Value" "C_100n_6V3_0402"
			(at 0 -1.4 270)
			(layer "B.Fab")
			(effects
				(font
					(size 0.7 0.7)
					(thickness 0.15)
				)
				(justify left bottom mirror)
			)
		)
		(property "Description" " "
			(at 0 0 90)
			(layer "F.Fab")
			(hide yes)
			(effects
				(font
					(size 1.27 1.27)
					(thickness 0.15)
				)
			)
		)
		(property "Author" "Antmicro"
			(at 249.4788 -50.9524 0)
			(layer "B.Fab")
			(hide yes)
			(effects
				(font
					(size 1 1)
					(thickness 0.15)
				)
				(justify mirror)
			)
		)
		(property "Dielectric" ""
			(at 249.4788 -50.9524 0)
			(layer "B.Fab")
			(hide yes)
			(effects
				(font
					(size 1 1)
					(thickness 0.15)
				)
				(justify mirror)
			)
		)
		(property "License" "Apache-2.0"
			(at 249.4788 -50.9524 0)
			(layer "B.Fab")
			(hide yes)
			(effects
				(font
					(size 1 1)
					(thickness 0.15)
				)
				(justify mirror)
			)
		)
		(property "MPN" "0402X104K6R3CT"
			(at 249.4788 -50.9524 0)
			(layer "B.Fab")
			(hide yes)
			(effects
				(font
					(size 1 1)
					(thickness 0.15)
				)
				(justify mirror)
			)
		)
		(property "Manufacturer" "Walsin"
			(at 249.4788 -50.9524 0)
			(layer "B.Fab")
			(hide yes)
			(effects
				(font
					(size 1 1)
					(thickness 0.15)
				)
				(justify mirror)
			)
		)
		(property "Val" "100n"
			(at 249.4788 -50.9524 0)
			(layer "B.Fab")
			(hide yes)
			(effects
				(font
					(size 1 1)
					(thickness 0.15)
				)
				(justify mirror)
			)
		)
		(property "Voltage" ""
			(at 249.4788 -50.9524 0)
			(layer "B.Fab")
			(hide yes)
			(effects
				(font
					(size 1 1)
					(thickness 0.15)
				)
				(justify mirror)
			)
		)
		(sheetname "HyperRAM")
		(sheetfile "hyperram.kicad_sch")
		(attr smd)
		(fp_rect
			(start -0.94 0.47)
			(end 0.94 -0.47)
			(stroke
				(width 0.05)
				(type solid)
			)
			(fill no)
			(layer "B.CrtYd")
		)
		(fp_rect
			(start -0.499 0.249)
			(end 0.499 -0.249)
			(stroke
				(width 0.15)
				(type solid)
			)
			(fill no)
			(layer "B.Fab")
		)
		(pad "1" smd roundrect
			(at -0.484 0 90)
			(size 0.59 0.64)
			(layers "B.Cu" "B.Mask" "B.Paste")
			(roundrect_rratio 0.25)
			(net 459 "3V3_SYS")
			(pintype "passive")
		)
		(pad "2" smd roundrect
			(at 0.484 0 90)
			(size 0.59 0.64)
			(layers "B.Cu" "B.Mask" "B.Paste")
			(roundrect_rratio 0.25)
			(net 5 "GND")
			(pintype "passive")
		)
	)
	(footprint "antmicro-footprints:C_0402_1005Metric"
		(layer "B.Cu")
		(at 150.9014 96.7232 -90)
		(descr "Capacitor SMD 0402")
		(tags "capacitor SMD 0402")
		(property "Reference" "C4"
			(at -0.7232 0.5014 90)
			(layer "B.SilkS")
			(effects
				(font
					(size 0.7 0.7)
					(thickness 0.15)
				)
				(justify left bottom mirror)
			)
		)
		(property "Value" "C_100n_6V3_0402"
			(at 0 -1.4 90)
			(layer "B.Fab")
			(effects
				(font
					(size 0.7 0.7)
					(thickness 0.15)
				)
				(justify left bottom mirror)
			)
		)
		(property "Description" " "
			(at 0 0 270)
			(layer "F.Fab")
			(hide yes)
			(effects
				(font
					(size 1.27 1.27)
					(thickness 0.15)
				)
			)
		)
		(property "Author" "Antmicro"
			(at 54.1782 247.6246 0)
			(layer "B.Fab")
			(hide yes)
			(effects
				(font
					(size 1 1)
					(thickness 0.15)
				)
				(justify mirror)
			)
		)
		(property "Dielectric" ""
			(at 54.1782 247.6246 0)
			(layer "B.Fab")
			(hide yes)
			(effects
				(font
					(size 1 1)
					(thickness 0.15)
				)
				(justify mirror)
			)
		)
		(property "License" "Apache-2.0"
			(at 54.1782 247.6246 0)
			(layer "B.Fab")
			(hide yes)
			(effects
				(font
					(size 1 1)
					(thickness 0.15)
				)
				(justify mirror)
			)
		)
		(property "MPN" "0402X104K6R3CT"
			(at 54.1782 247.6246 0)
			(layer "B.Fab")
			(hide yes)
			(effects
				(font
					(size 1 1)
					(thickness 0.15)
				)
				(justify mirror)
			)
		)
		(property "Manufacturer" "Walsin"
			(at 54.1782 247.6246 0)
			(layer "B.Fab")
			(hide yes)
			(effects
				(font
					(size 1 1)
					(thickness 0.15)
				)
				(justify mirror)
			)
		)
		(property "Val" "100n"
			(at 54.1782 247.6246 0)
			(layer "B.Fab")
			(hide yes)
			(effects
				(font
					(size 1 1)
					(thickness 0.15)
				)
				(justify mirror)
			)
		)
		(property "Voltage" ""
			(at 54.1782 247.6246 0)
			(layer "B.Fab")
			(hide yes)
			(effects
				(font
					(size 1 1)
					(thickness 0.15)
				)
				(justify mirror)
			)
		)
		(sheetname "HyperRAM")
		(sheetfile "hyperram.kicad_sch")
		(attr smd)
		(fp_rect
			(start -0.94 0.47)
			(end 0.94 -0.47)
			(stroke
				(width 0.05)
				(type solid)
			)
			(fill no)
			(layer "B.CrtYd")
		)
		(fp_rect
			(start -0.499 0.249)
			(end 0.499 -0.249)
			(stroke
				(width 0.15)
				(type solid)
			)
			(fill no)
			(layer "B.Fab")
		)
		(pad "1" smd roundrect
			(at -0.484 0 270)
			(size 0.59 0.64)
			(layers "B.Cu" "B.Mask" "B.Paste")
			(roundrect_rratio 0.25)
			(net 459 "3V3_SYS")
			(pintype "passive")
		)
		(pad "2" smd roundrect
			(at 0.484 0 270)
			(size 0.59 0.64)
			(layers "B.Cu" "B.Mask" "B.Paste")
			(roundrect_rratio 0.25)
			(net 5 "GND")
			(pintype "passive")
		)
	)
	(footprint "antmicro-footprints:C_0603_1608Metric"
		(layer "B.Cu")
		(at 173 81.8)
		(descr "Capacitor SMD 0603")
		(tags "capacitor 0603")
		(property "Reference" "C134"
			(at 1.4 1.4 180)
			(layer "B.SilkS")
			(effects
				(font
					(size 0.7 0.7)
					(thickness 0.15)
				)
				(justify left bottom mirror)
			)
		)
		(property "Value" "C_10n_0603"
			(at 0 -1.6 180)
			(layer "B.Fab")
			(effects
				(font
					(size 0.7 0.7)
					(thickness 0.15)
				)
				(justify left bottom mirror)
			)
		)
		(property "Description" " "
			(at 0 0 0)
			(layer "F.Fab")
			(hide yes)
			(effects
				(font
					(size 1.27 1.27)
					(thickness 0.15)
				)
			)
		)
		(property "Author" "Antmicro"
			(at 0 0 0)
			(layer "B.Fab")
			(hide yes)
			(effects
				(font
					(size 1 1)
					(thickness 0.15)
				)
				(justify mirror)
			)
		)
		(property "Dielectric" ""
			(at 0 0 0)
			(layer "B.Fab")
			(hide yes)
			(effects
				(font
					(size 1 1)
					(thickness 0.15)
				)
				(justify mirror)
			)
		)
		(property "License" "Apache-2.0"
			(at 0 0 0)
			(layer "B.Fab")
			(hide yes)
			(effects
				(font
					(size 1 1)
					(thickness 0.15)
				)
				(justify mirror)
			)
		)
		(property "MPN" "06031C103JAT2A"
			(at 0 0 0)
			(layer "B.Fab")
			(hide yes)
			(effects
				(font
					(size 1 1)
					(thickness 0.15)
				)
				(justify mirror)
			)
		)
		(property "Manufacturer" "AVX"
			(at 0 0 0)
			(layer "B.Fab")
			(hide yes)
			(effects
				(font
					(size 1 1)
					(thickness 0.15)
				)
				(justify mirror)
			)
		)
		(property "Val" "10n"
			(at 0 0 0)
			(layer "B.Fab")
			(hide yes)
			(effects
				(font
					(size 1 1)
					(thickness 0.15)
				)
				(justify mirror)
			)
		)
		(property "Voltage" ""
			(at 0 0 0)
			(layer "B.Fab")
			(hide yes)
			(effects
				(font
					(size 1 1)
					(thickness 0.15)
				)
				(justify mirror)
			)
		)
		(sheetname "Supply")
		(sheetfile "supply.kicad_sch")
		(attr smd)
		(fp_line
			(start -0.3 -0.3)
			(end 0.3 -0.3)
			(stroke
				(width 0.15)
				(type solid)
			)
			(layer "B.SilkS")
		)
		(fp_line
			(start -0.3 0.3)
			(end 0.3 0.3)
			(stroke
				(width 0.15)
				(type solid)
			)
			(layer "B.SilkS")
		)
		(fp_rect
			(start -1.24 0.7)
			(end 1.24 -0.7)
			(stroke
				(width 0.05)
				(type solid)
			)
			(fill no)
			(layer "B.CrtYd")
		)
		(fp_rect
			(start -0.8 0.4)
			(end 0.8 -0.4)
			(stroke
				(width 0.15)
				(type solid)
			)
			(fill no)
			(layer "B.Fab")
		)
		(pad "1" smd roundrect
			(at -0.7 0)
			(size 0.6 0.8)
			(layers "B.Cu" "B.Mask" "B.Paste")
			(roundrect_rratio 0.2)
			(net 66 "VDDQ")
			(pintype "passive")
		)
		(pad "2" smd roundrect
			(at 0.7 0)
			(size 0.6 0.8)
			(layers "B.Cu" "B.Mask" "B.Paste")
			(roundrect_rratio 0.2)
			(net 5 "GND")
			(pintype "passive")
		)
	)
	(footprint "antmicro-footprints:C_0603_1608Metric"
		(layer "B.Cu")
		(at 156.9 84.875 90)
		(descr "Capacitor SMD 0603")
		(tags "capacitor 0603")
		(property "Reference" "C143"
			(at 1.575 -0.6 270)
			(layer "B.SilkS")
			(effects
				(font
					(size 0.7 0.7)
					(thickness 0.15)
				)
				(justify left bottom mirror)
			)
		)
		(property "Value" "C_10n_0603"
			(at 0 -1.6 270)
			(layer "B.Fab")
			(effects
				(font
					(size 0.7 0.7)
					(thickness 0.15)
				)
				(justify left bottom mirror)
			)
		)
		(property "Description" " "
			(at 0 0 90)
			(layer "F.Fab")
			(hide yes)
			(effects
				(font
					(size 1.27 1.27)
					(thickness 0.15)
				)
			)
		)
		(property "Author" "Antmicro"
			(at 241.775 -72.025 0)
			(layer "B.Fab")
			(hide yes)
			(effects
				(font
					(size 1 1)
					(thickness 0.15)
				)
				(justify mirror)
			)
		)
		(property "Dielectric" ""
			(at 241.775 -72.025 0)
			(layer "B.Fab")
			(hide yes)
			(effects
				(font
					(size 1 1)
					(thickness 0.15)
				)
				(justify mirror)
			)
		)
		(property "License" "Apache-2.0"
			(at 241.775 -72.025 0)
			(layer "B.Fab")
			(hide yes)
			(effects
				(font
					(size 1 1)
					(thickness 0.15)
				)
				(justify mirror)
			)
		)
		(property "MPN" "06031C103JAT2A"
			(at 241.775 -72.025 0)
			(layer "B.Fab")
			(hide yes)
			(effects
				(font
					(size 1 1)
					(thickness 0.15)
				)
				(justify mirror)
			)
		)
		(property "Manufacturer" "AVX"
			(at 241.775 -72.025 0)
			(layer "B.Fab")
			(hide yes)
			(effects
				(font
					(size 1 1)
					(thickness 0.15)
				)
				(justify mirror)
			)
		)
		(property "Val" "10n"
			(at 241.775 -72.025 0)
			(layer "B.Fab")
			(hide yes)
			(effects
				(font
					(size 1 1)
					(thickness 0.15)
				)
				(justify mirror)
			)
		)
		(property "Voltage" ""
			(at 241.775 -72.025 0)
			(layer "B.Fab")
			(hide yes)
			(effects
				(font
					(size 1 1)
					(thickness 0.15)
				)
				(justify mirror)
			)
		)
		(sheetname "Supply")
		(sheetfile "supply.kicad_sch")
		(attr smd)
		(fp_line
			(start -0.3 -0.3)
			(end 0.3 -0.3)
			(stroke
				(width 0.15)
				(type solid)
			)
			(layer "B.SilkS")
		)
		(fp_line
			(start -0.3 0.3)
			(end 0.3 0.3)
			(stroke
				(width 0.15)
				(type solid)
			)
			(layer "B.SilkS")
		)
		(fp_rect
			(start -1.24 0.7)
			(end 1.24 -0.7)
			(stroke
				(width 0.05)
				(type solid)
			)
			(fill no)
			(layer "B.CrtYd")
		)
		(fp_rect
			(start -0.8 0.4)
			(end 0.8 -0.4)
			(stroke
				(width 0.15)
				(type solid)
			)
			(fill no)
			(layer "B.Fab")
		)
		(pad "1" smd roundrect
			(at -0.7 0 90)
			(size 0.6 0.8)
			(layers "B.Cu" "B.Mask" "B.Paste")
			(roundrect_rratio 0.2)
			(net 66 "VDDQ")
			(pintype "passive")
		)
		(pad "2" smd roundrect
			(at 0.7 0 90)
			(size 0.6 0.8)
			(layers "B.Cu" "B.Mask" "B.Paste")
			(roundrect_rratio 0.2)
			(net 5 "GND")
			(pintype "passive")
		)
	)
	(footprint "antmicro-footprints:C_0603_1608Metric"
		(layer "B.Cu")
		(at 177.85 66.5 90)
		(descr "Capacitor SMD 0603")
		(tags "capacitor 0603")
		(property "Reference" "C149"
			(at 1.4 1.35 270)
			(layer "B.SilkS")
			(effects
				(font
					(size 0.7 0.7)
					(thickness 0.15)
				)
				(justify left bottom mirror)
			)
		)
		(property "Value" "C_10n_0603"
			(at 0 -1.6 270)
			(layer "B.Fab")
			(effects
				(font
					(size 0.7 0.7)
					(thickness 0.15)
				)
				(justify left bottom mirror)
			)
		)
		(property "Description" " "
			(at 0 0 90)
			(layer "F.Fab")
			(hide yes)
			(effects
				(font
					(size 1.27 1.27)
					(thickness 0.15)
				)
			)
		)
		(property "Author" "Antmicro"
			(at 244.35 -111.35 0)
			(layer "B.Fab")
			(hide yes)
			(effects
				(font
					(size 1 1)
					(thickness 0.15)
				)
				(justify mirror)
			)
		)
		(property "Dielectric" ""
			(at 244.35 -111.35 0)
			(layer "B.Fab")
			(hide yes)
			(effects
				(font
					(size 1 1)
					(thickness 0.15)
				)
				(justify mirror)
			)
		)
		(property "License" "Apache-2.0"
			(at 244.35 -111.35 0)
			(layer "B.Fab")
			(hide yes)
			(effects
				(font
					(size 1 1)
					(thickness 0.15)
				)
				(justify mirror)
			)
		)
		(property "MPN" "06031C103JAT2A"
			(at 244.35 -111.35 0)
			(layer "B.Fab")
			(hide yes)
			(effects
				(font
					(size 1 1)
					(thickness 0.15)
				)
				(justify mirror)
			)
		)
		(property "Manufacturer" "AVX"
			(at 244.35 -111.35 0)
			(layer "B.Fab")
			(hide yes)
			(effects
				(font
					(size 1 1)
					(thickness 0.15)
				)
				(justify mirror)
			)
		)
		(property "Val" "10n"
			(at 244.35 -111.35 0)
			(layer "B.Fab")
			(hide yes)
			(effects
				(font
					(size 1 1)
					(thickness 0.15)
				)
				(justify mirror)
			)
		)
		(property "Voltage" ""
			(at 244.35 -111.35 0)
			(layer "B.Fab")
			(hide yes)
			(effects
				(font
					(size 1 1)
					(thickness 0.15)
				)
				(justify mirror)
			)
		)
		(sheetname "Supply")
		(sheetfile "supply.kicad_sch")
		(attr smd)
		(fp_line
			(start -0.3 -0.3)
			(end 0.3 -0.3)
			(stroke
				(width 0.15)
				(type solid)
			)
			(layer "B.SilkS")
		)
		(fp_line
			(start -0.3 0.3)
			(end 0.3 0.3)
			(stroke
				(width 0.15)
				(type solid)
			)
			(layer "B.SilkS")
		)
		(fp_rect
			(start -1.24 0.7)
			(end 1.24 -0.7)
			(stroke
				(width 0.05)
				(type solid)
			)
			(fill no)
			(layer "B.CrtYd")
		)
		(fp_rect
			(start -0.8 0.4)
			(end 0.8 -0.4)
			(stroke
				(width 0.15)
				(type solid)
			)
			(fill no)
			(layer "B.Fab")
		)
		(pad "1" smd roundrect
			(at -0.7 0 90)
			(size 0.6 0.8)
			(layers "B.Cu" "B.Mask" "B.Paste")
			(roundrect_rratio 0.2)
			(net 641 "1V8_DDR")
			(pintype "passive")
		)
		(pad "2" smd roundrect
			(at 0.7 0 90)
			(size 0.6 0.8)
			(layers "B.Cu" "B.Mask" "B.Paste")
			(roundrect_rratio 0.2)
			(net 5 "GND")
			(pintype "passive")
		)
	)
	(footprint "antmicro-footprints:C_0603_1608Metric"
		(layer "B.Cu")
		(at 182.136328 97.897157)
		(descr "Capacitor SMD 0603")
		(tags "capacitor 0603")
		(property "Reference" "C151"
			(at 1.363672 1.402843 180)
			(layer "B.SilkS")
			(effects
				(font
					(size 0.7 0.7)
					(thickness 0.15)
				)
				(justify left bottom mirror)
			)
		)
		(property "Value" "C_10n_0603"
			(at 0 -1.6 180)
			(layer "B.Fab")
			(effects
				(font
					(size 0.7 0.7)
					(thickness 0.15)
				)
				(justify left bottom mirror)
			)
		)
		(property "Description" " "
			(at 0 0 0)
			(layer "F.Fab")
			(hide yes)
			(effects
				(font
					(size 1.27 1.27)
					(thickness 0.15)
				)
			)
		)
		(property "Author" "Antmicro"
			(at 0 0 0)
			(layer "B.Fab")
			(hide yes)
			(effects
				(font
					(size 1 1)
					(thickness 0.15)
				)
				(justify mirror)
			)
		)
		(property "Dielectric" ""
			(at 0 0 0)
			(layer "B.Fab")
			(hide yes)
			(effects
				(font
					(size 1 1)
					(thickness 0.15)
				)
				(justify mirror)
			)
		)
		(property "License" "Apache-2.0"
			(at 0 0 0)
			(layer "B.Fab")
			(hide yes)
			(effects
				(font
					(size 1 1)
					(thickness 0.15)
				)
				(justify mirror)
			)
		)
		(property "MPN" "06031C103JAT2A"
			(at 0 0 0)
			(layer "B.Fab")
			(hide yes)
			(effects
				(font
					(size 1 1)
					(thickness 0.15)
				)
				(justify mirror)
			)
		)
		(property "Manufacturer" "AVX"
			(at 0 0 0)
			(layer "B.Fab")
			(hide yes)
			(effects
				(font
					(size 1 1)
					(thickness 0.15)
				)
				(justify mirror)
			)
		)
		(property "Val" "10n"
			(at 0 0 0)
			(layer "B.Fab")
			(hide yes)
			(effects
				(font
					(size 1 1)
					(thickness 0.15)
				)
				(justify mirror)
			)
		)
		(property "Voltage" ""
			(at 0 0 0)
			(layer "B.Fab")
			(hide yes)
			(effects
				(font
					(size 1 1)
					(thickness 0.15)
				)
				(justify mirror)
			)
		)
		(sheetname "Supply")
		(sheetfile "supply.kicad_sch")
		(attr smd)
		(fp_line
			(start -0.3 -0.3)
			(end 0.3 -0.3)
			(stroke
				(width 0.15)
				(type solid)
			)
			(layer "B.SilkS")
		)
		(fp_line
			(start -0.3 0.3)
			(end 0.3 0.3)
			(stroke
				(width 0.15)
				(type solid)
			)
			(layer "B.SilkS")
		)
		(fp_rect
			(start -1.24 0.7)
			(end 1.24 -0.7)
			(stroke
				(width 0.05)
				(type solid)
			)
			(fill no)
			(layer "B.CrtYd")
		)
		(fp_rect
			(start -0.8 0.4)
			(end 0.8 -0.4)
			(stroke
				(width 0.15)
				(type solid)
			)
			(fill no)
			(layer "B.Fab")
		)
		(pad "1" smd roundrect
			(at -0.7 0)
			(size 0.6 0.8)
			(layers "B.Cu" "B.Mask" "B.Paste")
			(roundrect_rratio 0.2)
			(net 460 "1V8_SYS")
			(pintype "passive")
		)
		(pad "2" smd roundrect
			(at 0.7 0)
			(size 0.6 0.8)
			(layers "B.Cu" "B.Mask" "B.Paste")
			(roundrect_rratio 0.2)
			(net 5 "GND")
			(pintype "passive")
		)
	)
	(footprint "antmicro-footprints:C_0603_1608Metric"
		(layer "B.Cu")
		(at 182.236328 86.597157)
		(descr "Capacitor SMD 0603")
		(tags "capacitor 0603")
		(property "Reference" "C147"
			(at 1.4 1.4 180)
			(layer "B.SilkS")
			(effects
				(font
					(size 0.7 0.7)
					(thickness 0.15)
				)
				(justify left bottom mirror)
			)
		)
		(property "Value" "C_10n_0603"
			(at 0 -1.6 180)
			(layer "B.Fab")
			(effects
				(font
					(size 0.7 0.7)
					(thickness 0.15)
				)
				(justify left bottom mirror)
			)
		)
		(property "Description" " "
			(at 0 0 0)
			(layer "F.Fab")
			(hide yes)
			(effects
				(font
					(size 1.27 1.27)
					(thickness 0.15)
				)
			)
		)
		(property "Author" "Antmicro"
			(at 0 0 0)
			(layer "B.Fab")
			(hide yes)
			(effects
				(font
					(size 1 1)
					(thickness 0.15)
				)
				(justify mirror)
			)
		)
		(property "Dielectric" ""
			(at 0 0 0)
			(layer "B.Fab")
			(hide yes)
			(effects
				(font
					(size 1 1)
					(thickness 0.15)
				)
				(justify mirror)
			)
		)
		(property "License" "Apache-2.0"
			(at 0 0 0)
			(layer "B.Fab")
			(hide yes)
			(effects
				(font
					(size 1 1)
					(thickness 0.15)
				)
				(justify mirror)
			)
		)
		(property "MPN" "06031C103JAT2A"
			(at 0 0 0)
			(layer "B.Fab")
			(hide yes)
			(effects
				(font
					(size 1 1)
					(thickness 0.15)
				)
				(justify mirror)
			)
		)
		(property "Manufacturer" "AVX"
			(at 0 0 0)
			(layer "B.Fab")
			(hide yes)
			(effects
				(font
					(size 1 1)
					(thickness 0.15)
				)
				(justify mirror)
			)
		)
		(property "Val" "10n"
			(at 0 0 0)
			(layer "B.Fab")
			(hide yes)
			(effects
				(font
					(size 1 1)
					(thickness 0.15)
				)
				(justify mirror)
			)
		)
		(property "Voltage" ""
			(at 0 0 0)
			(layer "B.Fab")
			(hide yes)
			(effects
				(font
					(size 1 1)
					(thickness 0.15)
				)
				(justify mirror)
			)
		)
		(sheetname "Supply")
		(sheetfile "supply.kicad_sch")
		(attr smd)
		(fp_line
			(start -0.3 -0.3)
			(end 0.3 -0.3)
			(stroke
				(width 0.15)
				(type solid)
			)
			(layer "B.SilkS")
		)
		(fp_line
			(start -0.3 0.3)
			(end 0.3 0.3)
			(stroke
				(width 0.15)
				(type solid)
			)
			(layer "B.SilkS")
		)
		(fp_rect
			(start -1.24 0.7)
			(end 1.24 -0.7)
			(stroke
				(width 0.05)
				(type solid)
			)
			(fill no)
			(layer "B.CrtYd")
		)
		(fp_rect
			(start -0.8 0.4)
			(end 0.8 -0.4)
			(stroke
				(width 0.15)
				(type solid)
			)
			(fill no)
			(layer "B.Fab")
		)
		(pad "1" smd roundrect
			(at -0.7 0)
			(size 0.6 0.8)
			(layers "B.Cu" "B.Mask" "B.Paste")
			(roundrect_rratio 0.2)
			(net 460 "1V8_SYS")
			(pintype "passive")
		)
		(pad "2" smd roundrect
			(at 0.7 0)
			(size 0.6 0.8)
			(layers "B.Cu" "B.Mask" "B.Paste")
			(roundrect_rratio 0.2)
			(net 5 "GND")
			(pintype "passive")
		)
	)
	(footprint "antmicro-footprints:C_0402_1005Metric"
		(layer "B.Cu")
		(at 173.5 105.125 180)
		(descr "Capacitor SMD 0402")
		(tags "capacitor SMD 0402")
		(property "Reference" "C89"
			(at -1.2 -1.275 0)
			(layer "B.SilkS")
			(effects
				(font
					(size 0.7 0.7)
					(thickness 0.15)
				)
				(justify left bottom mirror)
			)
		)
		(property "Value" "C_4u7_0402"
			(at 0 -1.4 0)
			(layer "B.Fab")
			(effects
				(font
					(size 0.7 0.7)
					(thickness 0.15)
				)
				(justify left bottom mirror)
			)
		)
		(property "Description" " "
			(at 0 0 180)
			(layer "F.Fab")
			(hide yes)
			(effects
				(font
					(size 1.27 1.27)
					(thickness 0.15)
				)
			)
		)
		(property "Author" "Antmicro"
			(at 347 210.25 0)
			(layer "B.Fab")
			(hide yes)
			(effects
				(font
					(size 1 1)
					(thickness 0.15)
				)
				(justify mirror)
			)
		)
		(property "Dielectric" ""
			(at 347 210.25 0)
			(layer "B.Fab")
			(hide yes)
			(effects
				(font
					(size 1 1)
					(thickness 0.15)
				)
				(justify mirror)
			)
		)
		(property "License" "Apache-2.0"
			(at 347 210.25 0)
			(layer "B.Fab")
			(hide yes)
			(effects
				(font
					(size 1 1)
					(thickness 0.15)
				)
				(justify mirror)
			)
		)
		(property "MPN" "GRM155R61A475MEAAD"
			(at 347 210.25 0)
			(layer "B.Fab")
			(hide yes)
			(effects
				(font
					(size 1 1)
					(thickness 0.15)
				)
				(justify mirror)
			)
		)
		(property "Manufacturer" "Murata"
			(at 347 210.25 0)
			(layer "B.Fab")
			(hide yes)
			(effects
				(font
					(size 1 1)
					(thickness 0.15)
				)
				(justify mirror)
			)
		)
		(property "Val" "4u7"
			(at 347 210.25 0)
			(layer "B.Fab")
			(hide yes)
			(effects
				(font
					(size 1 1)
					(thickness 0.15)
				)
				(justify mirror)
			)
		)
		(property "Voltage" ""
			(at 347 210.25 0)
			(layer "B.Fab")
			(hide yes)
			(effects
				(font
					(size 1 1)
					(thickness 0.15)
				)
				(justify mirror)
			)
		)
		(sheetname "FPGA power")
		(sheetfile "fpga-power.kicad_sch")
		(attr smd)
		(fp_rect
			(start -0.94 0.47)
			(end 0.94 -0.47)
			(stroke
				(width 0.05)
				(type solid)
			)
			(fill no)
			(layer "B.CrtYd")
		)
		(fp_rect
			(start -0.499 0.249)
			(end 0.499 -0.249)
			(stroke
				(width 0.15)
				(type solid)
			)
			(fill no)
			(layer "B.Fab")
		)
		(pad "1" smd roundrect
			(at -0.484 0 180)
			(size 0.59 0.64)
			(layers "B.Cu" "B.Mask" "B.Paste")
			(roundrect_rratio 0.25)
			(net 459 "3V3_SYS")
			(pintype "passive")
		)
		(pad "2" smd roundrect
			(at 0.484 0 180)
			(size 0.59 0.64)
			(layers "B.Cu" "B.Mask" "B.Paste")
			(roundrect_rratio 0.25)
			(net 5 "GND")
			(pintype "passive")
		)
	)
	(footprint "antmicro-footprints:R_0603_1608Metric"
		(layer "B.Cu")
		(at 156.936328 87.797157 90)
		(descr "Resistor SMD 0603")
		(tags "resistor SMD 0603")
		(property "Reference" "R6"
			(at 0.697157 -0.636328 270)
			(layer "B.SilkS")
			(effects
				(font
					(size 0.7 0.7)
					(thickness 0.15)
				)
				(justify left bottom mirror)
			)
		)
		(property "Value" "R_1k_0603"
			(at 0 -1.6 270)
			(layer "B.Fab")
			(effects
				(font
					(size 0.7 0.7)
					(thickness 0.15)
				)
				(justify left bottom mirror)
			)
		)
		(property "Description" "1k resistor in 0603 package with 1% tolerance"
			(at 0 0 90)
			(layer "F.Fab")
			(hide yes)
			(effects
				(font
					(size 1.27 1.27)
					(thickness 0.15)
				)
			)
		)
		(property "Author" "Antmicro"
			(at 244.733485 -69.139171 0)
			(layer "B.Fab")
			(hide yes)
			(effects
				(font
					(size 1 1)
					(thickness 0.15)
				)
				(justify mirror)
			)
		)
		(property "License" "Apache-2.0"
			(at 244.733485 -69.139171 0)
			(layer "B.Fab")
			(hide yes)
			(effects
				(font
					(size 1 1)
					(thickness 0.15)
				)
				(justify mirror)
			)
		)
		(property "MPN" "CR0603-FX-1001ELF"
			(at 244.733485 -69.139171 0)
			(layer "B.Fab")
			(hide yes)
			(effects
				(font
					(size 1 1)
					(thickness 0.15)
				)
				(justify mirror)
			)
		)
		(property "Manufacturer" "Bourns"
			(at 244.733485 -69.139171 0)
			(layer "B.Fab")
			(hide yes)
			(effects
				(font
					(size 1 1)
					(thickness 0.15)
				)
				(justify mirror)
			)
		)
		(property "Tolerance" "1%"
			(at 244.733485 -69.139171 0)
			(layer "B.Fab")
			(hide yes)
			(effects
				(font
					(size 1 1)
					(thickness 0.15)
				)
				(justify mirror)
			)
		)
		(property "Val" "1k"
			(at 244.733485 -69.139171 0)
			(layer "B.Fab")
			(hide yes)
			(effects
				(font
					(size 1 1)
					(thickness 0.15)
				)
				(justify mirror)
			)
		)
		(sheetname "FPGA Banks")
		(sheetfile "fpga-banks.kicad_sch")
		(attr smd)
		(fp_line
			(start -0.3 -0.3)
			(end 0.3 -0.3)
			(stroke
				(width 0.15)
				(type solid)
			)
			(layer "B.SilkS")
		)
		(fp_line
			(start -0.3 0.3)
			(end 0.3 0.3)
			(stroke
				(width 0.15)
				(type solid)
			)
			(layer "B.SilkS")
		)
		(fp_rect
			(start -1.25 0.7)
			(end 1.25 -0.7)
			(stroke
				(width 0.05)
				(type solid)
			)
			(fill no)
			(layer "B.CrtYd")
		)
		(fp_rect
			(start -0.8 0.4)
			(end 0.8 -0.4)
			(stroke
				(width 0.15)
				(type solid)
			)
			(fill no)
			(layer "B.Fab")
		)
		(pad "1" smd roundrect
			(at -0.7 0 90)
			(size 0.6 0.8)
			(layers "B.Cu" "B.Mask" "B.Paste")
			(roundrect_rratio 0.2)
			(net 510 "VREF_34")
			(pintype "passive")
		)
		(pad "2" smd roundrect
			(at 0.7 0 90)
			(size 0.6 0.8)
			(layers "B.Cu" "B.Mask" "B.Paste")
			(roundrect_rratio 0.2)
			(net 5 "GND")
			(pintype "passive")
		)
	)
	(footprint "antmicro-footprints:C_0402_1005Metric"
		(layer "B.Cu")
		(at 160.536328 89.797157)
		(descr "Capacitor SMD 0402")
		(tags "capacitor SMD 0402")
		(property "Reference" "C6"
			(at 0.763672 -0.497157 180)
			(layer "B.SilkS")
			(effects
				(font
					(size 0.7 0.7)
					(thickness 0.15)
				)
				(justify left bottom mirror)
			)
		)
		(property "Value" "C_100n_6V3_0402"
			(at 0 -1.4 180)
			(layer "B.Fab")
			(effects
				(font
					(size 0.7 0.7)
					(thickness 0.15)
				)
				(justify left bottom mirror)
			)
		)
		(property "Description" " "
			(at 0 0 0)
			(layer "F.Fab")
			(hide yes)
			(effects
				(font
					(size 1.27 1.27)
					(thickness 0.15)
				)
			)
		)
		(property "Author" "Antmicro"
			(at 0 0 0)
			(layer "B.Fab")
			(hide yes)
			(effects
				(font
					(size 1 1)
					(thickness 0.15)
				)
				(justify mirror)
			)
		)
		(property "Dielectric" ""
			(at 0 0 0)
			(layer "B.Fab")
			(hide yes)
			(effects
				(font
					(size 1 1)
					(thickness 0.15)
				)
				(justify mirror)
			)
		)
		(property "License" "Apache-2.0"
			(at 0 0 0)
			(layer "B.Fab")
			(hide yes)
			(effects
				(font
					(size 1 1)
					(thickness 0.15)
				)
				(justify mirror)
			)
		)
		(property "MPN" "0402X104K6R3CT"
			(at 0 0 0)
			(layer "B.Fab")
			(hide yes)
			(effects
				(font
					(size 1 1)
					(thickness 0.15)
				)
				(justify mirror)
			)
		)
		(property "Manufacturer" "Walsin"
			(at 0 0 0)
			(layer "B.Fab")
			(hide yes)
			(effects
				(font
					(size 1 1)
					(thickness 0.15)
				)
				(justify mirror)
			)
		)
		(property "Val" "100n"
			(at 0 0 0)
			(layer "B.Fab")
			(hide yes)
			(effects
				(font
					(size 1 1)
					(thickness 0.15)
				)
				(justify mirror)
			)
		)
		(property "Voltage" ""
			(at 0 0 0)
			(layer "B.Fab")
			(hide yes)
			(effects
				(font
					(size 1 1)
					(thickness 0.15)
				)
				(justify mirror)
			)
		)
		(sheetname "FPGA Banks")
		(sheetfile "fpga-banks.kicad_sch")
		(attr smd)
		(fp_rect
			(start -0.94 0.47)
			(end 0.94 -0.47)
			(stroke
				(width 0.05)
				(type solid)
			)
			(fill no)
			(layer "B.CrtYd")
		)
		(fp_rect
			(start -0.499 0.249)
			(end 0.499 -0.249)
			(stroke
				(width 0.15)
				(type solid)
			)
			(fill no)
			(layer "B.Fab")
		)
		(pad "1" smd roundrect
			(at -0.484 0)
			(size 0.59 0.64)
			(layers "B.Cu" "B.Mask" "B.Paste")
			(roundrect_rratio 0.25)
			(net 5 "GND")
			(pintype "passive")
		)
		(pad "2" smd roundrect
			(at 0.484 0)
			(size 0.59 0.64)
			(layers "B.Cu" "B.Mask" "B.Paste")
			(roundrect_rratio 0.25)
			(net 510 "VREF_34")
			(pintype "passive")
		)
	)
	(footprint "antmicro-footprints:C_0402_1005Metric"
		(layer "B.Cu")
		(at 169.036328 90.097157 90)
		(descr "Capacitor SMD 0402")
		(tags "capacitor SMD 0402")
		(property "Reference" "C7"
			(at 2.297157 0.463672 270)
			(layer "B.SilkS")
			(effects
				(font
					(size 0.7 0.7)
					(thickness 0.15)
				)
				(justify left bottom mirror)
			)
		)
		(property "Value" "C_100n_6V3_0402"
			(at 0 -1.4 270)
			(layer "B.Fab")
			(effects
				(font
					(size 0.7 0.7)
					(thickness 0.15)
				)
				(justify left bottom mirror)
			)
		)
		(property "Description" " "
			(at 0 0 90)
			(layer "F.Fab")
			(hide yes)
			(effects
				(font
					(size 1.27 1.27)
					(thickness 0.15)
				)
			)
		)
		(property "Author" "Antmicro"
			(at 259.133485 -78.939171 0)
			(layer "B.Fab")
			(hide yes)
			(effects
				(font
					(size 1 1)
					(thickness 0.15)
				)
				(justify mirror)
			)
		)
		(property "Dielectric" ""
			(at 259.133485 -78.939171 0)
			(layer "B.Fab")
			(hide yes)
			(effects
				(font
					(size 1 1)
					(thickness 0.15)
				)
				(justify mirror)
			)
		)
		(property "License" "Apache-2.0"
			(at 259.133485 -78.939171 0)
			(layer "B.Fab")
			(hide yes)
			(effects
				(font
					(size 1 1)
					(thickness 0.15)
				)
				(justify mirror)
			)
		)
		(property "MPN" "0402X104K6R3CT"
			(at 259.133485 -78.939171 0)
			(layer "B.Fab")
			(hide yes)
			(effects
				(font
					(size 1 1)
					(thickness 0.15)
				)
				(justify mirror)
			)
		)
		(property "Manufacturer" "Walsin"
			(at 259.133485 -78.939171 0)
			(layer "B.Fab")
			(hide yes)
			(effects
				(font
					(size 1 1)
					(thickness 0.15)
				)
				(justify mirror)
			)
		)
		(property "Val" "100n"
			(at 259.133485 -78.939171 0)
			(layer "B.Fab")
			(hide yes)
			(effects
				(font
					(size 1 1)
					(thickness 0.15)
				)
				(justify mirror)
			)
		)
		(property "Voltage" ""
			(at 259.133485 -78.939171 0)
			(layer "B.Fab")
			(hide yes)
			(effects
				(font
					(size 1 1)
					(thickness 0.15)
				)
				(justify mirror)
			)
		)
		(sheetname "FPGA Banks")
		(sheetfile "fpga-banks.kicad_sch")
		(attr smd)
		(fp_rect
			(start -0.94 0.47)
			(end 0.94 -0.47)
			(stroke
				(width 0.05)
				(type solid)
			)
			(fill no)
			(layer "B.CrtYd")
		)
		(fp_rect
			(start -0.499 0.249)
			(end 0.499 -0.249)
			(stroke
				(width 0.15)
				(type solid)
			)
			(fill no)
			(layer "B.Fab")
		)
		(pad "1" smd roundrect
			(at -0.484 0 90)
			(size 0.59 0.64)
			(layers "B.Cu" "B.Mask" "B.Paste")
			(roundrect_rratio 0.25)
			(net 5 "GND")
			(pintype "passive")
		)
		(pad "2" smd roundrect
			(at 0.484 0 90)
			(size 0.59 0.64)
			(layers "B.Cu" "B.Mask" "B.Paste")
			(roundrect_rratio 0.25)
			(net 510 "VREF_34")
			(pintype "passive")
		)
	)
	(footprint "antmicro-footprints:R_0603_1608Metric"
		(layer "B.Cu")
		(at 156.936328 90.397157 90)
		(descr "Resistor SMD 0603")
		(tags "resistor SMD 0603")
		(property "Reference" "R5"
			(at 0.797157 -0.636328 270)
			(layer "B.SilkS")
			(effects
				(font
					(size 0.7 0.7)
					(thickness 0.15)
				)
				(justify left bottom mirror)
			)
		)
		(property "Value" "R_1k_0603"
			(at 0 -1.6 270)
			(layer "B.Fab")
			(effects
				(font
					(size 0.7 0.7)
					(thickness 0.15)
				)
				(justify left bottom mirror)
			)
		)
		(property "Description" "1k resistor in 0603 package with 1% tolerance"
			(at 0 0 90)
			(layer "F.Fab")
			(hide yes)
			(effects
				(font
					(size 1.27 1.27)
					(thickness 0.15)
				)
			)
		)
		(property "Author" "Antmicro"
			(at 247.333485 -66.539171 0)
			(layer "B.Fab")
			(hide yes)
			(effects
				(font
					(size 1 1)
					(thickness 0.15)
				)
				(justify mirror)
			)
		)
		(property "License" "Apache-2.0"
			(at 247.333485 -66.539171 0)
			(layer "B.Fab")
			(hide yes)
			(effects
				(font
					(size 1 1)
					(thickness 0.15)
				)
				(justify mirror)
			)
		)
		(property "MPN" "CR0603-FX-1001ELF"
			(at 247.333485 -66.539171 0)
			(layer "B.Fab")
			(hide yes)
			(effects
				(font
					(size 1 1)
					(thickness 0.15)
				)
				(justify mirror)
			)
		)
		(property "Manufacturer" "Bourns"
			(at 247.333485 -66.539171 0)
			(layer "B.Fab")
			(hide yes)
			(effects
				(font
					(size 1 1)
					(thickness 0.15)
				)
				(justify mirror)
			)
		)
		(property "Tolerance" "1%"
			(at 247.333485 -66.539171 0)
			(layer "B.Fab")
			(hide yes)
			(effects
				(font
					(size 1 1)
					(thickness 0.15)
				)
				(justify mirror)
			)
		)
		(property "Val" "1k"
			(at 247.333485 -66.539171 0)
			(layer "B.Fab")
			(hide yes)
			(effects
				(font
					(size 1 1)
					(thickness 0.15)
				)
				(justify mirror)
			)
		)
		(sheetname "FPGA Banks")
		(sheetfile "fpga-banks.kicad_sch")
		(attr smd)
		(fp_line
			(start -0.3 -0.3)
			(end 0.3 -0.3)
			(stroke
				(width 0.15)
				(type solid)
			)
			(layer "B.SilkS")
		)
		(fp_line
			(start -0.3 0.3)
			(end 0.3 0.3)
			(stroke
				(width 0.15)
				(type solid)
			)
			(layer "B.SilkS")
		)
		(fp_rect
			(start -1.25 0.7)
			(end 1.25 -0.7)
			(stroke
				(width 0.05)
				(type solid)
			)
			(fill no)
			(layer "B.CrtYd")
		)
		(fp_rect
			(start -0.8 0.4)
			(end 0.8 -0.4)
			(stroke
				(width 0.15)
				(type solid)
			)
			(fill no)
			(layer "B.Fab")
		)
		(pad "1" smd roundrect
			(at -0.7 0 90)
			(size 0.6 0.8)
			(layers "B.Cu" "B.Mask" "B.Paste")
			(roundrect_rratio 0.2)
			(net 66 "VDDQ")
			(pintype "passive")
		)
		(pad "2" smd roundrect
			(at 0.7 0 90)
			(size 0.6 0.8)
			(layers "B.Cu" "B.Mask" "B.Paste")
			(roundrect_rratio 0.2)
			(net 510 "VREF_34")
			(pintype "passive")
		)
	)
	(footprint "antmicro-footprints:R_0402_1005Metric"
		(layer "B.Cu")
		(at 196.686328 94.520008 90)
		(descr "Resistor SMD 0402")
		(tags "resistor SMD 0402")
		(property "Reference" "R75"
			(at 2.920008 0.413672 270)
			(layer "B.SilkS")
			(effects
				(font
					(size 0.7 0.7)
					(thickness 0.15)
				)
				(justify left bottom mirror)
			)
		)
		(property "Value" "R_10k2_0402"
			(at 0 -1.4 270)
			(layer "B.Fab")
			(effects
				(font
					(size 0.7 0.7)
					(thickness 0.15)
				)
				(justify left bottom mirror)
			)
		)
		(property "Description" "10k2 resistor in 0402 package with 1% tolerance"
			(at 0 0 90)
			(layer "F.Fab")
			(hide yes)
			(effects
				(font
					(size 1.27 1.27)
					(thickness 0.15)
				)
			)
		)
		(property "Author" "Antmicro"
			(at 291.206336 -102.16632 0)
			(layer "B.Fab")
			(hide yes)
			(effects
				(font
					(size 1 1)
					(thickness 0.15)
				)
				(justify mirror)
			)
		)
		(property "License" "Apache-2.0"
			(at 291.206336 -102.16632 0)
			(layer "B.Fab")
			(hide yes)
			(effects
				(font
					(size 1 1)
					(thickness 0.15)
				)
				(justify mirror)
			)
		)
		(property "MPN" "CR0402-FX-1022GLF"
			(at 291.206336 -102.16632 0)
			(layer "B.Fab")
			(hide yes)
			(effects
				(font
					(size 1 1)
					(thickness 0.15)
				)
				(justify mirror)
			)
		)
		(property "Manufacturer" "Bourns"
			(at 291.206336 -102.16632 0)
			(layer "B.Fab")
			(hide yes)
			(effects
				(font
					(size 1 1)
					(thickness 0.15)
				)
				(justify mirror)
			)
		)
		(property "Tolerance" "1%"
			(at 291.206336 -102.16632 0)
			(layer "B.Fab")
			(hide yes)
			(effects
				(font
					(size 1 1)
					(thickness 0.15)
				)
				(justify mirror)
			)
		)
		(property "Val" "10k2"
			(at 291.206336 -102.16632 0)
			(layer "B.Fab")
			(hide yes)
			(effects
				(font
					(size 1 1)
					(thickness 0.15)
				)
				(justify mirror)
			)
		)
		(sheetname "Ethernet")
		(sheetfile "ethernet.kicad_sch")
		(attr exclude_from_pos_files exclude_from_bom dnp)
		(fp_rect
			(start -0.93 0.47)
			(end 0.93 -0.47)
			(stroke
				(width 0.05)
				(type solid)
			)
			(fill no)
			(layer "B.CrtYd")
		)
		(fp_rect
			(start -0.5 0.25)
			(end 0.5 -0.25)
			(stroke
				(width 0.15)
				(type solid)
			)
			(fill no)
			(layer "B.Fab")
		)
		(pad "1" smd roundrect
			(at -0.485 0 90)
			(size 0.59 0.64)
			(layers "B.Cu" "B.Mask" "B.Paste")
			(roundrect_rratio 0.25)
			(net 23 "ETH_RXD1")
			(pintype "passive")
		)
		(pad "2" smd roundrect
			(at 0.485 0 90)
			(size 0.59 0.64)
			(layers "B.Cu" "B.Mask" "B.Paste")
			(roundrect_rratio 0.25)
			(net 459 "3V3_SYS")
			(pintype "passive")
		)
	)
	(footprint "antmicro-footprints:R_0402_1005Metric"
		(layer "B.Cu")
		(at 197.686328 94.020008 90)
		(descr "Resistor SMD 0402")
		(tags "resistor SMD 0402")
		(property "Reference" "R76"
			(at 3.020008 0.413672 270)
			(layer "B.SilkS")
			(effects
				(font
					(size 0.7 0.7)
					(thickness 0.15)
				)
				(justify left bottom mirror)
			)
		)
		(property "Value" "R_10k2_0402"
			(at 0 -1.4 270)
			(layer "B.Fab")
			(effects
				(font
					(size 0.7 0.7)
					(thickness 0.15)
				)
				(justify left bottom mirror)
			)
		)
		(property "Description" "10k2 resistor in 0402 package with 1% tolerance"
			(at 0 0 90)
			(layer "F.Fab")
			(hide yes)
			(effects
				(font
					(size 1.27 1.27)
					(thickness 0.15)
				)
			)
		)
		(property "Author" "Antmicro"
			(at 291.706336 -103.66632 0)
			(layer "B.Fab")
			(hide yes)
			(effects
				(font
					(size 1 1)
					(thickness 0.15)
				)
				(justify mirror)
			)
		)
		(property "License" "Apache-2.0"
			(at 291.706336 -103.66632 0)
			(layer "B.Fab")
			(hide yes)
			(effects
				(font
					(size 1 1)
					(thickness 0.15)
				)
				(justify mirror)
			)
		)
		(property "MPN" "CR0402-FX-1022GLF"
			(at 291.706336 -103.66632 0)
			(layer "B.Fab")
			(hide yes)
			(effects
				(font
					(size 1 1)
					(thickness 0.15)
				)
				(justify mirror)
			)
		)
		(property "Manufacturer" "Bourns"
			(at 291.706336 -103.66632 0)
			(layer "B.Fab")
			(hide yes)
			(effects
				(font
					(size 1 1)
					(thickness 0.15)
				)
				(justify mirror)
			)
		)
		(property "Tolerance" "1%"
			(at 291.706336 -103.66632 0)
			(layer "B.Fab")
			(hide yes)
			(effects
				(font
					(size 1 1)
					(thickness 0.15)
				)
				(justify mirror)
			)
		)
		(property "Val" "10k2"
			(at 291.706336 -103.66632 0)
			(layer "B.Fab")
			(hide yes)
			(effects
				(font
					(size 1 1)
					(thickness 0.15)
				)
				(justify mirror)
			)
		)
		(sheetname "Ethernet")
		(sheetfile "ethernet.kicad_sch")
		(attr smd)
		(fp_rect
			(start -0.93 0.47)
			(end 0.93 -0.47)
			(stroke
				(width 0.05)
				(type solid)
			)
			(fill no)
			(layer "B.CrtYd")
		)
		(fp_rect
			(start -0.5 0.25)
			(end 0.5 -0.25)
			(stroke
				(width 0.15)
				(type solid)
			)
			(fill no)
			(layer "B.Fab")
		)
		(pad "1" smd roundrect
			(at -0.485 0 90)
			(size 0.59 0.64)
			(layers "B.Cu" "B.Mask" "B.Paste")
			(roundrect_rratio 0.25)
			(net 37 "ETH_RXD2")
			(pintype "passive")
		)
		(pad "2" smd roundrect
			(at 0.485 0 90)
			(size 0.59 0.64)
			(layers "B.Cu" "B.Mask" "B.Paste")
			(roundrect_rratio 0.25)
			(net 459 "3V3_SYS")
			(pintype "passive")
		)
	)
	(footprint "antmicro-footprints:R_0402_1005Metric"
		(layer "B.Cu")
		(at 199.786328 93.220008 90)
		(descr "Resistor SMD 0402")
		(tags "resistor SMD 0402")
		(property "Reference" "R77"
			(at 1.120008 1.313672 270)
			(layer "B.SilkS")
			(effects
				(font
					(size 0.7 0.7)
					(thickness 0.15)
				)
				(justify left bottom mirror)
			)
		)
		(property "Value" "R_10k2_0402"
			(at 0 -1.4 270)
			(layer "B.Fab")
			(effects
				(font
					(size 0.7 0.7)
					(thickness 0.15)
				)
				(justify left bottom mirror)
			)
		)
		(property "Description" "10k2 resistor in 0402 package with 1% tolerance"
			(at 0 0 90)
			(layer "F.Fab")
			(hide yes)
			(effects
				(font
					(size 1.27 1.27)
					(thickness 0.15)
				)
			)
		)
		(property "Author" "Antmicro"
			(at 293.006336 -106.56632 0)
			(layer "B.Fab")
			(hide yes)
			(effects
				(font
					(size 1 1)
					(thickness 0.15)
				)
				(justify mirror)
			)
		)
		(property "License" "Apache-2.0"
			(at 293.006336 -106.56632 0)
			(layer "B.Fab")
			(hide yes)
			(effects
				(font
					(size 1 1)
					(thickness 0.15)
				)
				(justify mirror)
			)
		)
		(property "MPN" "CR0402-FX-1022GLF"
			(at 293.006336 -106.56632 0)
			(layer "B.Fab")
			(hide yes)
			(effects
				(font
					(size 1 1)
					(thickness 0.15)
				)
				(justify mirror)
			)
		)
		(property "Manufacturer" "Bourns"
			(at 293.006336 -106.56632 0)
			(layer "B.Fab")
			(hide yes)
			(effects
				(font
					(size 1 1)
					(thickness 0.15)
				)
				(justify mirror)
			)
		)
		(property "Tolerance" "1%"
			(at 293.006336 -106.56632 0)
			(layer "B.Fab")
			(hide yes)
			(effects
				(font
					(size 1 1)
					(thickness 0.15)
				)
				(justify mirror)
			)
		)
		(property "Val" "10k2"
			(at 293.006336 -106.56632 0)
			(layer "B.Fab")
			(hide yes)
			(effects
				(font
					(size 1 1)
					(thickness 0.15)
				)
				(justify mirror)
			)
		)
		(sheetname "Ethernet")
		(sheetfile "ethernet.kicad_sch")
		(attr smd)
		(fp_rect
			(start -0.93 0.47)
			(end 0.93 -0.47)
			(stroke
				(width 0.05)
				(type solid)
			)
			(fill no)
			(layer "B.CrtYd")
		)
		(fp_rect
			(start -0.5 0.25)
			(end 0.5 -0.25)
			(stroke
				(width 0.15)
				(type solid)
			)
			(fill no)
			(layer "B.Fab")
		)
		(pad "1" smd roundrect
			(at -0.485 0 90)
			(size 0.59 0.64)
			(layers "B.Cu" "B.Mask" "B.Paste")
			(roundrect_rratio 0.25)
			(net 33 "ETH_RXD3")
			(pintype "passive")
		)
		(pad "2" smd roundrect
			(at 0.485 0 90)
			(size 0.59 0.64)
			(layers "B.Cu" "B.Mask" "B.Paste")
			(roundrect_rratio 0.25)
			(net 459 "3V3_SYS")
			(pintype "passive")
		)
	)
	(footprint "antmicro-footprints:R_0402_1005Metric"
		(layer "B.Cu")
		(at 194.686328 95.720008 90)
		(descr "Resistor SMD 0402")
		(tags "resistor SMD 0402")
		(property "Reference" "R78"
			(at 2.920008 0.413672 270)
			(layer "B.SilkS")
			(effects
				(font
					(size 0.7 0.7)
					(thickness 0.15)
				)
				(justify left bottom mirror)
			)
		)
		(property "Value" "R_10k2_0402"
			(at 0 -1.4 270)
			(layer "B.Fab")
			(effects
				(font
					(size 0.7 0.7)
					(thickness 0.15)
				)
				(justify left bottom mirror)
			)
		)
		(property "Description" "10k2 resistor in 0402 package with 1% tolerance"
			(at 0 0 90)
			(layer "F.Fab")
			(hide yes)
			(effects
				(font
					(size 1.27 1.27)
					(thickness 0.15)
				)
			)
		)
		(property "Author" "Antmicro"
			(at 290.406336 -98.96632 0)
			(layer "B.Fab")
			(hide yes)
			(effects
				(font
					(size 1 1)
					(thickness 0.15)
				)
				(justify mirror)
			)
		)
		(property "License" "Apache-2.0"
			(at 290.406336 -98.96632 0)
			(layer "B.Fab")
			(hide yes)
			(effects
				(font
					(size 1 1)
					(thickness 0.15)
				)
				(justify mirror)
			)
		)
		(property "MPN" "CR0402-FX-1022GLF"
			(at 290.406336 -98.96632 0)
			(layer "B.Fab")
			(hide yes)
			(effects
				(font
					(size 1 1)
					(thickness 0.15)
				)
				(justify mirror)
			)
		)
		(property "Manufacturer" "Bourns"
			(at 290.406336 -98.96632 0)
			(layer "B.Fab")
			(hide yes)
			(effects
				(font
					(size 1 1)
					(thickness 0.15)
				)
				(justify mirror)
			)
		)
		(property "Tolerance" "1%"
			(at 290.406336 -98.96632 0)
			(layer "B.Fab")
			(hide yes)
			(effects
				(font
					(size 1 1)
					(thickness 0.15)
				)
				(justify mirror)
			)
		)
		(property "Val" "10k2"
			(at 290.406336 -98.96632 0)
			(layer "B.Fab")
			(hide yes)
			(effects
				(font
					(size 1 1)
					(thickness 0.15)
				)
				(justify mirror)
			)
		)
		(sheetname "Ethernet")
		(sheetfile "ethernet.kicad_sch")
		(attr exclude_from_pos_files exclude_from_bom dnp)
		(fp_rect
			(start -0.93 0.47)
			(end 0.93 -0.47)
			(stroke
				(width 0.05)
				(type solid)
			)
			(fill no)
			(layer "B.CrtYd")
		)
		(fp_rect
			(start -0.5 0.25)
			(end 0.5 -0.25)
			(stroke
				(width 0.15)
				(type solid)
			)
			(fill no)
			(layer "B.Fab")
		)
		(pad "1" smd roundrect
			(at -0.485 0 90)
			(size 0.59 0.64)
			(layers "B.Cu" "B.Mask" "B.Paste")
			(roundrect_rratio 0.25)
			(net 34 "ETH_RX_DV")
			(pintype "passive")
		)
		(pad "2" smd roundrect
			(at 0.485 0 90)
			(size 0.59 0.64)
			(layers "B.Cu" "B.Mask" "B.Paste")
			(roundrect_rratio 0.25)
			(net 459 "3V3_SYS")
			(pintype "passive")
		)
	)
	(footprint "antmicro-footprints:R_0402_1005Metric"
		(layer "B.Cu")
		(at 195.686328 96.220008 90)
		(descr "Resistor SMD 0402")
		(tags "resistor SMD 0402")
		(property "Reference" "R79"
			(at 3.020008 0.513672 270)
			(layer "B.SilkS")
			(effects
				(font
					(size 0.7 0.7)
					(thickness 0.15)
				)
				(justify left bottom mirror)
			)
		)
		(property "Value" "R_10k2_0402"
			(at 0 -1.4 270)
			(layer "B.Fab")
			(effects
				(font
					(size 0.7 0.7)
					(thickness 0.15)
				)
				(justify left bottom mirror)
			)
		)
		(property "Description" "10k2 resistor in 0402 package with 1% tolerance"
			(at 0 0 90)
			(layer "F.Fab")
			(hide yes)
			(effects
				(font
					(size 1.27 1.27)
					(thickness 0.15)
				)
			)
		)
		(property "Author" "Antmicro"
			(at 291.906336 -99.46632 0)
			(layer "B.Fab")
			(hide yes)
			(effects
				(font
					(size 1 1)
					(thickness 0.15)
				)
				(justify mirror)
			)
		)
		(property "License" "Apache-2.0"
			(at 291.906336 -99.46632 0)
			(layer "B.Fab")
			(hide yes)
			(effects
				(font
					(size 1 1)
					(thickness 0.15)
				)
				(justify mirror)
			)
		)
		(property "MPN" "CR0402-FX-1022GLF"
			(at 291.906336 -99.46632 0)
			(layer "B.Fab")
			(hide yes)
			(effects
				(font
					(size 1 1)
					(thickness 0.15)
				)
				(justify mirror)
			)
		)
		(property "Manufacturer" "Bourns"
			(at 291.906336 -99.46632 0)
			(layer "B.Fab")
			(hide yes)
			(effects
				(font
					(size 1 1)
					(thickness 0.15)
				)
				(justify mirror)
			)
		)
		(property "Tolerance" "1%"
			(at 291.906336 -99.46632 0)
			(layer "B.Fab")
			(hide yes)
			(effects
				(font
					(size 1 1)
					(thickness 0.15)
				)
				(justify mirror)
			)
		)
		(property "Val" "10k2"
			(at 291.906336 -99.46632 0)
			(layer "B.Fab")
			(hide yes)
			(effects
				(font
					(size 1 1)
					(thickness 0.15)
				)
				(justify mirror)
			)
		)
		(sheetname "Ethernet")
		(sheetfile "ethernet.kicad_sch")
		(attr exclude_from_pos_files exclude_from_bom dnp)
		(fp_rect
			(start -0.93 0.47)
			(end 0.93 -0.47)
			(stroke
				(width 0.05)
				(type solid)
			)
			(fill no)
			(layer "B.CrtYd")
		)
		(fp_rect
			(start -0.5 0.25)
			(end 0.5 -0.25)
			(stroke
				(width 0.15)
				(type solid)
			)
			(fill no)
			(layer "B.Fab")
		)
		(pad "1" smd roundrect
			(at -0.485 0 90)
			(size 0.59 0.64)
			(layers "B.Cu" "B.Mask" "B.Paste")
			(roundrect_rratio 0.25)
			(net 36 "ETH_RX_CLK")
			(pintype "passive")
		)
		(pad "2" smd roundrect
			(at 0.485 0 90)
			(size 0.59 0.64)
			(layers "B.Cu" "B.Mask" "B.Paste")
			(roundrect_rratio 0.25)
			(net 459 "3V3_SYS")
			(pintype "passive")
		)
	)
	(footprint "antmicro-footprints:R_0402_1005Metric"
		(layer "B.Cu")
		(at 198.376328 103.390008 -90)
		(descr "Resistor SMD 0402")
		(tags "resistor SMD 0402")
		(property "Reference" "R80"
			(at -1.090008 -1.223672 90)
			(layer "B.SilkS")
			(effects
				(font
					(size 0.7 0.7)
					(thickness 0.15)
				)
				(justify left bottom mirror)
			)
		)
		(property "Value" "R_10k2_0402"
			(at 0 -1.4 90)
			(layer "B.Fab")
			(effects
				(font
					(size 0.7 0.7)
					(thickness 0.15)
				)
				(justify left bottom mirror)
			)
		)
		(property "Description" "10k2 resistor in 0402 package with 1% tolerance"
			(at 0 0 270)
			(layer "F.Fab")
			(hide yes)
			(effects
				(font
					(size 1.27 1.27)
					(thickness 0.15)
				)
			)
		)
		(property "Author" "Antmicro"
			(at 94.98632 301.766336 0)
			(layer "B.Fab")
			(hide yes)
			(effects
				(font
					(size 1 1)
					(thickness 0.15)
				)
				(justify mirror)
			)
		)
		(property "License" "Apache-2.0"
			(at 94.98632 301.766336 0)
			(layer "B.Fab")
			(hide yes)
			(effects
				(font
					(size 1 1)
					(thickness 0.15)
				)
				(justify mirror)
			)
		)
		(property "MPN" "CR0402-FX-1022GLF"
			(at 94.98632 301.766336 0)
			(layer "B.Fab")
			(hide yes)
			(effects
				(font
					(size 1 1)
					(thickness 0.15)
				)
				(justify mirror)
			)
		)
		(property "Manufacturer" "Bourns"
			(at 94.98632 301.766336 0)
			(layer "B.Fab")
			(hide yes)
			(effects
				(font
					(size 1 1)
					(thickness 0.15)
				)
				(justify mirror)
			)
		)
		(property "Tolerance" "1%"
			(at 94.98632 301.766336 0)
			(layer "B.Fab")
			(hide yes)
			(effects
				(font
					(size 1 1)
					(thickness 0.15)
				)
				(justify mirror)
			)
		)
		(property "Val" "10k2"
			(at 94.98632 301.766336 0)
			(layer "B.Fab")
			(hide yes)
			(effects
				(font
					(size 1 1)
					(thickness 0.15)
				)
				(justify mirror)
			)
		)
		(sheetname "Ethernet")
		(sheetfile "ethernet.kicad_sch")
		(attr smd)
		(fp_rect
			(start -0.93 0.47)
			(end 0.93 -0.47)
			(stroke
				(width 0.05)
				(type solid)
			)
			(fill no)
			(layer "B.CrtYd")
		)
		(fp_rect
			(start -0.5 0.25)
			(end 0.5 -0.25)
			(stroke
				(width 0.15)
				(type solid)
			)
			(fill no)
			(layer "B.Fab")
		)
		(pad "1" smd roundrect
			(at -0.485 0 270)
			(size 0.59 0.64)
			(layers "B.Cu" "B.Mask" "B.Paste")
			(roundrect_rratio 0.25)
			(net 26 "ETH_REF_CLK")
			(pintype "passive")
		)
		(pad "2" smd roundrect
			(at 0.485 0 270)
			(size 0.59 0.64)
			(layers "B.Cu" "B.Mask" "B.Paste")
			(roundrect_rratio 0.25)
			(net 459 "3V3_SYS")
			(pintype "passive")
		)
	)
	(footprint "antmicro-footprints:R_0402_1005Metric"
		(layer "B.Cu")
		(at 198.771328 97.445008 -90)
		(descr "Resistor SMD 0402")
		(tags "resistor SMD 0402")
		(property "Reference" "R85"
			(at -1.045008 -1.328672 90)
			(layer "B.SilkS")
			(effects
				(font
					(size 0.7 0.7)
					(thickness 0.15)
				)
				(justify left bottom mirror)
			)
		)
		(property "Value" "R_2k2_0402"
			(at 0 -1.4 90)
			(layer "B.Fab")
			(effects
				(font
					(size 0.7 0.7)
					(thickness 0.15)
				)
				(justify left bottom mirror)
			)
		)
		(property "Description" "2k2 resistor in 0402 package with 1% tolerance"
			(at 0 0 270)
			(layer "F.Fab")
			(hide yes)
			(effects
				(font
					(size 1.27 1.27)
					(thickness 0.15)
				)
			)
		)
		(property "Author" "Antmicro"
			(at 101.32632 296.216336 0)
			(layer "B.Fab")
			(hide yes)
			(effects
				(font
					(size 1 1)
					(thickness 0.15)
				)
				(justify mirror)
			)
		)
		(property "License" "Apache-2.0"
			(at 101.32632 296.216336 0)
			(layer "B.Fab")
			(hide yes)
			(effects
				(font
					(size 1 1)
					(thickness 0.15)
				)
				(justify mirror)
			)
		)
		(property "MPN" "CR0402-FX-2201GLF"
			(at 101.32632 296.216336 0)
			(layer "B.Fab")
			(hide yes)
			(effects
				(font
					(size 1 1)
					(thickness 0.15)
				)
				(justify mirror)
			)
		)
		(property "Manufacturer" "Bourns"
			(at 101.32632 296.216336 0)
			(layer "B.Fab")
			(hide yes)
			(effects
				(font
					(size 1 1)
					(thickness 0.15)
				)
				(justify mirror)
			)
		)
		(property "Tolerance" "1%"
			(at 101.32632 296.216336 0)
			(layer "B.Fab")
			(hide yes)
			(effects
				(font
					(size 1 1)
					(thickness 0.15)
				)
				(justify mirror)
			)
		)
		(property "Val" "2k2"
			(at 101.32632 296.216336 0)
			(layer "B.Fab")
			(hide yes)
			(effects
				(font
					(size 1 1)
					(thickness 0.15)
				)
				(justify mirror)
			)
		)
		(sheetname "Ethernet")
		(sheetfile "ethernet.kicad_sch")
		(attr smd)
		(fp_rect
			(start -0.93 0.47)
			(end 0.93 -0.47)
			(stroke
				(width 0.05)
				(type solid)
			)
			(fill no)
			(layer "B.CrtYd")
		)
		(fp_rect
			(start -0.5 0.25)
			(end 0.5 -0.25)
			(stroke
				(width 0.15)
				(type solid)
			)
			(fill no)
			(layer "B.Fab")
		)
		(pad "1" smd roundrect
			(at -0.485 0 270)
			(size 0.59 0.64)
			(layers "B.Cu" "B.Mask" "B.Paste")
			(roundrect_rratio 0.25)
			(net 22 "ETH_RXD0")
			(pintype "passive")
		)
		(pad "2" smd roundrect
			(at 0.485 0 270)
			(size 0.59 0.64)
			(layers "B.Cu" "B.Mask" "B.Paste")
			(roundrect_rratio 0.25)
			(net 5 "GND")
			(pintype "passive")
		)
	)
	(footprint "antmicro-footprints:R_0402_1005Metric"
		(layer "B.Cu")
		(at 195.886328 99.520008)
		(descr "Resistor SMD 0402")
		(tags "resistor SMD 0402")
		(property "Reference" "R83"
			(at 1.013672 1.379992 180)
			(layer "B.SilkS")
			(effects
				(font
					(size 0.7 0.7)
					(thickness 0.15)
				)
				(justify left bottom mirror)
			)
		)
		(property "Value" "R_1k_0402"
			(at 0 -1.4 180)
			(layer "B.Fab")
			(effects
				(font
					(size 0.7 0.7)
					(thickness 0.15)
				)
				(justify left bottom mirror)
			)
		)
		(property "Description" "1k resistor in 0402 package with 1% tolerance"
			(at 0 0 0)
			(layer "F.Fab")
			(hide yes)
			(effects
				(font
					(size 1.27 1.27)
					(thickness 0.15)
				)
			)
		)
		(property "Author" "Antmicro"
			(at 0 0 0)
			(layer "B.Fab")
			(hide yes)
			(effects
				(font
					(size 1 1)
					(thickness 0.15)
				)
				(justify mirror)
			)
		)
		(property "License" "Apache-2.0"
			(at 0 0 0)
			(layer "B.Fab")
			(hide yes)
			(effects
				(font
					(size 1 1)
					(thickness 0.15)
				)
				(justify mirror)
			)
		)
		(property "MPN" "CR0402-FX-1001GLF"
			(at 0 0 0)
			(layer "B.Fab")
			(hide yes)
			(effects
				(font
					(size 1 1)
					(thickness 0.15)
				)
				(justify mirror)
			)
		)
		(property "Manufacturer" "Bourns"
			(at 0 0 0)
			(layer "B.Fab")
			(hide yes)
			(effects
				(font
					(size 1 1)
					(thickness 0.15)
				)
				(justify mirror)
			)
		)
		(property "Tolerance" "1%"
			(at 0 0 0)
			(layer "B.Fab")
			(hide yes)
			(effects
				(font
					(size 1 1)
					(thickness 0.15)
				)
				(justify mirror)
			)
		)
		(property "Val" "1k"
			(at 0 0 0)
			(layer "B.Fab")
			(hide yes)
			(effects
				(font
					(size 1 1)
					(thickness 0.15)
				)
				(justify mirror)
			)
		)
		(sheetname "Ethernet")
		(sheetfile "ethernet.kicad_sch")
		(attr smd)
		(fp_rect
			(start -0.93 0.47)
			(end 0.93 -0.47)
			(stroke
				(width 0.05)
				(type solid)
			)
			(fill no)
			(layer "B.CrtYd")
		)
		(fp_rect
			(start -0.5 0.25)
			(end 0.5 -0.25)
			(stroke
				(width 0.15)
				(type solid)
			)
			(fill no)
			(layer "B.Fab")
		)
		(pad "1" smd roundrect
			(at -0.485 0)
			(size 0.59 0.64)
			(layers "B.Cu" "B.Mask" "B.Paste")
			(roundrect_rratio 0.25)
			(net 25 "ETH_MDIO")
			(pintype "passive")
		)
		(pad "2" smd roundrect
			(at 0.485 0)
			(size 0.59 0.64)
			(layers "B.Cu" "B.Mask" "B.Paste")
			(roundrect_rratio 0.25)
			(net 459 "3V3_SYS")
			(pintype "passive")
		)
	)
	(footprint "antmicro-footprints:R_0402_1005Metric"
		(layer "B.Cu")
		(at 196.886328 103.320008)
		(descr "Resistor SMD 0402")
		(tags "resistor SMD 0402")
		(property "Reference" "R84"
			(at 1.013672 1.279992 180)
			(layer "B.SilkS")
			(effects
				(font
					(size 0.7 0.7)
					(thickness 0.15)
				)
				(justify left bottom mirror)
			)
		)
		(property "Value" "R_10k2_0402"
			(at 0 -1.4 180)
			(layer "B.Fab")
			(effects
				(font
					(size 0.7 0.7)
					(thickness 0.15)
				)
				(justify left bottom mirror)
			)
		)
		(property "Description" "10k2 resistor in 0402 package with 1% tolerance"
			(at 0 0 0)
			(layer "F.Fab")
			(hide yes)
			(effects
				(font
					(size 1.27 1.27)
					(thickness 0.15)
				)
			)
		)
		(property "Author" "Antmicro"
			(at 0 0 0)
			(layer "B.Fab")
			(hide yes)
			(effects
				(font
					(size 1 1)
					(thickness 0.15)
				)
				(justify mirror)
			)
		)
		(property "License" "Apache-2.0"
			(at 0 0 0)
			(layer "B.Fab")
			(hide yes)
			(effects
				(font
					(size 1 1)
					(thickness 0.15)
				)
				(justify mirror)
			)
		)
		(property "MPN" "CR0402-FX-1022GLF"
			(at 0 0 0)
			(layer "B.Fab")
			(hide yes)
			(effects
				(font
					(size 1 1)
					(thickness 0.15)
				)
				(justify mirror)
			)
		)
		(property "Manufacturer" "Bourns"
			(at 0 0 0)
			(layer "B.Fab")
			(hide yes)
			(effects
				(font
					(size 1 1)
					(thickness 0.15)
				)
				(justify mirror)
			)
		)
		(property "Tolerance" "1%"
			(at 0 0 0)
			(layer "B.Fab")
			(hide yes)
			(effects
				(font
					(size 1 1)
					(thickness 0.15)
				)
				(justify mirror)
			)
		)
		(property "Val" "10k2"
			(at 0 0 0)
			(layer "B.Fab")
			(hide yes)
			(effects
				(font
					(size 1 1)
					(thickness 0.15)
				)
				(justify mirror)
			)
		)
		(sheetname "Ethernet")
		(sheetfile "ethernet.kicad_sch")
		(attr smd)
		(fp_rect
			(start -0.93 0.47)
			(end 0.93 -0.47)
			(stroke
				(width 0.05)
				(type solid)
			)
			(fill no)
			(layer "B.CrtYd")
		)
		(fp_rect
			(start -0.5 0.25)
			(end 0.5 -0.25)
			(stroke
				(width 0.15)
				(type solid)
			)
			(fill no)
			(layer "B.Fab")
		)
		(pad "1" smd roundrect
			(at -0.485 0)
			(size 0.59 0.64)
			(layers "B.Cu" "B.Mask" "B.Paste")
			(roundrect_rratio 0.25)
			(net 24 "ETH_RSTN")
			(pintype "passive")
		)
		(pad "2" smd roundrect
			(at 0.485 0)
			(size 0.59 0.64)
			(layers "B.Cu" "B.Mask" "B.Paste")
			(roundrect_rratio 0.25)
			(net 459 "3V3_SYS")
			(pintype "passive")
		)
	)
	(footprint "antmicro-footprints:R_0402_1005Metric"
		(layer "B.Cu")
		(at 208.786328 105.020008)
		(descr "Resistor SMD 0402")
		(tags "resistor SMD 0402")
		(property "Reference" "R81"
			(at 3.013672 0.379992 180)
			(layer "B.SilkS")
			(effects
				(font
					(size 0.7 0.7)
					(thickness 0.15)
				)
				(justify left bottom mirror)
			)
		)
		(property "Value" "R_10k2_0402"
			(at 0 -1.4 180)
			(layer "B.Fab")
			(effects
				(font
					(size 0.7 0.7)
					(thickness 0.15)
				)
				(justify left bottom mirror)
			)
		)
		(property "Description" "10k2 resistor in 0402 package with 1% tolerance"
			(at 0 0 0)
			(layer "F.Fab")
			(hide yes)
			(effects
				(font
					(size 1.27 1.27)
					(thickness 0.15)
				)
			)
		)
		(property "Author" "Antmicro"
			(at 0 0 0)
			(layer "B.Fab")
			(hide yes)
			(effects
				(font
					(size 1 1)
					(thickness 0.15)
				)
				(justify mirror)
			)
		)
		(property "License" "Apache-2.0"
			(at 0 0 0)
			(layer "B.Fab")
			(hide yes)
			(effects
				(font
					(size 1 1)
					(thickness 0.15)
				)
				(justify mirror)
			)
		)
		(property "MPN" "CR0402-FX-1022GLF"
			(at 0 0 0)
			(layer "B.Fab")
			(hide yes)
			(effects
				(font
					(size 1 1)
					(thickness 0.15)
				)
				(justify mirror)
			)
		)
		(property "Manufacturer" "Bourns"
			(at 0 0 0)
			(layer "B.Fab")
			(hide yes)
			(effects
				(font
					(size 1 1)
					(thickness 0.15)
				)
				(justify mirror)
			)
		)
		(property "Tolerance" "1%"
			(at 0 0 0)
			(layer "B.Fab")
			(hide yes)
			(effects
				(font
					(size 1 1)
					(thickness 0.15)
				)
				(justify mirror)
			)
		)
		(property "Val" "10k2"
			(at 0 0 0)
			(layer "B.Fab")
			(hide yes)
			(effects
				(font
					(size 1 1)
					(thickness 0.15)
				)
				(justify mirror)
			)
		)
		(sheetname "Ethernet")
		(sheetfile "ethernet.kicad_sch")
		(attr smd)
		(fp_rect
			(start -0.93 0.47)
			(end 0.93 -0.47)
			(stroke
				(width 0.05)
				(type solid)
			)
			(fill no)
			(layer "B.CrtYd")
		)
		(fp_rect
			(start -0.5 0.25)
			(end 0.5 -0.25)
			(stroke
				(width 0.15)
				(type solid)
			)
			(fill no)
			(layer "B.Fab")
		)
		(pad "1" smd roundrect
			(at -0.485 0)
			(size 0.59 0.64)
			(layers "B.Cu" "B.Mask" "B.Paste")
			(roundrect_rratio 0.25)
			(net 13 "LED_SPD")
			(pintype "passive")
		)
		(pad "2" smd roundrect
			(at 0.485 0)
			(size 0.59 0.64)
			(layers "B.Cu" "B.Mask" "B.Paste")
			(roundrect_rratio 0.25)
			(net 459 "3V3_SYS")
			(pintype "passive")
		)
	)
	(footprint "antmicro-footprints:C_0402_1005Metric"
		(layer "B.Cu")
		(at 199.086328 108.789306 -90)
		(descr "Capacitor SMD 0402")
		(tags "capacitor SMD 0402")
		(property "Reference" "C99"
			(at 0.810694 -0.413672 90)
			(layer "B.SilkS")
			(effects
				(font
					(size 0.7 0.7)
					(thickness 0.15)
				)
				(justify left bottom mirror)
			)
		)
		(property "Value" "C_4u7_0402"
			(at 0 -1.4 90)
			(layer "B.Fab")
			(effects
				(font
					(size 0.7 0.7)
					(thickness 0.15)
				)
				(justify left bottom mirror)
			)
		)
		(property "Description" " "
			(at 0 0 270)
			(layer "F.Fab")
			(hide yes)
			(effects
				(font
					(size 1.27 1.27)
					(thickness 0.15)
				)
			)
		)
		(property "Author" "Antmicro"
			(at 90.297022 307.875634 0)
			(layer "B.Fab")
			(hide yes)
			(effects
				(font
					(size 1 1)
					(thickness 0.15)
				)
				(justify mirror)
			)
		)
		(property "Dielectric" ""
			(at 90.297022 307.875634 0)
			(layer "B.Fab")
			(hide yes)
			(effects
				(font
					(size 1 1)
					(thickness 0.15)
				)
				(justify mirror)
			)
		)
		(property "License" "Apache-2.0"
			(at 90.297022 307.875634 0)
			(layer "B.Fab")
			(hide yes)
			(effects
				(font
					(size 1 1)
					(thickness 0.15)
				)
				(justify mirror)
			)
		)
		(property "MPN" "GRM155R61A475MEAAD"
			(at 90.297022 307.875634 0)
			(layer "B.Fab")
			(hide yes)
			(effects
				(font
					(size 1 1)
					(thickness 0.15)
				)
				(justify mirror)
			)
		)
		(property "Manufacturer" "Murata"
			(at 90.297022 307.875634 0)
			(layer "B.Fab")
			(hide yes)
			(effects
				(font
					(size 1 1)
					(thickness 0.15)
				)
				(justify mirror)
			)
		)
		(property "Val" "4u7"
			(at 90.297022 307.875634 0)
			(layer "B.Fab")
			(hide yes)
			(effects
				(font
					(size 1 1)
					(thickness 0.15)
				)
				(justify mirror)
			)
		)
		(property "Voltage" ""
			(at 90.297022 307.875634 0)
			(layer "B.Fab")
			(hide yes)
			(effects
				(font
					(size 1 1)
					(thickness 0.15)
				)
				(justify mirror)
			)
		)
		(sheetname "Ethernet")
		(sheetfile "ethernet.kicad_sch")
		(attr smd)
		(fp_rect
			(start -0.94 0.47)
			(end 0.94 -0.47)
			(stroke
				(width 0.05)
				(type solid)
			)
			(fill no)
			(layer "B.CrtYd")
		)
		(fp_rect
			(start -0.499 0.249)
			(end 0.499 -0.249)
			(stroke
				(width 0.15)
				(type solid)
			)
			(fill no)
			(layer "B.Fab")
		)
		(pad "1" smd roundrect
			(at -0.484 0 270)
			(size 0.59 0.64)
			(layers "B.Cu" "B.Mask" "B.Paste")
			(roundrect_rratio 0.25)
			(net 529 "/Ethernet/AVDDL")
			(pintype "passive")
		)
		(pad "2" smd roundrect
			(at 0.484 0 270)
			(size 0.59 0.64)
			(layers "B.Cu" "B.Mask" "B.Paste")
			(roundrect_rratio 0.25)
			(net 5 "GND")
			(pintype "passive")
		)
	)
	(footprint "antmicro-footprints:C_0402_1005Metric"
		(layer "B.Cu")
		(at 199.486328 100.020008 -90)
		(descr "Capacitor SMD 0402")
		(tags "capacitor SMD 0402")
		(property "Reference" "C100"
			(at -1.820008 -6.613672 90)
			(layer "B.SilkS")
			(effects
				(font
					(size 0.7 0.7)
					(thickness 0.15)
				)
				(justify left bottom mirror)
			)
		)
		(property "Value" "C_470n_0402"
			(at 0 -1.4 90)
			(layer "B.Fab")
			(effects
				(font
					(size 0.7 0.7)
					(thickness 0.15)
				)
				(justify left bottom mirror)
			)
		)
		(property "Description" " "
			(at 0 0 270)
			(layer "F.Fab")
			(hide yes)
			(effects
				(font
					(size 1.27 1.27)
					(thickness 0.15)
				)
			)
		)
		(property "Author" "Antmicro"
			(at 99.46632 299.506336 0)
			(layer "B.Fab")
			(hide yes)
			(effects
				(font
					(size 1 1)
					(thickness 0.15)
				)
				(justify mirror)
			)
		)
		(property "Dielectric" ""
			(at 99.46632 299.506336 0)
			(layer "B.Fab")
			(hide yes)
			(effects
				(font
					(size 1 1)
					(thickness 0.15)
				)
				(justify mirror)
			)
		)
		(property "License" "Apache-2.0"
			(at 99.46632 299.506336 0)
			(layer "B.Fab")
			(hide yes)
			(effects
				(font
					(size 1 1)
					(thickness 0.15)
				)
				(justify mirror)
			)
		)
		(property "MPN" "C1005X5R1E474M050BB"
			(at 99.46632 299.506336 0)
			(layer "B.Fab")
			(hide yes)
			(effects
				(font
					(size 1 1)
					(thickness 0.15)
				)
				(justify mirror)
			)
		)
		(property "Manufacturer" "TDK"
			(at 99.46632 299.506336 0)
			(layer "B.Fab")
			(hide yes)
			(effects
				(font
					(size 1 1)
					(thickness 0.15)
				)
				(justify mirror)
			)
		)
		(property "Val" "470n"
			(at 99.46632 299.506336 0)
			(layer "B.Fab")
			(hide yes)
			(effects
				(font
					(size 1 1)
					(thickness 0.15)
				)
				(justify mirror)
			)
		)
		(property "Voltage" ""
			(at 99.46632 299.506336 0)
			(layer "B.Fab")
			(hide yes)
			(effects
				(font
					(size 1 1)
					(thickness 0.15)
				)
				(justify mirror)
			)
		)
		(sheetname "Ethernet")
		(sheetfile "ethernet.kicad_sch")
		(attr smd)
		(fp_rect
			(start -0.94 0.47)
			(end 0.94 -0.47)
			(stroke
				(width 0.05)
				(type solid)
			)
			(fill no)
			(layer "B.CrtYd")
		)
		(fp_rect
			(start -0.499 0.249)
			(end 0.499 -0.249)
			(stroke
				(width 0.15)
				(type solid)
			)
			(fill no)
			(layer "B.Fab")
		)
		(pad "1" smd roundrect
			(at -0.484 0 270)
			(size 0.59 0.64)
			(layers "B.Cu" "B.Mask" "B.Paste")
			(roundrect_rratio 0.25)
			(net 602 "1V2_SYS")
			(pintype "passive")
		)
		(pad "2" smd roundrect
			(at 0.484 0 270)
			(size 0.59 0.64)
			(layers "B.Cu" "B.Mask" "B.Paste")
			(roundrect_rratio 0.25)
			(net 5 "GND")
			(pintype "passive")
		)
	)
	(footprint "antmicro-footprints:C_0402_1005Metric"
		(layer "B.Cu")
		(at 202.086328 108.774306 -90)
		(descr "Capacitor SMD 0402")
		(tags "capacitor SMD 0402")
		(property "Reference" "C103"
			(at 0.810694 -0.413672 90)
			(layer "B.SilkS")
			(effects
				(font
					(size 0.7 0.7)
					(thickness 0.15)
				)
				(justify left bottom mirror)
			)
		)
		(property "Value" "C_470n_0402"
			(at 0 -1.4 90)
			(layer "B.Fab")
			(effects
				(font
					(size 0.7 0.7)
					(thickness 0.15)
				)
				(justify left bottom mirror)
			)
		)
		(property "Description" " "
			(at 0 0 270)
			(layer "F.Fab")
			(hide yes)
			(effects
				(font
					(size 1.27 1.27)
					(thickness 0.15)
				)
			)
		)
		(property "Author" "Antmicro"
			(at 93.312022 310.860634 0)
			(layer "B.Fab")
			(hide yes)
			(effects
				(font
					(size 1 1)
					(thickness 0.15)
				)
				(justify mirror)
			)
		)
		(property "Dielectric" ""
			(at 93.312022 310.860634 0)
			(layer "B.Fab")
			(hide yes)
			(effects
				(font
					(size 1 1)
					(thickness 0.15)
				)
				(justify mirror)
			)
		)
		(property "License" "Apache-2.0"
			(at 93.312022 310.860634 0)
			(layer "B.Fab")
			(hide yes)
			(effects
				(font
					(size 1 1)
					(thickness 0.15)
				)
				(justify mirror)
			)
		)
		(property "MPN" "C1005X5R1E474M050BB"
			(at 93.312022 310.860634 0)
			(layer "B.Fab")
			(hide yes)
			(effects
				(font
					(size 1 1)
					(thickness 0.15)
				)
				(justify mirror)
			)
		)
		(property "Manufacturer" "TDK"
			(at 93.312022 310.860634 0)
			(layer "B.Fab")
			(hide yes)
			(effects
				(font
					(size 1 1)
					(thickness 0.15)
				)
				(justify mirror)
			)
		)
		(property "Val" "470n"
			(at 93.312022 310.860634 0)
			(layer "B.Fab")
			(hide yes)
			(effects
				(font
					(size 1 1)
					(thickness 0.15)
				)
				(justify mirror)
			)
		)
		(property "Voltage" ""
			(at 93.312022 310.860634 0)
			(layer "B.Fab")
			(hide yes)
			(effects
				(font
					(size 1 1)
					(thickness 0.15)
				)
				(justify mirror)
			)
		)
		(sheetname "Ethernet")
		(sheetfile "ethernet.kicad_sch")
		(attr smd)
		(fp_rect
			(start -0.94 0.47)
			(end 0.94 -0.47)
			(stroke
				(width 0.05)
				(type solid)
			)
			(fill no)
			(layer "B.CrtYd")
		)
		(fp_rect
			(start -0.499 0.249)
			(end 0.499 -0.249)
			(stroke
				(width 0.15)
				(type solid)
			)
			(fill no)
			(layer "B.Fab")
		)
		(pad "1" smd roundrect
			(at -0.484 0 270)
			(size 0.59 0.64)
			(layers "B.Cu" "B.Mask" "B.Paste")
			(roundrect_rratio 0.25)
			(net 529 "/Ethernet/AVDDL")
			(pintype "passive")
		)
		(pad "2" smd roundrect
			(at 0.484 0 270)
			(size 0.59 0.64)
			(layers "B.Cu" "B.Mask" "B.Paste")
			(roundrect_rratio 0.25)
			(net 5 "GND")
			(pintype "passive")
		)
	)
	(footprint "antmicro-footprints:C_0402_1005Metric"
		(layer "B.Cu")
		(at 200.086328 108.774306 -90)
		(descr "Capacitor SMD 0402")
		(tags "capacitor SMD 0402")
		(property "Reference" "C107"
			(at 0.810694 -0.413672 90)
			(layer "B.SilkS")
			(effects
				(font
					(size 0.7 0.7)
					(thickness 0.15)
				)
				(justify left bottom mirror)
			)
		)
		(property "Value" "C_10n_0402"
			(at 0 -1.4 90)
			(layer "B.Fab")
			(effects
				(font
					(size 0.7 0.7)
					(thickness 0.15)
				)
				(justify left bottom mirror)
			)
		)
		(property "Description" " "
			(at 0 0 270)
			(layer "F.Fab")
			(hide yes)
			(effects
				(font
					(size 1.27 1.27)
					(thickness 0.15)
				)
			)
		)
		(property "Author" "Antmicro"
			(at 91.312022 308.860634 0)
			(layer "B.Fab")
			(hide yes)
			(effects
				(font
					(size 1 1)
					(thickness 0.15)
				)
				(justify mirror)
			)
		)
		(property "Dielectric" "X7R"
			(at 91.312022 308.860634 0)
			(layer "B.Fab")
			(hide yes)
			(effects
				(font
					(size 1 1)
					(thickness 0.15)
				)
				(justify mirror)
			)
		)
		(property "License" "Apache-2.0"
			(at 91.312022 308.860634 0)
			(layer "B.Fab")
			(hide yes)
			(effects
				(font
					(size 1 1)
					(thickness 0.15)
				)
				(justify mirror)
			)
		)
		(property "MPN" "GRM155R71H103KA88D"
			(at 91.312022 308.860634 0)
			(layer "B.Fab")
			(hide yes)
			(effects
				(font
					(size 1 1)
					(thickness 0.15)
				)
				(justify mirror)
			)
		)
		(property "Manufacturer" "Murata"
			(at 91.312022 308.860634 0)
			(layer "B.Fab")
			(hide yes)
			(effects
				(font
					(size 1 1)
					(thickness 0.15)
				)
				(justify mirror)
			)
		)
		(property "Val" "10n"
			(at 91.312022 308.860634 0)
			(layer "B.Fab")
			(hide yes)
			(effects
				(font
					(size 1 1)
					(thickness 0.15)
				)
				(justify mirror)
			)
		)
		(property "Voltage" "50V"
			(at 91.312022 308.860634 0)
			(layer "B.Fab")
			(hide yes)
			(effects
				(font
					(size 1 1)
					(thickness 0.15)
				)
				(justify mirror)
			)
		)
		(sheetname "Ethernet")
		(sheetfile "ethernet.kicad_sch")
		(attr smd)
		(fp_rect
			(start -0.94 0.47)
			(end 0.94 -0.47)
			(stroke
				(width 0.05)
				(type solid)
			)
			(fill no)
			(layer "B.CrtYd")
		)
		(fp_rect
			(start -0.499 0.249)
			(end 0.499 -0.249)
			(stroke
				(width 0.15)
				(type solid)
			)
			(fill no)
			(layer "B.Fab")
		)
		(pad "1" smd roundrect
			(at -0.484 0 270)
			(size 0.59 0.64)
			(layers "B.Cu" "B.Mask" "B.Paste")
			(roundrect_rratio 0.25)
			(net 529 "/Ethernet/AVDDL")
			(pintype "passive")
		)
		(pad "2" smd roundrect
			(at 0.484 0 270)
			(size 0.59 0.64)
			(layers "B.Cu" "B.Mask" "B.Paste")
			(roundrect_rratio 0.25)
			(net 5 "GND")
			(pintype "passive")
		)
	)
	(footprint "antmicro-footprints:C_0402_1005Metric"
		(layer "B.Cu")
		(at 198.486328 100.020008 -90)
		(descr "Capacitor SMD 0402")
		(tags "capacitor SMD 0402")
		(property "Reference" "C109"
			(at -1.820008 -6.613672 90)
			(layer "B.SilkS")
			(effects
				(font
					(size 0.7 0.7)
					(thickness 0.15)
				)
				(justify left bottom mirror)
			)
		)
		(property "Value" "C_10n_0402"
			(at 0 -1.4 90)
			(layer "B.Fab")
			(effects
				(font
					(size 0.7 0.7)
					(thickness 0.15)
				)
				(justify left bottom mirror)
			)
		)
		(property "Description" " "
			(at 0 0 270)
			(layer "F.Fab")
			(hide yes)
			(effects
				(font
					(size 1.27 1.27)
					(thickness 0.15)
				)
			)
		)
		(property "Author" "Antmicro"
			(at 98.46632 298.506336 0)
			(layer "B.Fab")
			(hide yes)
			(effects
				(font
					(size 1 1)
					(thickness 0.15)
				)
				(justify mirror)
			)
		)
		(property "Dielectric" "X7R"
			(at 98.46632 298.506336 0)
			(layer "B.Fab")
			(hide yes)
			(effects
				(font
					(size 1 1)
					(thickness 0.15)
				)
				(justify mirror)
			)
		)
		(property "License" "Apache-2.0"
			(at 98.46632 298.506336 0)
			(layer "B.Fab")
			(hide yes)
			(effects
				(font
					(size 1 1)
					(thickness 0.15)
				)
				(justify mirror)
			)
		)
		(property "MPN" "GRM155R71H103KA88D"
			(at 98.46632 298.506336 0)
			(layer "B.Fab")
			(hide yes)
			(effects
				(font
					(size 1 1)
					(thickness 0.15)
				)
				(justify mirror)
			)
		)
		(property "Manufacturer" "Murata"
			(at 98.46632 298.506336 0)
			(layer "B.Fab")
			(hide yes)
			(effects
				(font
					(size 1 1)
					(thickness 0.15)
				)
				(justify mirror)
			)
		)
		(property "Val" "10n"
			(at 98.46632 298.506336 0)
			(layer "B.Fab")
			(hide yes)
			(effects
				(font
					(size 1 1)
					(thickness 0.15)
				)
				(justify mirror)
			)
		)
		(property "Voltage" "50V"
			(at 98.46632 298.506336 0)
			(layer "B.Fab")
			(hide yes)
			(effects
				(font
					(size 1 1)
					(thickness 0.15)
				)
				(justify mirror)
			)
		)
		(sheetname "Ethernet")
		(sheetfile "ethernet.kicad_sch")
		(attr smd)
		(fp_rect
			(start -0.94 0.47)
			(end 0.94 -0.47)
			(stroke
				(width 0.05)
				(type solid)
			)
			(fill no)
			(layer "B.CrtYd")
		)
		(fp_rect
			(start -0.499 0.249)
			(end 0.499 -0.249)
			(stroke
				(width 0.15)
				(type solid)
			)
			(fill no)
			(layer "B.Fab")
		)
		(pad "1" smd roundrect
			(at -0.484 0 270)
			(size 0.59 0.64)
			(layers "B.Cu" "B.Mask" "B.Paste")
			(roundrect_rratio 0.25)
			(net 459 "3V3_SYS")
			(pintype "passive")
		)
		(pad "2" smd roundrect
			(at 0.484 0 270)
			(size 0.59 0.64)
			(layers "B.Cu" "B.Mask" "B.Paste")
			(roundrect_rratio 0.25)
			(net 5 "GND")
			(pintype "passive")
		)
	)
	(footprint "antmicro-footprints:C_0402_1005Metric"
		(layer "B.Cu")
		(at 197.686328 108.774306 -90)
		(descr "Capacitor SMD 0402")
		(tags "capacitor SMD 0402")
		(property "Reference" "C110"
			(at 0.825694 -0.413672 90)
			(layer "B.SilkS")
			(effects
				(font
					(size 0.7 0.7)
					(thickness 0.15)
				)
				(justify left bottom mirror)
			)
		)
		(property "Value" "C_4u7_0402"
			(at 0 -1.4 90)
			(layer "B.Fab")
			(effects
				(font
					(size 0.7 0.7)
					(thickness 0.15)
				)
				(justify left bottom mirror)
			)
		)
		(property "Description" " "
			(at 0 0 270)
			(layer "F.Fab")
			(hide yes)
			(effects
				(font
					(size 1.27 1.27)
					(thickness 0.15)
				)
			)
		)
		(property "Author" "Antmicro"
			(at 88.912022 306.460634 0)
			(layer "B.Fab")
			(hide yes)
			(effects
				(font
					(size 1 1)
					(thickness 0.15)
				)
				(justify mirror)
			)
		)
		(property "Dielectric" ""
			(at 88.912022 306.460634 0)
			(layer "B.Fab")
			(hide yes)
			(effects
				(font
					(size 1 1)
					(thickness 0.15)
				)
				(justify mirror)
			)
		)
		(property "License" "Apache-2.0"
			(at 88.912022 306.460634 0)
			(layer "B.Fab")
			(hide yes)
			(effects
				(font
					(size 1 1)
					(thickness 0.15)
				)
				(justify mirror)
			)
		)
		(property "MPN" "GRM155R61A475MEAAD"
			(at 88.912022 306.460634 0)
			(layer "B.Fab")
			(hide yes)
			(effects
				(font
					(size 1 1)
					(thickness 0.15)
				)
				(justify mirror)
			)
		)
		(property "Manufacturer" "Murata"
			(at 88.912022 306.460634 0)
			(layer "B.Fab")
			(hide yes)
			(effects
				(font
					(size 1 1)
					(thickness 0.15)
				)
				(justify mirror)
			)
		)
		(property "Val" "4u7"
			(at 88.912022 306.460634 0)
			(layer "B.Fab")
			(hide yes)
			(effects
				(font
					(size 1 1)
					(thickness 0.15)
				)
				(justify mirror)
			)
		)
		(property "Voltage" ""
			(at 88.912022 306.460634 0)
			(layer "B.Fab")
			(hide yes)
			(effects
				(font
					(size 1 1)
					(thickness 0.15)
				)
				(justify mirror)
			)
		)
		(sheetname "Ethernet")
		(sheetfile "ethernet.kicad_sch")
		(attr smd)
		(fp_rect
			(start -0.94 0.47)
			(end 0.94 -0.47)
			(stroke
				(width 0.05)
				(type solid)
			)
			(fill no)
			(layer "B.CrtYd")
		)
		(fp_rect
			(start -0.499 0.249)
			(end 0.499 -0.249)
			(stroke
				(width 0.15)
				(type solid)
			)
			(fill no)
			(layer "B.Fab")
		)
		(pad "1" smd roundrect
			(at -0.484 0 270)
			(size 0.59 0.64)
			(layers "B.Cu" "B.Mask" "B.Paste")
			(roundrect_rratio 0.25)
			(net 531 "/Ethernet/AVDDH")
			(pintype "passive")
		)
		(pad "2" smd roundrect
			(at 0.484 0 270)
			(size 0.59 0.64)
			(layers "B.Cu" "B.Mask" "B.Paste")
			(roundrect_rratio 0.25)
			(net 5 "GND")
			(pintype "passive")
		)
	)
	(footprint "antmicro-footprints:C_0402_1005Metric"
		(layer "B.Cu")
		(at 194.786328 102.520008 -90)
		(descr "Capacitor SMD 0402")
		(tags "capacitor SMD 0402")
		(property "Reference" "C114"
			(at -1.320008 0.486328 90)
			(layer "B.SilkS")
			(effects
				(font
					(size 0.7 0.7)
					(thickness 0.15)
				)
				(justify left bottom mirror)
			)
		)
		(property "Value" "C_10n_0402"
			(at 0 -1.4 90)
			(layer "B.Fab")
			(effects
				(font
					(size 0.7 0.7)
					(thickness 0.15)
				)
				(justify left bottom mirror)
			)
		)
		(property "Description" " "
			(at 0 0 270)
			(layer "F.Fab")
			(hide yes)
			(effects
				(font
					(size 1.27 1.27)
					(thickness 0.15)
				)
			)
		)
		(property "Author" "Antmicro"
			(at 92.26632 297.306336 0)
			(layer "B.Fab")
			(hide yes)
			(effects
				(font
					(size 1 1)
					(thickness 0.15)
				)
				(justify mirror)
			)
		)
		(property "Dielectric" "X7R"
			(at 92.26632 297.306336 0)
			(layer "B.Fab")
			(hide yes)
			(effects
				(font
					(size 1 1)
					(thickness 0.15)
				)
				(justify mirror)
			)
		)
		(property "License" "Apache-2.0"
			(at 92.26632 297.306336 0)
			(layer "B.Fab")
			(hide yes)
			(effects
				(font
					(size 1 1)
					(thickness 0.15)
				)
				(justify mirror)
			)
		)
		(property "MPN" "GRM155R71H103KA88D"
			(at 92.26632 297.306336 0)
			(layer "B.Fab")
			(hide yes)
			(effects
				(font
					(size 1 1)
					(thickness 0.15)
				)
				(justify mirror)
			)
		)
		(property "Manufacturer" "Murata"
			(at 92.26632 297.306336 0)
			(layer "B.Fab")
			(hide yes)
			(effects
				(font
					(size 1 1)
					(thickness 0.15)
				)
				(justify mirror)
			)
		)
		(property "Val" "10n"
			(at 92.26632 297.306336 0)
			(layer "B.Fab")
			(hide yes)
			(effects
				(font
					(size 1 1)
					(thickness 0.15)
				)
				(justify mirror)
			)
		)
		(property "Voltage" "50V"
			(at 92.26632 297.306336 0)
			(layer "B.Fab")
			(hide yes)
			(effects
				(font
					(size 1 1)
					(thickness 0.15)
				)
				(justify mirror)
			)
		)
		(sheetname "Ethernet")
		(sheetfile "ethernet.kicad_sch")
		(attr smd)
		(fp_rect
			(start -0.94 0.47)
			(end 0.94 -0.47)
			(stroke
				(width 0.05)
				(type solid)
			)
			(fill no)
			(layer "B.CrtYd")
		)
		(fp_rect
			(start -0.499 0.249)
			(end 0.499 -0.249)
			(stroke
				(width 0.15)
				(type solid)
			)
			(fill no)
			(layer "B.Fab")
		)
		(pad "1" smd roundrect
			(at -0.484 0 270)
			(size 0.59 0.64)
			(layers "B.Cu" "B.Mask" "B.Paste")
			(roundrect_rratio 0.25)
			(net 459 "3V3_SYS")
			(pintype "passive")
		)
		(pad "2" smd roundrect
			(at 0.484 0 270)
			(size 0.59 0.64)
			(layers "B.Cu" "B.Mask" "B.Paste")
			(roundrect_rratio 0.25)
			(net 5 "GND")
			(pintype "passive")
		)
	)
	(footprint "antmicro-footprints:C_0402_1005Metric"
		(layer "B.Cu")
		(at 203.186328 108.774306 -90)
		(descr "Capacitor SMD 0402")
		(tags "capacitor SMD 0402")
		(property "Reference" "C115"
			(at 0.810694 -0.413672 90)
			(layer "B.SilkS")
			(effects
				(font
					(size 0.7 0.7)
					(thickness 0.15)
				)
				(justify left bottom mirror)
			)
		)
		(property "Value" "C_4u7_0402"
			(at 0 -1.4 90)
			(layer "B.Fab")
			(effects
				(font
					(size 0.7 0.7)
					(thickness 0.15)
				)
				(justify left bottom mirror)
			)
		)
		(property "Description" " "
			(at 0 0 270)
			(layer "F.Fab")
			(hide yes)
			(effects
				(font
					(size 1.27 1.27)
					(thickness 0.15)
				)
			)
		)
		(property "Author" "Antmicro"
			(at 94.412022 311.960634 0)
			(layer "B.Fab")
			(hide yes)
			(effects
				(font
					(size 1 1)
					(thickness 0.15)
				)
				(justify mirror)
			)
		)
		(property "Dielectric" ""
			(at 94.412022 311.960634 0)
			(layer "B.Fab")
			(hide yes)
			(effects
				(font
					(size 1 1)
					(thickness 0.15)
				)
				(justify mirror)
			)
		)
		(property "License" "Apache-2.0"
			(at 94.412022 311.960634 0)
			(layer "B.Fab")
			(hide yes)
			(effects
				(font
					(size 1 1)
					(thickness 0.15)
				)
				(justify mirror)
			)
		)
		(property "MPN" "GRM155R61A475MEAAD"
			(at 94.412022 311.960634 0)
			(layer "B.Fab")
			(hide yes)
			(effects
				(font
					(size 1 1)
					(thickness 0.15)
				)
				(justify mirror)
			)
		)
		(property "Manufacturer" "Murata"
			(at 94.412022 311.960634 0)
			(layer "B.Fab")
			(hide yes)
			(effects
				(font
					(size 1 1)
					(thickness 0.15)
				)
				(justify mirror)
			)
		)
		(property "Val" "4u7"
			(at 94.412022 311.960634 0)
			(layer "B.Fab")
			(hide yes)
			(effects
				(font
					(size 1 1)
					(thickness 0.15)
				)
				(justify mirror)
			)
		)
		(property "Voltage" ""
			(at 94.412022 311.960634 0)
			(layer "B.Fab")
			(hide yes)
			(effects
				(font
					(size 1 1)
					(thickness 0.15)
				)
				(justify mirror)
			)
		)
		(sheetname "Ethernet")
		(sheetfile "ethernet.kicad_sch")
		(attr smd)
		(fp_rect
			(start -0.94 0.47)
			(end 0.94 -0.47)
			(stroke
				(width 0.05)
				(type solid)
			)
			(fill no)
			(layer "B.CrtYd")
		)
		(fp_rect
			(start -0.499 0.249)
			(end 0.499 -0.249)
			(stroke
				(width 0.15)
				(type solid)
			)
			(fill no)
			(layer "B.Fab")
		)
		(pad "1" smd roundrect
			(at -0.484 0 270)
			(size 0.59 0.64)
			(layers "B.Cu" "B.Mask" "B.Paste")
			(roundrect_rratio 0.25)
			(net 531 "/Ethernet/AVDDH")
			(pintype "passive")
		)
		(pad "2" smd roundrect
			(at 0.484 0 270)
			(size 0.59 0.64)
			(layers "B.Cu" "B.Mask" "B.Paste")
			(roundrect_rratio 0.25)
			(net 5 "GND")
			(pintype "passive")
		)
	)
	(footprint "antmicro-footprints:C_0402_1005Metric"
		(layer "B.Cu")
		(at 200.486328 100.020008 -90)
		(descr "Capacitor SMD 0402")
		(tags "capacitor SMD 0402")
		(property "Reference" "C116"
			(at -1.820008 -6.613672 90)
			(layer "B.SilkS")
			(effects
				(font
					(size 0.7 0.7)
					(thickness 0.15)
				)
				(justify left bottom mirror)
			)
		)
		(property "Value" "C_10n_0402"
			(at 0 -1.4 90)
			(layer "B.Fab")
			(effects
				(font
					(size 0.7 0.7)
					(thickness 0.15)
				)
				(justify left bottom mirror)
			)
		)
		(property "Description" " "
			(at 0 0 270)
			(layer "F.Fab")
			(hide yes)
			(effects
				(font
					(size 1.27 1.27)
					(thickness 0.15)
				)
			)
		)
		(property "Author" "Antmicro"
			(at 100.46632 300.506336 0)
			(layer "B.Fab")
			(hide yes)
			(effects
				(font
					(size 1 1)
					(thickness 0.15)
				)
				(justify mirror)
			)
		)
		(property "Dielectric" "X7R"
			(at 100.46632 300.506336 0)
			(layer "B.Fab")
			(hide yes)
			(effects
				(font
					(size 1 1)
					(thickness 0.15)
				)
				(justify mirror)
			)
		)
		(property "License" "Apache-2.0"
			(at 100.46632 300.506336 0)
			(layer "B.Fab")
			(hide yes)
			(effects
				(font
					(size 1 1)
					(thickness 0.15)
				)
				(justify mirror)
			)
		)
		(property "MPN" "GRM155R71H103KA88D"
			(at 100.46632 300.506336 0)
			(layer "B.Fab")
			(hide yes)
			(effects
				(font
					(size 1 1)
					(thickness 0.15)
				)
				(justify mirror)
			)
		)
		(property "Manufacturer" "Murata"
			(at 100.46632 300.506336 0)
			(layer "B.Fab")
			(hide yes)
			(effects
				(font
					(size 1 1)
					(thickness 0.15)
				)
				(justify mirror)
			)
		)
		(property "Val" "10n"
			(at 100.46632 300.506336 0)
			(layer "B.Fab")
			(hide yes)
			(effects
				(font
					(size 1 1)
					(thickness 0.15)
				)
				(justify mirror)
			)
		)
		(property "Voltage" "50V"
			(at 100.46632 300.506336 0)
			(layer "B.Fab")
			(hide yes)
			(effects
				(font
					(size 1 1)
					(thickness 0.15)
				)
				(justify mirror)
			)
		)
		(sheetname "Ethernet")
		(sheetfile "ethernet.kicad_sch")
		(attr smd)
		(fp_rect
			(start -0.94 0.47)
			(end 0.94 -0.47)
			(stroke
				(width 0.05)
				(type solid)
			)
			(fill no)
			(layer "B.CrtYd")
		)
		(fp_rect
			(start -0.499 0.249)
			(end 0.499 -0.249)
			(stroke
				(width 0.15)
				(type solid)
			)
			(fill no)
			(layer "B.Fab")
		)
		(pad "1" smd roundrect
			(at -0.484 0 270)
			(size 0.59 0.64)
			(layers "B.Cu" "B.Mask" "B.Paste")
			(roundrect_rratio 0.25)
			(net 602 "1V2_SYS")
			(pintype "passive")
		)
		(pad "2" smd roundrect
			(at 0.484 0 270)
			(size 0.59 0.64)
			(layers "B.Cu" "B.Mask" "B.Paste")
			(roundrect_rratio 0.25)
			(net 5 "GND")
			(pintype "passive")
		)
	)
	(footprint "antmicro-footprints:C_0402_1005Metric"
		(layer "B.Cu")
		(at 204.186328 108.774306 -90)
		(descr "Capacitor SMD 0402")
		(tags "capacitor SMD 0402")
		(property "Reference" "C118"
			(at 0.810694 -0.413672 90)
			(layer "B.SilkS")
			(effects
				(font
					(size 0.7 0.7)
					(thickness 0.15)
				)
				(justify left bottom mirror)
			)
		)
		(property "Value" "C_4u7_0402"
			(at 0 -1.4 90)
			(layer "B.Fab")
			(effects
				(font
					(size 0.7 0.7)
					(thickness 0.15)
				)
				(justify left bottom mirror)
			)
		)
		(property "Description" " "
			(at 0 0 270)
			(layer "F.Fab")
			(hide yes)
			(effects
				(font
					(size 1.27 1.27)
					(thickness 0.15)
				)
			)
		)
		(property "Author" "Antmicro"
			(at 95.412022 312.960634 0)
			(layer "B.Fab")
			(hide yes)
			(effects
				(font
					(size 1 1)
					(thickness 0.15)
				)
				(justify mirror)
			)
		)
		(property "Dielectric" ""
			(at 95.412022 312.960634 0)
			(layer "B.Fab")
			(hide yes)
			(effects
				(font
					(size 1 1)
					(thickness 0.15)
				)
				(justify mirror)
			)
		)
		(property "License" "Apache-2.0"
			(at 95.412022 312.960634 0)
			(layer "B.Fab")
			(hide yes)
			(effects
				(font
					(size 1 1)
					(thickness 0.15)
				)
				(justify mirror)
			)
		)
		(property "MPN" "GRM155R61A475MEAAD"
			(at 95.412022 312.960634 0)
			(layer "B.Fab")
			(hide yes)
			(effects
				(font
					(size 1 1)
					(thickness 0.15)
				)
				(justify mirror)
			)
		)
		(property "Manufacturer" "Murata"
			(at 95.412022 312.960634 0)
			(layer "B.Fab")
			(hide yes)
			(effects
				(font
					(size 1 1)
					(thickness 0.15)
				)
				(justify mirror)
			)
		)
		(property "Val" "4u7"
			(at 95.412022 312.960634 0)
			(layer "B.Fab")
			(hide yes)
			(effects
				(font
					(size 1 1)
					(thickness 0.15)
				)
				(justify mirror)
			)
		)
		(property "Voltage" ""
			(at 95.412022 312.960634 0)
			(layer "B.Fab")
			(hide yes)
			(effects
				(font
					(size 1 1)
					(thickness 0.15)
				)
				(justify mirror)
			)
		)
		(sheetname "Ethernet")
		(sheetfile "ethernet.kicad_sch")
		(attr smd)
		(fp_rect
			(start -0.94 0.47)
			(end 0.94 -0.47)
			(stroke
				(width 0.05)
				(type solid)
			)
			(fill no)
			(layer "B.CrtYd")
		)
		(fp_rect
			(start -0.499 0.249)
			(end 0.499 -0.249)
			(stroke
				(width 0.15)
				(type solid)
			)
			(fill no)
			(layer "B.Fab")
		)
		(pad "1" smd roundrect
			(at -0.484 0 270)
			(size 0.59 0.64)
			(layers "B.Cu" "B.Mask" "B.Paste")
			(roundrect_rratio 0.25)
			(net 531 "/Ethernet/AVDDH")
			(pintype "passive")
		)
		(pad "2" smd roundrect
			(at 0.484 0 270)
			(size 0.59 0.64)
			(layers "B.Cu" "B.Mask" "B.Paste")
			(roundrect_rratio 0.25)
			(net 5 "GND")
			(pintype "passive")
		)
	)
	(footprint "antmicro-footprints:C_0402_1005Metric"
		(layer "B.Cu")
		(at 202.686328 100.020008 -90)
		(descr "Capacitor SMD 0402")
		(tags "capacitor SMD 0402")
		(property "Reference" "C119"
			(at -1.820008 -6.613672 90)
			(layer "B.SilkS")
			(effects
				(font
					(size 0.7 0.7)
					(thickness 0.15)
				)
				(justify left bottom mirror)
			)
		)
		(property "Value" "C_10n_0402"
			(at 0 -1.4 90)
			(layer "B.Fab")
			(effects
				(font
					(size 0.7 0.7)
					(thickness 0.15)
				)
				(justify left bottom mirror)
			)
		)
		(property "Description" " "
			(at 0 0 270)
			(layer "F.Fab")
			(hide yes)
			(effects
				(font
					(size 1.27 1.27)
					(thickness 0.15)
				)
			)
		)
		(property "Author" "Antmicro"
			(at 102.66632 302.706336 0)
			(layer "B.Fab")
			(hide yes)
			(effects
				(font
					(size 1 1)
					(thickness 0.15)
				)
				(justify mirror)
			)
		)
		(property "Dielectric" "X7R"
			(at 102.66632 302.706336 0)
			(layer "B.Fab")
			(hide yes)
			(effects
				(font
					(size 1 1)
					(thickness 0.15)
				)
				(justify mirror)
			)
		)
		(property "License" "Apache-2.0"
			(at 102.66632 302.706336 0)
			(layer "B.Fab")
			(hide yes)
			(effects
				(font
					(size 1 1)
					(thickness 0.15)
				)
				(justify mirror)
			)
		)
		(property "MPN" "GRM155R71H103KA88D"
			(at 102.66632 302.706336 0)
			(layer "B.Fab")
			(hide yes)
			(effects
				(font
					(size 1 1)
					(thickness 0.15)
				)
				(justify mirror)
			)
		)
		(property "Manufacturer" "Murata"
			(at 102.66632 302.706336 0)
			(layer "B.Fab")
			(hide yes)
			(effects
				(font
					(size 1 1)
					(thickness 0.15)
				)
				(justify mirror)
			)
		)
		(property "Val" "10n"
			(at 102.66632 302.706336 0)
			(layer "B.Fab")
			(hide yes)
			(effects
				(font
					(size 1 1)
					(thickness 0.15)
				)
				(justify mirror)
			)
		)
		(property "Voltage" "50V"
			(at 102.66632 302.706336 0)
			(layer "B.Fab")
			(hide yes)
			(effects
				(font
					(size 1 1)
					(thickness 0.15)
				)
				(justify mirror)
			)
		)
		(sheetname "Ethernet")
		(sheetfile "ethernet.kicad_sch")
		(attr smd)
		(fp_rect
			(start -0.94 0.47)
			(end 0.94 -0.47)
			(stroke
				(width 0.05)
				(type solid)
			)
			(fill no)
			(layer "B.CrtYd")
		)
		(fp_rect
			(start -0.499 0.249)
			(end 0.499 -0.249)
			(stroke
				(width 0.15)
				(type solid)
			)
			(fill no)
			(layer "B.Fab")
		)
		(pad "1" smd roundrect
			(at -0.484 0 270)
			(size 0.59 0.64)
			(layers "B.Cu" "B.Mask" "B.Paste")
			(roundrect_rratio 0.25)
			(net 602 "1V2_SYS")
			(pintype "passive")
		)
		(pad "2" smd roundrect
			(at 0.484 0 270)
			(size 0.59 0.64)
			(layers "B.Cu" "B.Mask" "B.Paste")
			(roundrect_rratio 0.25)
			(net 5 "GND")
			(pintype "passive")
		)
	)
	(footprint "antmicro-footprints:FB_0603_1608Metric"
		(layer "B.Cu")
		(at 195.786328 108.274306)
		(property "Reference" "FB4"
			(at 1.113672 1.525694 180)
			(layer "B.SilkS")
			(effects
				(font
					(size 0.7 0.7)
					(thickness 0.15)
				)
				(justify left bottom mirror)
			)
		)
		(property "Value" "FB_120Z_2A_0603"
			(at 0 -1.5 180)
			(layer "B.Fab")
			(effects
				(font
					(size 0.7 0.7)
					(thickness 0.15)
				)
				(justify left bottom mirror)
			)
		)
		(property "Description" "Ferrite Beads WE-TMSB Suppression 240Ohm 200mA "
			(at 0 0 0)
			(layer "F.Fab")
			(hide yes)
			(effects
				(font
					(size 1.27 1.27)
					(thickness 0.15)
				)
			)
		)
		(property "Author" "Antmicro"
			(at 0 0 0)
			(layer "B.Fab")
			(hide yes)
			(effects
				(font
					(size 1 1)
					(thickness 0.15)
				)
				(justify mirror)
			)
		)
		(property "License" "Apache-2.0"
			(at 0 0 0)
			(layer "B.Fab")
			(hide yes)
			(effects
				(font
					(size 1 1)
					(thickness 0.15)
				)
				(justify mirror)
			)
		)
		(property "MPN" "BLM18PG121SN1D"
			(at 0 0 0)
			(layer "B.Fab")
			(hide yes)
			(effects
				(font
					(size 1 1)
					(thickness 0.15)
				)
				(justify mirror)
			)
		)
		(property "Manufacturer" "Murata"
			(at 0 0 0)
			(layer "B.Fab")
			(hide yes)
			(effects
				(font
					(size 1 1)
					(thickness 0.15)
				)
				(justify mirror)
			)
		)
		(sheetname "Ethernet")
		(sheetfile "ethernet.kicad_sch")
		(attr smd)
		(fp_line
			(start -0.196 -0.406)
			(end 0.193 -0.406)
			(stroke
				(width 0.15)
				(type solid)
			)
			(layer "B.SilkS")
		)
		(fp_line
			(start -0.196 0.408)
			(end 0.193 0.408)
			(stroke
				(width 0.15)
				(type solid)
			)
			(layer "B.SilkS")
		)
		(fp_rect
			(start -1.3 0.6)
			(end 1.3 -0.6)
			(stroke
				(width 0.05)
				(type solid)
			)
			(fill no)
			(layer "B.CrtYd")
		)
		(fp_line
			(start -0.803 -0.406)
			(end -0.803 0.408)
			(stroke
				(width 0.15)
				(type solid)
			)
			(layer "B.Fab")
		)
		(fp_line
			(start 0.8 -0.406)
			(end -0.803 -0.406)
			(stroke
				(width 0.15)
				(type solid)
			)
			(layer "B.Fab")
		)
		(fp_line
			(start 0.8 0.408)
			(end -0.803 0.408)
			(stroke
				(width 0.15)
				(type solid)
			)
			(layer "B.Fab")
		)
		(fp_line
			(start 0.8 0.408)
			(end 0.8 -0.406)
			(stroke
				(width 0.15)
				(type solid)
			)
			(layer "B.Fab")
		)
		(pad "1" smd roundrect
			(at -0.891 0)
			(size 0.762 1.09)
			(layers "B.Cu" "B.Mask" "B.Paste")
			(roundrect_rratio 0.15)
			(net 459 "3V3_SYS")
			(pintype "passive")
		)
		(pad "2" smd roundrect
			(at 0.888 0)
			(size 0.762 1.09)
			(layers "B.Cu" "B.Mask" "B.Paste")
			(roundrect_rratio 0.15)
			(net 531 "/Ethernet/AVDDH")
			(pintype "passive")
		)
	)
	(footprint "antmicro-footprints:FB_0603_1608Metric"
		(layer "B.Cu")
		(at 213.086328 121.189063 90)
		(property "Reference" "FB7"
			(at 0.989063 1.513672 270)
			(layer "B.SilkS")
			(effects
				(font
					(size 0.7 0.7)
					(thickness 0.15)
				)
				(justify left bottom mirror)
			)
		)
		(property "Value" "FB_120Z_2A_0603"
			(at 0 -1.5 270)
			(layer "B.Fab")
			(effects
				(font
					(size 0.7 0.7)
					(thickness 0.15)
				)
				(justify left bottom mirror)
			)
		)
		(property "Description" "Ferrite Beads WE-TMSB Suppression 240Ohm 200mA "
			(at 0 0 90)
			(layer "F.Fab")
			(hide yes)
			(effects
				(font
					(size 1.27 1.27)
					(thickness 0.15)
				)
			)
		)
		(property "Author" "Antmicro"
			(at 334.275391 -91.897265 0)
			(layer "B.Fab")
			(hide yes)
			(effects
				(font
					(size 1 1)
					(thickness 0.15)
				)
				(justify mirror)
			)
		)
		(property "License" "Apache-2.0"
			(at 334.275391 -91.897265 0)
			(layer "B.Fab")
			(hide yes)
			(effects
				(font
					(size 1 1)
					(thickness 0.15)
				)
				(justify mirror)
			)
		)
		(property "MPN" "BLM18PG121SN1D"
			(at 334.275391 -91.897265 0)
			(layer "B.Fab")
			(hide yes)
			(effects
				(font
					(size 1 1)
					(thickness 0.15)
				)
				(justify mirror)
			)
		)
		(property "Manufacturer" "Murata"
			(at 334.275391 -91.897265 0)
			(layer "B.Fab")
			(hide yes)
			(effects
				(font
					(size 1 1)
					(thickness 0.15)
				)
				(justify mirror)
			)
		)
		(sheetname "Ethernet")
		(sheetfile "ethernet.kicad_sch")
		(attr smd)
		(fp_line
			(start -0.196 -0.406)
			(end 0.193 -0.406)
			(stroke
				(width 0.15)
				(type solid)
			)
			(layer "B.SilkS")
		)
		(fp_line
			(start -0.196 0.408)
			(end 0.193 0.408)
			(stroke
				(width 0.15)
				(type solid)
			)
			(layer "B.SilkS")
		)
		(fp_rect
			(start -1.3 0.6)
			(end 1.3 -0.6)
			(stroke
				(width 0.05)
				(type solid)
			)
			(fill no)
			(layer "B.CrtYd")
		)
		(fp_line
			(start 0.8 -0.406)
			(end -0.803 -0.406)
			(stroke
				(width 0.15)
				(type solid)
			)
			(layer "B.Fab")
		)
		(fp_line
			(start -0.803 -0.406)
			(end -0.803 0.408)
			(stroke
				(width 0.15)
				(type solid)
			)
			(layer "B.Fab")
		)
		(fp_line
			(start 0.8 0.408)
			(end 0.8 -0.406)
			(stroke
				(width 0.15)
				(type solid)
			)
			(layer "B.Fab")
		)
		(fp_line
			(start 0.8 0.408)
			(end -0.803 0.408)
			(stroke
				(width 0.15)
				(type solid)
			)
			(layer "B.Fab")
		)
		(pad "1" smd roundrect
			(at -0.891 0 90)
			(size 0.762 1.09)
			(layers "B.Cu" "B.Mask" "B.Paste")
			(roundrect_rratio 0.15)
			(net 521 "Net-(FB7-Pad1)")
			(pintype "passive")
		)
		(pad "2" smd roundrect
			(at 0.888 0 90)
			(size 0.762 1.09)
			(layers "B.Cu" "B.Mask" "B.Paste")
			(roundrect_rratio 0.15)
			(net 5 "GND")
			(pintype "passive")
		)
	)
	(footprint "antmicro-footprints:R_0402_1005Metric"
		(layer "B.Cu")
		(at 191.686328 128.989063 180)
		(descr "Resistor SMD 0402")
		(tags "resistor SMD 0402")
		(property "Reference" "R70"
			(at -1.013672 0.489063 0)
			(layer "B.SilkS")
			(effects
				(font
					(size 0.7 0.7)
					(thickness 0.15)
				)
				(justify left bottom mirror)
			)
		)
		(property "Value" "R_220R_0402"
			(at 0 -1.4 0)
			(layer "B.Fab")
			(effects
				(font
					(size 0.7 0.7)
					(thickness 0.15)
				)
				(justify left bottom mirror)
			)
		)
		(property "Description" "220R resistor in 0402 package with 1% tolerance"
			(at 0 0 180)
			(layer "F.Fab")
			(hide yes)
			(effects
				(font
					(size 1.27 1.27)
					(thickness 0.15)
				)
			)
		)
		(property "Author" "Antmicro"
			(at 383.372656 257.978126 0)
			(layer "B.Fab")
			(hide yes)
			(effects
				(font
					(size 1 1)
					(thickness 0.15)
				)
				(justify mirror)
			)
		)
		(property "License" "Apache-2.0"
			(at 383.372656 257.978126 0)
			(layer "B.Fab")
			(hide yes)
			(effects
				(font
					(size 1 1)
					(thickness 0.15)
				)
				(justify mirror)
			)
		)
		(property "MPN" "CR0402-FX-2200GLF"
			(at 383.372656 257.978126 0)
			(layer "B.Fab")
			(hide yes)
			(effects
				(font
					(size 1 1)
					(thickness 0.15)
				)
				(justify mirror)
			)
		)
		(property "Manufacturer" "Bourns"
			(at 383.372656 257.978126 0)
			(layer "B.Fab")
			(hide yes)
			(effects
				(font
					(size 1 1)
					(thickness 0.15)
				)
				(justify mirror)
			)
		)
		(property "Tolerance" "1%"
			(at 383.372656 257.978126 0)
			(layer "B.Fab")
			(hide yes)
			(effects
				(font
					(size 1 1)
					(thickness 0.15)
				)
				(justify mirror)
			)
		)
		(property "Val" "220R"
			(at 383.372656 257.978126 0)
			(layer "B.Fab")
			(hide yes)
			(effects
				(font
					(size 1 1)
					(thickness 0.15)
				)
				(justify mirror)
			)
		)
		(sheetname "Ethernet")
		(sheetfile "ethernet.kicad_sch")
		(attr smd)
		(fp_rect
			(start -0.93 0.47)
			(end 0.93 -0.47)
			(stroke
				(width 0.05)
				(type solid)
			)
			(fill no)
			(layer "B.CrtYd")
		)
		(fp_rect
			(start -0.5 0.25)
			(end 0.5 -0.25)
			(stroke
				(width 0.15)
				(type solid)
			)
			(fill no)
			(layer "B.Fab")
		)
		(pad "1" smd roundrect
			(at -0.485 0 180)
			(size 0.59 0.64)
			(layers "B.Cu" "B.Mask" "B.Paste")
			(roundrect_rratio 0.25)
			(net 89 "Net-(J5-LED1_Y+)")
			(pintype "passive")
		)
		(pad "2" smd roundrect
			(at 0.485 0 180)
			(size 0.59 0.64)
			(layers "B.Cu" "B.Mask" "B.Paste")
			(roundrect_rratio 0.25)
			(net 459 "3V3_SYS")
			(pintype "passive")
		)
	)
	(footprint "antmicro-footprints:R_0402_1005Metric"
		(layer "B.Cu")
		(at 202.686328 128.989063 180)
		(descr "Resistor SMD 0402")
		(tags "resistor SMD 0402")
		(property "Reference" "R71"
			(at -1.013672 0.489063 0)
			(layer "B.SilkS")
			(effects
				(font
					(size 0.7 0.7)
					(thickness 0.15)
				)
				(justify left bottom mirror)
			)
		)
		(property "Value" "R_220R_0402"
			(at 0 -1.4 0)
			(layer "B.Fab")
			(effects
				(font
					(size 0.7 0.7)
					(thickness 0.15)
				)
				(justify left bottom mirror)
			)
		)
		(property "Description" "220R resistor in 0402 package with 1% tolerance"
			(at 0 0 180)
			(layer "F.Fab")
			(hide yes)
			(effects
				(font
					(size 1.27 1.27)
					(thickness 0.15)
				)
			)
		)
		(property "Author" "Antmicro"
			(at 405.372656 257.978126 0)
			(layer "B.Fab")
			(hide yes)
			(effects
				(font
					(size 1 1)
					(thickness 0.15)
				)
				(justify mirror)
			)
		)
		(property "License" "Apache-2.0"
			(at 405.372656 257.978126 0)
			(layer "B.Fab")
			(hide yes)
			(effects
				(font
					(size 1 1)
					(thickness 0.15)
				)
				(justify mirror)
			)
		)
		(property "MPN" "CR0402-FX-2200GLF"
			(at 405.372656 257.978126 0)
			(layer "B.Fab")
			(hide yes)
			(effects
				(font
					(size 1 1)
					(thickness 0.15)
				)
				(justify mirror)
			)
		)
		(property "Manufacturer" "Bourns"
			(at 405.372656 257.978126 0)
			(layer "B.Fab")
			(hide yes)
			(effects
				(font
					(size 1 1)
					(thickness 0.15)
				)
				(justify mirror)
			)
		)
		(property "Tolerance" "1%"
			(at 405.372656 257.978126 0)
			(layer "B.Fab")
			(hide yes)
			(effects
				(font
					(size 1 1)
					(thickness 0.15)
				)
				(justify mirror)
			)
		)
		(property "Val" "220R"
			(at 405.372656 257.978126 0)
			(layer "B.Fab")
			(hide yes)
			(effects
				(font
					(size 1 1)
					(thickness 0.15)
				)
				(justify mirror)
			)
		)
		(sheetname "Ethernet")
		(sheetfile "ethernet.kicad_sch")
		(attr smd)
		(fp_rect
			(start -0.93 0.47)
			(end 0.93 -0.47)
			(stroke
				(width 0.05)
				(type solid)
			)
			(fill no)
			(layer "B.CrtYd")
		)
		(fp_rect
			(start -0.5 0.25)
			(end 0.5 -0.25)
			(stroke
				(width 0.15)
				(type solid)
			)
			(fill no)
			(layer "B.Fab")
		)
		(pad "1" smd roundrect
			(at -0.485 0 180)
			(size 0.59 0.64)
			(layers "B.Cu" "B.Mask" "B.Paste")
			(roundrect_rratio 0.25)
			(net 90 "Net-(J5-LED2_G+)")
			(pintype "passive")
		)
		(pad "2" smd roundrect
			(at 0.485 0 180)
			(size 0.59 0.64)
			(layers "B.Cu" "B.Mask" "B.Paste")
			(roundrect_rratio 0.25)
			(net 459 "3V3_SYS")
			(pintype "passive")
		)
	)
	(footprint "antmicro-footprints:R_0603_1608Metric"
		(layer "B.Cu")
		(at 170.536328 86.697157 180)
		(descr "Resistor SMD 0603")
		(tags "resistor SMD 0603")
		(property "Reference" "R3"
			(at -0.763672 0.597157 0)
			(layer "B.SilkS")
			(effects
				(font
					(size 0.7 0.7)
					(thickness 0.15)
				)
				(justify left bottom mirror)
			)
		)
		(property "Value" "R_120R_0603"
			(at 0 -1.6 0)
			(layer "B.Fab")
			(effects
				(font
					(size 0.7 0.7)
					(thickness 0.15)
				)
				(justify left bottom mirror)
			)
		)
		(property "Description" "120R resistor in 0603 package with 1% tolerance"
			(at 0 0 180)
			(layer "F.Fab")
			(hide yes)
			(effects
				(font
					(size 1.27 1.27)
					(thickness 0.15)
				)
			)
		)
		(property "Author" "Antmicro"
			(at 341.072656 173.394314 0)
			(layer "B.Fab")
			(hide yes)
			(effects
				(font
					(size 1 1)
					(thickness 0.15)
				)
				(justify mirror)
			)
		)
		(property "License" "Apache-2.0"
			(at 341.072656 173.394314 0)
			(layer "B.Fab")
			(hide yes)
			(effects
				(font
					(size 1 1)
					(thickness 0.15)
				)
				(justify mirror)
			)
		)
		(property "MPN" "CR0603-FX-1200ELF"
			(at 341.072656 173.394314 0)
			(layer "B.Fab")
			(hide yes)
			(effects
				(font
					(size 1 1)
					(thickness 0.15)
				)
				(justify mirror)
			)
		)
		(property "Manufacturer" "Bourns"
			(at 341.072656 173.394314 0)
			(layer "B.Fab")
			(hide yes)
			(effects
				(font
					(size 1 1)
					(thickness 0.15)
				)
				(justify mirror)
			)
		)
		(property "Tolerance" "1%"
			(at 341.072656 173.394314 0)
			(layer "B.Fab")
			(hide yes)
			(effects
				(font
					(size 1 1)
					(thickness 0.15)
				)
				(justify mirror)
			)
		)
		(property "Val" "120R"
			(at 341.072656 173.394314 0)
			(layer "B.Fab")
			(hide yes)
			(effects
				(font
					(size 1 1)
					(thickness 0.15)
				)
				(justify mirror)
			)
		)
		(sheetname "FPGA Banks")
		(sheetfile "fpga-banks.kicad_sch")
		(attr smd)
		(fp_line
			(start -0.3 0.3)
			(end 0.3 0.3)
			(stroke
				(width 0.15)
				(type solid)
			)
			(layer "B.SilkS")
		)
		(fp_line
			(start -0.3 -0.3)
			(end 0.3 -0.3)
			(stroke
				(width 0.15)
				(type solid)
			)
			(layer "B.SilkS")
		)
		(fp_rect
			(start -1.25 0.7)
			(end 1.25 -0.7)
			(stroke
				(width 0.05)
				(type solid)
			)
			(fill no)
			(layer "B.CrtYd")
		)
		(fp_rect
			(start -0.8 0.4)
			(end 0.8 -0.4)
			(stroke
				(width 0.15)
				(type solid)
			)
			(fill no)
			(layer "B.Fab")
		)
		(pad "1" smd roundrect
			(at -0.7 0 180)
			(size 0.6 0.8)
			(layers "B.Cu" "B.Mask" "B.Paste")
			(roundrect_rratio 0.2)
			(net 511 "VRN")
			(pintype "passive")
		)
		(pad "2" smd roundrect
			(at 0.7 0 180)
			(size 0.6 0.8)
			(layers "B.Cu" "B.Mask" "B.Paste")
			(roundrect_rratio 0.2)
			(net 66 "VDDQ")
			(pintype "passive")
		)
	)
	(footprint "antmicro-footprints:R_0603_1608Metric"
		(layer "B.Cu")
		(at 162.836328 89.897157)
		(descr "Resistor SMD 0603")
		(tags "resistor SMD 0603")
		(property "Reference" "R4"
			(at 0.663672 -0.597157 180)
			(layer "B.SilkS")
			(effects
				(font
					(size 0.7 0.7)
					(thickness 0.15)
				)
				(justify left bottom mirror)
			)
		)
		(property "Value" "R_120R_0603"
			(at 0 -1.6 180)
			(layer "B.Fab")
			(effects
				(font
					(size 0.7 0.7)
					(thickness 0.15)
				)
				(justify left bottom mirror)
			)
		)
		(property "Description" "120R resistor in 0603 package with 1% tolerance"
			(at 0 0 0)
			(layer "F.Fab")
			(hide yes)
			(effects
				(font
					(size 1.27 1.27)
					(thickness 0.15)
				)
			)
		)
		(property "Author" "Antmicro"
			(at 0 0 0)
			(layer "B.Fab")
			(hide yes)
			(effects
				(font
					(size 1 1)
					(thickness 0.15)
				)
				(justify mirror)
			)
		)
		(property "License" "Apache-2.0"
			(at 0 0 0)
			(layer "B.Fab")
			(hide yes)
			(effects
				(font
					(size 1 1)
					(thickness 0.15)
				)
				(justify mirror)
			)
		)
		(property "MPN" "CR0603-FX-1200ELF"
			(at 0 0 0)
			(layer "B.Fab")
			(hide yes)
			(effects
				(font
					(size 1 1)
					(thickness 0.15)
				)
				(justify mirror)
			)
		)
		(property "Manufacturer" "Bourns"
			(at 0 0 0)
			(layer "B.Fab")
			(hide yes)
			(effects
				(font
					(size 1 1)
					(thickness 0.15)
				)
				(justify mirror)
			)
		)
		(property "Tolerance" "1%"
			(at 0 0 0)
			(layer "B.Fab")
			(hide yes)
			(effects
				(font
					(size 1 1)
					(thickness 0.15)
				)
				(justify mirror)
			)
		)
		(property "Val" "120R"
			(at 0 0 0)
			(layer "B.Fab")
			(hide yes)
			(effects
				(font
					(size 1 1)
					(thickness 0.15)
				)
				(justify mirror)
			)
		)
		(sheetname "FPGA Banks")
		(sheetfile "fpga-banks.kicad_sch")
		(attr smd)
		(fp_line
			(start -0.3 -0.3)
			(end 0.3 -0.3)
			(stroke
				(width 0.15)
				(type solid)
			)
			(layer "B.SilkS")
		)
		(fp_line
			(start -0.3 0.3)
			(end 0.3 0.3)
			(stroke
				(width 0.15)
				(type solid)
			)
			(layer "B.SilkS")
		)
		(fp_rect
			(start -1.25 0.7)
			(end 1.25 -0.7)
			(stroke
				(width 0.05)
				(type solid)
			)
			(fill no)
			(layer "B.CrtYd")
		)
		(fp_rect
			(start -0.8 0.4)
			(end 0.8 -0.4)
			(stroke
				(width 0.15)
				(type solid)
			)
			(fill no)
			(layer "B.Fab")
		)
		(pad "1" smd roundrect
			(at -0.7 0)
			(size 0.6 0.8)
			(layers "B.Cu" "B.Mask" "B.Paste")
			(roundrect_rratio 0.2)
			(net 512 "VRP")
			(pintype "passive")
		)
		(pad "2" smd roundrect
			(at 0.7 0)
			(size 0.6 0.8)
			(layers "B.Cu" "B.Mask" "B.Paste")
			(roundrect_rratio 0.2)
			(net 5 "GND")
			(pintype "passive")
		)
	)
	(footprint "antmicro-footprints:C_0402_1005Metric"
		(layer "B.Cu")
		(at 197.486328 100.020008 -90)
		(descr "Capacitor SMD 0402")
		(tags "capacitor SMD 0402")
		(property "Reference" "C101"
			(at -1.820008 -6.613672 90)
			(layer "B.SilkS")
			(effects
				(font
					(size 0.7 0.7)
					(thickness 0.15)
				)
				(justify left bottom mirror)
			)
		)
		(property "Value" "C_4u7_0402"
			(at 0 -1.4 90)
			(layer "B.Fab")
			(effects
				(font
					(size 0.7 0.7)
					(thickness 0.15)
				)
				(justify left bottom mirror)
			)
		)
		(property "Description" " "
			(at 0 0 270)
			(layer "F.Fab")
			(hide yes)
			(effects
				(font
					(size 1.27 1.27)
					(thickness 0.15)
				)
			)
		)
		(property "Author" "Antmicro"
			(at 97.46632 297.506336 0)
			(layer "B.Fab")
			(hide yes)
			(effects
				(font
					(size 1 1)
					(thickness 0.15)
				)
				(justify mirror)
			)
		)
		(property "Dielectric" ""
			(at 97.46632 297.506336 0)
			(layer "B.Fab")
			(hide yes)
			(effects
				(font
					(size 1 1)
					(thickness 0.15)
				)
				(justify mirror)
			)
		)
		(property "License" "Apache-2.0"
			(at 97.46632 297.506336 0)
			(layer "B.Fab")
			(hide yes)
			(effects
				(font
					(size 1 1)
					(thickness 0.15)
				)
				(justify mirror)
			)
		)
		(property "MPN" "GRM155R61A475MEAAD"
			(at 97.46632 297.506336 0)
			(layer "B.Fab")
			(hide yes)
			(effects
				(font
					(size 1 1)
					(thickness 0.15)
				)
				(justify mirror)
			)
		)
		(property "Manufacturer" "Murata"
			(at 97.46632 297.506336 0)
			(layer "B.Fab")
			(hide yes)
			(effects
				(font
					(size 1 1)
					(thickness 0.15)
				)
				(justify mirror)
			)
		)
		(property "Val" "4u7"
			(at 97.46632 297.506336 0)
			(layer "B.Fab")
			(hide yes)
			(effects
				(font
					(size 1 1)
					(thickness 0.15)
				)
				(justify mirror)
			)
		)
		(property "Voltage" ""
			(at 97.46632 297.506336 0)
			(layer "B.Fab")
			(hide yes)
			(effects
				(font
					(size 1 1)
					(thickness 0.15)
				)
				(justify mirror)
			)
		)
		(sheetname "Ethernet")
		(sheetfile "ethernet.kicad_sch")
		(attr smd)
		(fp_rect
			(start -0.94 0.47)
			(end 0.94 -0.47)
			(stroke
				(width 0.05)
				(type solid)
			)
			(fill no)
			(layer "B.CrtYd")
		)
		(fp_rect
			(start -0.499 0.249)
			(end 0.499 -0.249)
			(stroke
				(width 0.15)
				(type solid)
			)
			(fill no)
			(layer "B.Fab")
		)
		(pad "1" smd roundrect
			(at -0.484 0 270)
			(size 0.59 0.64)
			(layers "B.Cu" "B.Mask" "B.Paste")
			(roundrect_rratio 0.25)
			(net 459 "3V3_SYS")
			(pintype "passive")
		)
		(pad "2" smd roundrect
			(at 0.484 0 270)
			(size 0.59 0.64)
			(layers "B.Cu" "B.Mask" "B.Paste")
			(roundrect_rratio 0.25)
			(net 5 "GND")
			(pintype "passive")
		)
	)
	(footprint "antmicro-footprints:R_0402_1005Metric"
		(layer "B.Cu")
		(at 208.786328 103.520008)
		(descr "Resistor SMD 0402")
		(tags "resistor SMD 0402")
		(property "Reference" "R82"
			(at 3.013672 0.379992 180)
			(layer "B.SilkS")
			(effects
				(font
					(size 0.7 0.7)
					(thickness 0.15)
				)
				(justify left bottom mirror)
			)
		)
		(property "Value" "R_10k2_0402"
			(at 0 -1.4 180)
			(layer "B.Fab")
			(effects
				(font
					(size 0.7 0.7)
					(thickness 0.15)
				)
				(justify left bottom mirror)
			)
		)
		(property "Description" "10k2 resistor in 0402 package with 1% tolerance"
			(at 0 0 0)
			(layer "F.Fab")
			(hide yes)
			(effects
				(font
					(size 1.27 1.27)
					(thickness 0.15)
				)
			)
		)
		(property "Author" "Antmicro"
			(at 0 0 0)
			(layer "B.Fab")
			(hide yes)
			(effects
				(font
					(size 1 1)
					(thickness 0.15)
				)
				(justify mirror)
			)
		)
		(property "License" "Apache-2.0"
			(at 0 0 0)
			(layer "B.Fab")
			(hide yes)
			(effects
				(font
					(size 1 1)
					(thickness 0.15)
				)
				(justify mirror)
			)
		)
		(property "MPN" "CR0402-FX-1022GLF"
			(at 0 0 0)
			(layer "B.Fab")
			(hide yes)
			(effects
				(font
					(size 1 1)
					(thickness 0.15)
				)
				(justify mirror)
			)
		)
		(property "Manufacturer" "Bourns"
			(at 0 0 0)
			(layer "B.Fab")
			(hide yes)
			(effects
				(font
					(size 1 1)
					(thickness 0.15)
				)
				(justify mirror)
			)
		)
		(property "Tolerance" "1%"
			(at 0 0 0)
			(layer "B.Fab")
			(hide yes)
			(effects
				(font
					(size 1 1)
					(thickness 0.15)
				)
				(justify mirror)
			)
		)
		(property "Val" "10k2"
			(at 0 0 0)
			(layer "B.Fab")
			(hide yes)
			(effects
				(font
					(size 1 1)
					(thickness 0.15)
				)
				(justify mirror)
			)
		)
		(sheetname "Ethernet")
		(sheetfile "ethernet.kicad_sch")
		(attr smd)
		(fp_rect
			(start -0.93 0.47)
			(end 0.93 -0.47)
			(stroke
				(width 0.05)
				(type solid)
			)
			(fill no)
			(layer "B.CrtYd")
		)
		(fp_rect
			(start -0.5 0.25)
			(end 0.5 -0.25)
			(stroke
				(width 0.15)
				(type solid)
			)
			(fill no)
			(layer "B.Fab")
		)
		(pad "1" smd roundrect
			(at -0.485 0)
			(size 0.59 0.64)
			(layers "B.Cu" "B.Mask" "B.Paste")
			(roundrect_rratio 0.25)
			(net 12 "LED_LINK")
			(pintype "passive")
		)
		(pad "2" smd roundrect
			(at 0.485 0)
			(size 0.59 0.64)
			(layers "B.Cu" "B.Mask" "B.Paste")
			(roundrect_rratio 0.25)
			(net 459 "3V3_SYS")
			(pintype "passive")
		)
	)
	(footprint "antmicro-footprints:FB_0603_1608Metric"
		(layer "B.Cu")
		(at 200.486328 106.53 -90)
		(property "Reference" "FB6"
			(at -1.03 -1.613672 90)
			(layer "B.SilkS")
			(effects
				(font
					(size 0.7 0.7)
					(thickness 0.15)
				)
				(justify left bottom mirror)
			)
		)
		(property "Value" "FB_120Z_2A_0603"
			(at 0 -1.5 90)
			(layer "B.Fab")
			(effects
				(font
					(size 0.7 0.7)
					(thickness 0.15)
				)
				(justify left bottom mirror)
			)
		)
		(property "Description" "Ferrite Beads WE-TMSB Suppression 240Ohm 200mA "
			(at 0 0 270)
			(layer "F.Fab")
			(hide yes)
			(effects
				(font
					(size 1.27 1.27)
					(thickness 0.15)
				)
			)
		)
		(property "Author" "Antmicro"
			(at 93.956328 307.016328 0)
			(layer "B.Fab")
			(hide yes)
			(effects
				(font
					(size 1 1)
					(thickness 0.15)
				)
				(justify mirror)
			)
		)
		(property "License" "Apache-2.0"
			(at 93.956328 307.016328 0)
			(layer "B.Fab")
			(hide yes)
			(effects
				(font
					(size 1 1)
					(thickness 0.15)
				)
				(justify mirror)
			)
		)
		(property "MPN" "BLM18PG121SN1D"
			(at 93.956328 307.016328 0)
			(layer "B.Fab")
			(hide yes)
			(effects
				(font
					(size 1 1)
					(thickness 0.15)
				)
				(justify mirror)
			)
		)
		(property "Manufacturer" "Murata"
			(at 93.956328 307.016328 0)
			(layer "B.Fab")
			(hide yes)
			(effects
				(font
					(size 1 1)
					(thickness 0.15)
				)
				(justify mirror)
			)
		)
		(sheetname "Ethernet")
		(sheetfile "ethernet.kicad_sch")
		(attr smd)
		(fp_line
			(start -0.196 0.408)
			(end 0.193 0.408)
			(stroke
				(width 0.15)
				(type solid)
			)
			(layer "B.SilkS")
		)
		(fp_line
			(start -0.196 -0.406)
			(end 0.193 -0.406)
			(stroke
				(width 0.15)
				(type solid)
			)
			(layer "B.SilkS")
		)
		(fp_rect
			(start -1.3 0.6)
			(end 1.3 -0.6)
			(stroke
				(width 0.05)
				(type solid)
			)
			(fill no)
			(layer "B.CrtYd")
		)
		(fp_line
			(start 0.8 0.408)
			(end -0.803 0.408)
			(stroke
				(width 0.15)
				(type solid)
			)
			(layer "B.Fab")
		)
		(fp_line
			(start 0.8 0.408)
			(end 0.8 -0.406)
			(stroke
				(width 0.15)
				(type solid)
			)
			(layer "B.Fab")
		)
		(fp_line
			(start -0.803 -0.406)
			(end -0.803 0.408)
			(stroke
				(width 0.15)
				(type solid)
			)
			(layer "B.Fab")
		)
		(fp_line
			(start 0.8 -0.406)
			(end -0.803 -0.406)
			(stroke
				(width 0.15)
				(type solid)
			)
			(layer "B.Fab")
		)
		(pad "1" smd roundrect
			(at -0.891 0 270)
			(size 0.762 1.09)
			(layers "B.Cu" "B.Mask" "B.Paste")
			(roundrect_rratio 0.15)
			(net 602 "1V2_SYS")
			(pintype "passive")
		)
		(pad "2" smd roundrect
			(at 0.888 0 270)
			(size 0.762 1.09)
			(layers "B.Cu" "B.Mask" "B.Paste")
			(roundrect_rratio 0.15)
			(net 529 "/Ethernet/AVDDL")
			(pintype "passive")
		)
	)
	(footprint "antmicro-footprints:C_0402_1005Metric"
		(layer "B.Cu")
		(at 201.086328 108.774306 -90)
		(descr "Capacitor SMD 0402")
		(tags "capacitor SMD 0402")
		(property "Reference" "C112"
			(at 0.810694 -0.413672 90)
			(layer "B.SilkS")
			(effects
				(font
					(size 0.7 0.7)
					(thickness 0.15)
				)
				(justify left bottom mirror)
			)
		)
		(property "Value" "C_10n_0402"
			(at 0 -1.4 90)
			(layer "B.Fab")
			(effects
				(font
					(size 0.7 0.7)
					(thickness 0.15)
				)
				(justify left bottom mirror)
			)
		)
		(property "Description" " "
			(at 0 0 270)
			(layer "F.Fab")
			(hide yes)
			(effects
				(font
					(size 1.27 1.27)
					(thickness 0.15)
				)
			)
		)
		(property "Author" "Antmicro"
			(at 92.312022 309.860634 0)
			(layer "B.Fab")
			(hide yes)
			(effects
				(font
					(size 1 1)
					(thickness 0.15)
				)
				(justify mirror)
			)
		)
		(property "Dielectric" "X7R"
			(at 92.312022 309.860634 0)
			(layer "B.Fab")
			(hide yes)
			(effects
				(font
					(size 1 1)
					(thickness 0.15)
				)
				(justify mirror)
			)
		)
		(property "License" "Apache-2.0"
			(at 92.312022 309.860634 0)
			(layer "B.Fab")
			(hide yes)
			(effects
				(font
					(size 1 1)
					(thickness 0.15)
				)
				(justify mirror)
			)
		)
		(property "MPN" "GRM155R71H103KA88D"
			(at 92.312022 309.860634 0)
			(layer "B.Fab")
			(hide yes)
			(effects
				(font
					(size 1 1)
					(thickness 0.15)
				)
				(justify mirror)
			)
		)
		(property "Manufacturer" "Murata"
			(at 92.312022 309.860634 0)
			(layer "B.Fab")
			(hide yes)
			(effects
				(font
					(size 1 1)
					(thickness 0.15)
				)
				(justify mirror)
			)
		)
		(property "Val" "10n"
			(at 92.312022 309.860634 0)
			(layer "B.Fab")
			(hide yes)
			(effects
				(font
					(size 1 1)
					(thickness 0.15)
				)
				(justify mirror)
			)
		)
		(property "Voltage" "50V"
			(at 92.312022 309.860634 0)
			(layer "B.Fab")
			(hide yes)
			(effects
				(font
					(size 1 1)
					(thickness 0.15)
				)
				(justify mirror)
			)
		)
		(sheetname "Ethernet")
		(sheetfile "ethernet.kicad_sch")
		(attr smd)
		(fp_rect
			(start -0.94 0.47)
			(end 0.94 -0.47)
			(stroke
				(width 0.05)
				(type solid)
			)
			(fill no)
			(layer "B.CrtYd")
		)
		(fp_rect
			(start -0.499 0.249)
			(end 0.499 -0.249)
			(stroke
				(width 0.15)
				(type solid)
			)
			(fill no)
			(layer "B.Fab")
		)
		(pad "1" smd roundrect
			(at -0.484 0 270)
			(size 0.59 0.64)
			(layers "B.Cu" "B.Mask" "B.Paste")
			(roundrect_rratio 0.25)
			(net 529 "/Ethernet/AVDDL")
			(pintype "passive")
		)
		(pad "2" smd roundrect
			(at 0.484 0 270)
			(size 0.59 0.64)
			(layers "B.Cu" "B.Mask" "B.Paste")
			(roundrect_rratio 0.25)
			(net 5 "GND")
			(pintype "passive")
		)
	)
	(footprint "antmicro-footprints:C_0402_1005Metric"
		(layer "B.Cu")
		(at 201.586328 100.020008 -90)
		(descr "Capacitor SMD 0402")
		(tags "capacitor SMD 0402")
		(property "Reference" "C104"
			(at -1.820008 -6.613672 90)
			(layer "B.SilkS")
			(effects
				(font
					(size 0.7 0.7)
					(thickness 0.15)
				)
				(justify left bottom mirror)
			)
		)
		(property "Value" "C_470n_0402"
			(at 0 -1.4 90)
			(layer "B.Fab")
			(effects
				(font
					(size 0.7 0.7)
					(thickness 0.15)
				)
				(justify left bottom mirror)
			)
		)
		(property "Description" " "
			(at 0 0 270)
			(layer "F.Fab")
			(hide yes)
			(effects
				(font
					(size 1.27 1.27)
					(thickness 0.15)
				)
			)
		)
		(property "Author" "Antmicro"
			(at 101.56632 301.606336 0)
			(layer "B.Fab")
			(hide yes)
			(effects
				(font
					(size 1 1)
					(thickness 0.15)
				)
				(justify mirror)
			)
		)
		(property "Dielectric" ""
			(at 101.56632 301.606336 0)
			(layer "B.Fab")
			(hide yes)
			(effects
				(font
					(size 1 1)
					(thickness 0.15)
				)
				(justify mirror)
			)
		)
		(property "License" "Apache-2.0"
			(at 101.56632 301.606336 0)
			(layer "B.Fab")
			(hide yes)
			(effects
				(font
					(size 1 1)
					(thickness 0.15)
				)
				(justify mirror)
			)
		)
		(property "MPN" "C1005X5R1E474M050BB"
			(at 101.56632 301.606336 0)
			(layer "B.Fab")
			(hide yes)
			(effects
				(font
					(size 1 1)
					(thickness 0.15)
				)
				(justify mirror)
			)
		)
		(property "Manufacturer" "TDK"
			(at 101.56632 301.606336 0)
			(layer "B.Fab")
			(hide yes)
			(effects
				(font
					(size 1 1)
					(thickness 0.15)
				)
				(justify mirror)
			)
		)
		(property "Val" "470n"
			(at 101.56632 301.606336 0)
			(layer "B.Fab")
			(hide yes)
			(effects
				(font
					(size 1 1)
					(thickness 0.15)
				)
				(justify mirror)
			)
		)
		(property "Voltage" ""
			(at 101.56632 301.606336 0)
			(layer "B.Fab")
			(hide yes)
			(effects
				(font
					(size 1 1)
					(thickness 0.15)
				)
				(justify mirror)
			)
		)
		(sheetname "Ethernet")
		(sheetfile "ethernet.kicad_sch")
		(attr smd)
		(fp_rect
			(start -0.94 0.47)
			(end 0.94 -0.47)
			(stroke
				(width 0.05)
				(type solid)
			)
			(fill no)
			(layer "B.CrtYd")
		)
		(fp_rect
			(start -0.499 0.249)
			(end 0.499 -0.249)
			(stroke
				(width 0.15)
				(type solid)
			)
			(fill no)
			(layer "B.Fab")
		)
		(pad "1" smd roundrect
			(at -0.484 0 270)
			(size 0.59 0.64)
			(layers "B.Cu" "B.Mask" "B.Paste")
			(roundrect_rratio 0.25)
			(net 602 "1V2_SYS")
			(pintype "passive")
		)
		(pad "2" smd roundrect
			(at 0.484 0 270)
			(size 0.59 0.64)
			(layers "B.Cu" "B.Mask" "B.Paste")
			(roundrect_rratio 0.25)
			(net 5 "GND")
			(pintype "passive")
		)
	)
	(footprint "antmicro-footprints:R_0402_1005Metric"
		(layer "B.Cu")
		(at 198.786328 95.120008 90)
		(descr "Resistor SMD 0402")
		(tags "resistor SMD 0402")
		(property "Reference" "R74"
			(at 2.920008 0.413672 270)
			(layer "B.SilkS")
			(effects
				(font
					(size 0.7 0.7)
					(thickness 0.15)
				)
				(justify left bottom mirror)
			)
		)
		(property "Value" "R_10k2_0402"
			(at 0 -1.4 270)
			(layer "B.Fab")
			(effects
				(font
					(size 0.7 0.7)
					(thickness 0.15)
				)
				(justify left bottom mirror)
			)
		)
		(property "Description" "10k2 resistor in 0402 package with 1% tolerance"
			(at 0 0 90)
			(layer "F.Fab")
			(hide yes)
			(effects
				(font
					(size 1.27 1.27)
					(thickness 0.15)
				)
			)
		)
		(property "Author" "Antmicro"
			(at 293.906336 -103.66632 0)
			(layer "B.Fab")
			(hide yes)
			(effects
				(font
					(size 1 1)
					(thickness 0.15)
				)
				(justify mirror)
			)
		)
		(property "License" "Apache-2.0"
			(at 293.906336 -103.66632 0)
			(layer "B.Fab")
			(hide yes)
			(effects
				(font
					(size 1 1)
					(thickness 0.15)
				)
				(justify mirror)
			)
		)
		(property "MPN" "CR0402-FX-1022GLF"
			(at 293.906336 -103.66632 0)
			(layer "B.Fab")
			(hide yes)
			(effects
				(font
					(size 1 1)
					(thickness 0.15)
				)
				(justify mirror)
			)
		)
		(property "Manufacturer" "Bourns"
			(at 293.906336 -103.66632 0)
			(layer "B.Fab")
			(hide yes)
			(effects
				(font
					(size 1 1)
					(thickness 0.15)
				)
				(justify mirror)
			)
		)
		(property "Tolerance" "1%"
			(at 293.906336 -103.66632 0)
			(layer "B.Fab")
			(hide yes)
			(effects
				(font
					(size 1 1)
					(thickness 0.15)
				)
				(justify mirror)
			)
		)
		(property "Val" "10k2"
			(at 293.906336 -103.66632 0)
			(layer "B.Fab")
			(hide yes)
			(effects
				(font
					(size 1 1)
					(thickness 0.15)
				)
				(justify mirror)
			)
		)
		(sheetname "Ethernet")
		(sheetfile "ethernet.kicad_sch")
		(attr exclude_from_pos_files exclude_from_bom dnp)
		(fp_rect
			(start -0.93 0.47)
			(end 0.93 -0.47)
			(stroke
				(width 0.05)
				(type solid)
			)
			(fill no)
			(layer "B.CrtYd")
		)
		(fp_rect
			(start -0.5 0.25)
			(end 0.5 -0.25)
			(stroke
				(width 0.15)
				(type solid)
			)
			(fill no)
			(layer "B.Fab")
		)
		(pad "1" smd roundrect
			(at -0.485 0 90)
			(size 0.59 0.64)
			(layers "B.Cu" "B.Mask" "B.Paste")
			(roundrect_rratio 0.25)
			(net 22 "ETH_RXD0")
			(pintype "passive")
		)
		(pad "2" smd roundrect
			(at 0.485 0 90)
			(size 0.59 0.64)
			(layers "B.Cu" "B.Mask" "B.Paste")
			(roundrect_rratio 0.25)
			(net 459 "3V3_SYS")
			(pintype "passive")
		)
	)
	(footprint "antmicro-footprints:R_0402_1005Metric"
		(layer "B.Cu")
		(at 140.536328 92.370008 -90)
		(descr "Resistor SMD 0402")
		(tags "resistor SMD 0402")
		(property "Reference" "R107"
			(at 0.829992 -0.363672 90)
			(layer "B.SilkS")
			(effects
				(font
					(size 0.7 0.7)
					(thickness 0.15)
				)
				(justify left bottom mirror)
			)
		)
		(property "Value" "R_10k_0402"
			(at 0 -1.4 90)
			(layer "B.Fab")
			(effects
				(font
					(size 0.7 0.7)
					(thickness 0.15)
				)
				(justify left bottom mirror)
			)
		)
		(property "Description" "10k resistor in 0402 package with 1% tolerance"
			(at 0 0 270)
			(layer "F.Fab")
			(hide yes)
			(effects
				(font
					(size 1.27 1.27)
					(thickness 0.15)
				)
			)
		)
		(property "Author" "Antmicro"
			(at 48.16632 232.906336 0)
			(layer "B.Fab")
			(hide yes)
			(effects
				(font
					(size 1 1)
					(thickness 0.15)
				)
				(justify mirror)
			)
		)
		(property "License" "Apache-2.0"
			(at 48.16632 232.906336 0)
			(layer "B.Fab")
			(hide yes)
			(effects
				(font
					(size 1 1)
					(thickness 0.15)
				)
				(justify mirror)
			)
		)
		(property "MPN" "CR0402-FX-1002GLF"
			(at 48.16632 232.906336 0)
			(layer "B.Fab")
			(hide yes)
			(effects
				(font
					(size 1 1)
					(thickness 0.15)
				)
				(justify mirror)
			)
		)
		(property "Manufacturer" "Bourns"
			(at 48.16632 232.906336 0)
			(layer "B.Fab")
			(hide yes)
			(effects
				(font
					(size 1 1)
					(thickness 0.15)
				)
				(justify mirror)
			)
		)
		(property "Tolerance" "1%"
			(at 48.16632 232.906336 0)
			(layer "B.Fab")
			(hide yes)
			(effects
				(font
					(size 1 1)
					(thickness 0.15)
				)
				(justify mirror)
			)
		)
		(property "Val" "10k"
			(at 48.16632 232.906336 0)
			(layer "B.Fab")
			(hide yes)
			(effects
				(font
					(size 1 1)
					(thickness 0.15)
				)
				(justify mirror)
			)
		)
		(sheetname "Supply")
		(sheetfile "supply.kicad_sch")
		(attr smd)
		(fp_rect
			(start -0.93 0.47)
			(end 0.93 -0.47)
			(stroke
				(width 0.05)
				(type solid)
			)
			(fill no)
			(layer "B.CrtYd")
		)
		(fp_rect
			(start -0.5 0.25)
			(end 0.5 -0.25)
			(stroke
				(width 0.15)
				(type solid)
			)
			(fill no)
			(layer "B.Fab")
		)
		(pad "1" smd roundrect
			(at -0.485 0 270)
			(size 0.59 0.64)
			(layers "B.Cu" "B.Mask" "B.Paste")
			(roundrect_rratio 0.25)
			(net 463 "VCC5V0_INT")
			(pintype "passive")
		)
		(pad "2" smd roundrect
			(at 0.485 0 270)
			(size 0.59 0.64)
			(layers "B.Cu" "B.Mask" "B.Paste")
			(roundrect_rratio 0.25)
			(net 468 "/Supply/VCC_INT_EN")
			(pintype "passive")
		)
	)
	(footprint "antmicro-footprints:R_0402_1005Metric"
		(layer "B.Cu")
		(at 141.536328 92.370008 -90)
		(descr "Resistor SMD 0402")
		(tags "resistor SMD 0402")
		(property "Reference" "R108"
			(at 0.829992 -0.363672 90)
			(layer "B.SilkS")
			(effects
				(font
					(size 0.7 0.7)
					(thickness 0.15)
				)
				(justify left bottom mirror)
			)
		)
		(property "Value" "R_10k_0402"
			(at 0 -1.4 90)
			(layer "B.Fab")
			(effects
				(font
					(size 0.7 0.7)
					(thickness 0.15)
				)
				(justify left bottom mirror)
			)
		)
		(property "Description" "10k resistor in 0402 package with 1% tolerance"
			(at 0 0 270)
			(layer "F.Fab")
			(hide yes)
			(effects
				(font
					(size 1.27 1.27)
					(thickness 0.15)
				)
			)
		)
		(property "Author" "Antmicro"
			(at 49.16632 233.906336 0)
			(layer "B.Fab")
			(hide yes)
			(effects
				(font
					(size 1 1)
					(thickness 0.15)
				)
				(justify mirror)
			)
		)
		(property "License" "Apache-2.0"
			(at 49.16632 233.906336 0)
			(layer "B.Fab")
			(hide yes)
			(effects
				(font
					(size 1 1)
					(thickness 0.15)
				)
				(justify mirror)
			)
		)
		(property "MPN" "CR0402-FX-1002GLF"
			(at 49.16632 233.906336 0)
			(layer "B.Fab")
			(hide yes)
			(effects
				(font
					(size 1 1)
					(thickness 0.15)
				)
				(justify mirror)
			)
		)
		(property "Manufacturer" "Bourns"
			(at 49.16632 233.906336 0)
			(layer "B.Fab")
			(hide yes)
			(effects
				(font
					(size 1 1)
					(thickness 0.15)
				)
				(justify mirror)
			)
		)
		(property "Tolerance" "1%"
			(at 49.16632 233.906336 0)
			(layer "B.Fab")
			(hide yes)
			(effects
				(font
					(size 1 1)
					(thickness 0.15)
				)
				(justify mirror)
			)
		)
		(property "Val" "10k"
			(at 49.16632 233.906336 0)
			(layer "B.Fab")
			(hide yes)
			(effects
				(font
					(size 1 1)
					(thickness 0.15)
				)
				(justify mirror)
			)
		)
		(sheetname "Supply")
		(sheetfile "supply.kicad_sch")
		(attr smd)
		(fp_rect
			(start -0.93 0.47)
			(end 0.93 -0.47)
			(stroke
				(width 0.05)
				(type solid)
			)
			(fill no)
			(layer "B.CrtYd")
		)
		(fp_rect
			(start -0.5 0.25)
			(end 0.5 -0.25)
			(stroke
				(width 0.15)
				(type solid)
			)
			(fill no)
			(layer "B.Fab")
		)
		(pad "1" smd roundrect
			(at -0.485 0 270)
			(size 0.59 0.64)
			(layers "B.Cu" "B.Mask" "B.Paste")
			(roundrect_rratio 0.25)
			(net 463 "VCC5V0_INT")
			(pintype "passive")
		)
		(pad "2" smd roundrect
			(at 0.485 0 270)
			(size 0.59 0.64)
			(layers "B.Cu" "B.Mask" "B.Paste")
			(roundrect_rratio 0.25)
			(net 469 "/Supply/VCC_AUX_EN")
			(pintype "passive")
		)
	)
	(footprint "antmicro-footprints:R_0402_1005Metric"
		(layer "B.Cu")
		(at 142.536328 92.370008 -90)
		(descr "Resistor SMD 0402")
		(tags "resistor SMD 0402")
		(property "Reference" "R109"
			(at 0.829992 -0.363672 90)
			(layer "B.SilkS")
			(effects
				(font
					(size 0.7 0.7)
					(thickness 0.15)
				)
				(justify left bottom mirror)
			)
		)
		(property "Value" "R_10k_0402"
			(at 0 -1.4 90)
			(layer "B.Fab")
			(effects
				(font
					(size 0.7 0.7)
					(thickness 0.15)
				)
				(justify left bottom mirror)
			)
		)
		(property "Description" "10k resistor in 0402 package with 1% tolerance"
			(at 0 0 270)
			(layer "F.Fab")
			(hide yes)
			(effects
				(font
					(size 1.27 1.27)
					(thickness 0.15)
				)
			)
		)
		(property "Author" "Antmicro"
			(at 50.16632 234.906336 0)
			(layer "B.Fab")
			(hide yes)
			(effects
				(font
					(size 1 1)
					(thickness 0.15)
				)
				(justify mirror)
			)
		)
		(property "License" "Apache-2.0"
			(at 50.16632 234.906336 0)
			(layer "B.Fab")
			(hide yes)
			(effects
				(font
					(size 1 1)
					(thickness 0.15)
				)
				(justify mirror)
			)
		)
		(property "MPN" "CR0402-FX-1002GLF"
			(at 50.16632 234.906336 0)
			(layer "B.Fab")
			(hide yes)
			(effects
				(font
					(size 1 1)
					(thickness 0.15)
				)
				(justify mirror)
			)
		)
		(property "Manufacturer" "Bourns"
			(at 50.16632 234.906336 0)
			(layer "B.Fab")
			(hide yes)
			(effects
				(font
					(size 1 1)
					(thickness 0.15)
				)
				(justify mirror)
			)
		)
		(property "Tolerance" "1%"
			(at 50.16632 234.906336 0)
			(layer "B.Fab")
			(hide yes)
			(effects
				(font
					(size 1 1)
					(thickness 0.15)
				)
				(justify mirror)
			)
		)
		(property "Val" "10k"
			(at 50.16632 234.906336 0)
			(layer "B.Fab")
			(hide yes)
			(effects
				(font
					(size 1 1)
					(thickness 0.15)
				)
				(justify mirror)
			)
		)
		(sheetname "Supply")
		(sheetfile "supply.kicad_sch")
		(attr smd)
		(fp_rect
			(start -0.93 0.47)
			(end 0.93 -0.47)
			(stroke
				(width 0.05)
				(type solid)
			)
			(fill no)
			(layer "B.CrtYd")
		)
		(fp_rect
			(start -0.5 0.25)
			(end 0.5 -0.25)
			(stroke
				(width 0.15)
				(type solid)
			)
			(fill no)
			(layer "B.Fab")
		)
		(pad "1" smd roundrect
			(at -0.485 0 270)
			(size 0.59 0.64)
			(layers "B.Cu" "B.Mask" "B.Paste")
			(roundrect_rratio 0.25)
			(net 463 "VCC5V0_INT")
			(pintype "passive")
		)
		(pad "2" smd roundrect
			(at 0.485 0 270)
			(size 0.59 0.64)
			(layers "B.Cu" "B.Mask" "B.Paste")
			(roundrect_rratio 0.25)
			(net 470 "/Supply/VCC_IO_EN")
			(pintype "passive")
		)
	)
	(footprint "antmicro-footprints:R_0402_1005Metric"
		(layer "B.Cu")
		(at 196.686328 96.760008 -90)
		(descr "Resistor SMD 0402")
		(tags "resistor SMD 0402")
		(property "Reference" "R86"
			(at 0.739992 2.486328 270)
			(layer "B.SilkS")
			(effects
				(font
					(size 0.7 0.7)
					(thickness 0.15)
				)
				(justify left bottom mirror)
			)
		)
		(property "Value" "R_2k2_0402"
			(at 0 -1.4 90)
			(layer "B.Fab")
			(effects
				(font
					(size 0.7 0.7)
					(thickness 0.15)
				)
				(justify left bottom mirror)
			)
		)
		(property "Description" "2k2 resistor in 0402 package with 1% tolerance"
			(at 0 0 270)
			(layer "F.Fab")
			(hide yes)
			(effects
				(font
					(size 1.27 1.27)
					(thickness 0.15)
				)
			)
		)
		(property "Author" "Antmicro"
			(at 99.92632 293.446336 0)
			(layer "B.Fab")
			(hide yes)
			(effects
				(font
					(size 1 1)
					(thickness 0.15)
				)
				(justify mirror)
			)
		)
		(property "License" "Apache-2.0"
			(at 99.92632 293.446336 0)
			(layer "B.Fab")
			(hide yes)
			(effects
				(font
					(size 1 1)
					(thickness 0.15)
				)
				(justify mirror)
			)
		)
		(property "MPN" "CR0402-FX-2201GLF"
			(at 99.92632 293.446336 0)
			(layer "B.Fab")
			(hide yes)
			(effects
				(font
					(size 1 1)
					(thickness 0.15)
				)
				(justify mirror)
			)
		)
		(property "Manufacturer" "Bourns"
			(at 99.92632 293.446336 0)
			(layer "B.Fab")
			(hide yes)
			(effects
				(font
					(size 1 1)
					(thickness 0.15)
				)
				(justify mirror)
			)
		)
		(property "Tolerance" "1%"
			(at 99.92632 293.446336 0)
			(layer "B.Fab")
			(hide yes)
			(effects
				(font
					(size 1 1)
					(thickness 0.15)
				)
				(justify mirror)
			)
		)
		(property "Val" "2k2"
			(at 99.92632 293.446336 0)
			(layer "B.Fab")
			(hide yes)
			(effects
				(font
					(size 1 1)
					(thickness 0.15)
				)
				(justify mirror)
			)
		)
		(sheetname "Ethernet")
		(sheetfile "ethernet.kicad_sch")
		(attr smd)
		(fp_rect
			(start -0.93 0.47)
			(end 0.93 -0.47)
			(stroke
				(width 0.05)
				(type solid)
			)
			(fill no)
			(layer "B.CrtYd")
		)
		(fp_rect
			(start -0.5 0.25)
			(end 0.5 -0.25)
			(stroke
				(width 0.15)
				(type solid)
			)
			(fill no)
			(layer "B.Fab")
		)
		(pad "1" smd roundrect
			(at -0.485 0 270)
			(size 0.59 0.64)
			(layers "B.Cu" "B.Mask" "B.Paste")
			(roundrect_rratio 0.25)
			(net 23 "ETH_RXD1")
			(pintype "passive")
		)
		(pad "2" smd roundrect
			(at 0.485 0 270)
			(size 0.59 0.64)
			(layers "B.Cu" "B.Mask" "B.Paste")
			(roundrect_rratio 0.25)
			(net 5 "GND")
			(pintype "passive")
		)
	)
	(footprint "antmicro-footprints:R_0402_1005Metric"
		(layer "B.Cu")
		(at 197.686328 96.280008 -90)
		(descr "Resistor SMD 0402")
		(tags "resistor SMD 0402")
		(property "Reference" "R87"
			(at 0.719992 -0.513672 90)
			(layer "B.SilkS")
			(effects
				(font
					(size 0.7 0.7)
					(thickness 0.15)
				)
				(justify left bottom mirror)
			)
		)
		(property "Value" "R_2k2_0402"
			(at 0 -1.4 90)
			(layer "B.Fab")
			(effects
				(font
					(size 0.7 0.7)
					(thickness 0.15)
				)
				(justify left bottom mirror)
			)
		)
		(property "Description" "2k2 resistor in 0402 package with 1% tolerance"
			(at 0 0 270)
			(layer "F.Fab")
			(hide yes)
			(effects
				(font
					(size 1.27 1.27)
					(thickness 0.15)
				)
			)
		)
		(property "Author" "Antmicro"
			(at 101.40632 293.966336 0)
			(layer "B.Fab")
			(hide yes)
			(effects
				(font
					(size 1 1)
					(thickness 0.15)
				)
				(justify mirror)
			)
		)
		(property "License" "Apache-2.0"
			(at 101.40632 293.966336 0)
			(layer "B.Fab")
			(hide yes)
			(effects
				(font
					(size 1 1)
					(thickness 0.15)
				)
				(justify mirror)
			)
		)
		(property "MPN" "CR0402-FX-2201GLF"
			(at 101.40632 293.966336 0)
			(layer "B.Fab")
			(hide yes)
			(effects
				(font
					(size 1 1)
					(thickness 0.15)
				)
				(justify mirror)
			)
		)
		(property "Manufacturer" "Bourns"
			(at 101.40632 293.966336 0)
			(layer "B.Fab")
			(hide yes)
			(effects
				(font
					(size 1 1)
					(thickness 0.15)
				)
				(justify mirror)
			)
		)
		(property "Tolerance" "1%"
			(at 101.40632 293.966336 0)
			(layer "B.Fab")
			(hide yes)
			(effects
				(font
					(size 1 1)
					(thickness 0.15)
				)
				(justify mirror)
			)
		)
		(property "Val" "2k2"
			(at 101.40632 293.966336 0)
			(layer "B.Fab")
			(hide yes)
			(effects
				(font
					(size 1 1)
					(thickness 0.15)
				)
				(justify mirror)
			)
		)
		(sheetname "Ethernet")
		(sheetfile "ethernet.kicad_sch")
		(attr exclude_from_pos_files exclude_from_bom dnp)
		(fp_rect
			(start -0.93 0.47)
			(end 0.93 -0.47)
			(stroke
				(width 0.05)
				(type solid)
			)
			(fill no)
			(layer "B.CrtYd")
		)
		(fp_rect
			(start -0.5 0.25)
			(end 0.5 -0.25)
			(stroke
				(width 0.15)
				(type solid)
			)
			(fill no)
			(layer "B.Fab")
		)
		(pad "1" smd roundrect
			(at -0.485 0 270)
			(size 0.59 0.64)
			(layers "B.Cu" "B.Mask" "B.Paste")
			(roundrect_rratio 0.25)
			(net 37 "ETH_RXD2")
			(pintype "passive")
		)
		(pad "2" smd roundrect
			(at 0.485 0 270)
			(size 0.59 0.64)
			(layers "B.Cu" "B.Mask" "B.Paste")
			(roundrect_rratio 0.25)
			(net 5 "GND")
			(pintype "passive")
		)
	)
	(footprint "antmicro-footprints:R_0402_1005Metric"
		(layer "B.Cu")
		(at 199.836328 95.440008 -90)
		(descr "Resistor SMD 0402")
		(tags "resistor SMD 0402")
		(property "Reference" "R88"
			(at -1.140008 -1.263672 90)
			(layer "B.SilkS")
			(effects
				(font
					(size 0.7 0.7)
					(thickness 0.15)
				)
				(justify left bottom mirror)
			)
		)
		(property "Value" "R_2k2_0402"
			(at 0 -1.4 90)
			(layer "B.Fab")
			(effects
				(font
					(size 0.7 0.7)
					(thickness 0.15)
				)
				(justify left bottom mirror)
			)
		)
		(property "Description" "2k2 resistor in 0402 package with 1% tolerance"
			(at 0 0 270)
			(layer "F.Fab")
			(hide yes)
			(effects
				(font
					(size 1.27 1.27)
					(thickness 0.15)
				)
			)
		)
		(property "Author" "Antmicro"
			(at 104.39632 295.276336 0)
			(layer "B.Fab")
			(hide yes)
			(effects
				(font
					(size 1 1)
					(thickness 0.15)
				)
				(justify mirror)
			)
		)
		(property "License" "Apache-2.0"
			(at 104.39632 295.276336 0)
			(layer "B.Fab")
			(hide yes)
			(effects
				(font
					(size 1 1)
					(thickness 0.15)
				)
				(justify mirror)
			)
		)
		(property "MPN" "CR0402-FX-2201GLF"
			(at 104.39632 295.276336 0)
			(layer "B.Fab")
			(hide yes)
			(effects
				(font
					(size 1 1)
					(thickness 0.15)
				)
				(justify mirror)
			)
		)
		(property "Manufacturer" "Bourns"
			(at 104.39632 295.276336 0)
			(layer "B.Fab")
			(hide yes)
			(effects
				(font
					(size 1 1)
					(thickness 0.15)
				)
				(justify mirror)
			)
		)
		(property "Tolerance" "1%"
			(at 104.39632 295.276336 0)
			(layer "B.Fab")
			(hide yes)
			(effects
				(font
					(size 1 1)
					(thickness 0.15)
				)
				(justify mirror)
			)
		)
		(property "Val" "2k2"
			(at 104.39632 295.276336 0)
			(layer "B.Fab")
			(hide yes)
			(effects
				(font
					(size 1 1)
					(thickness 0.15)
				)
				(justify mirror)
			)
		)
		(sheetname "Ethernet")
		(sheetfile "ethernet.kicad_sch")
		(attr exclude_from_pos_files exclude_from_bom dnp)
		(fp_rect
			(start -0.93 0.47)
			(end 0.93 -0.47)
			(stroke
				(width 0.05)
				(type solid)
			)
			(fill no)
			(layer "B.CrtYd")
		)
		(fp_rect
			(start -0.5 0.25)
			(end 0.5 -0.25)
			(stroke
				(width 0.15)
				(type solid)
			)
			(fill no)
			(layer "B.Fab")
		)
		(pad "1" smd roundrect
			(at -0.485 0 270)
			(size 0.59 0.64)
			(layers "B.Cu" "B.Mask" "B.Paste")
			(roundrect_rratio 0.25)
			(net 33 "ETH_RXD3")
			(pintype "passive")
		)
		(pad "2" smd roundrect
			(at 0.485 0 270)
			(size 0.59 0.64)
			(layers "B.Cu" "B.Mask" "B.Paste")
			(roundrect_rratio 0.25)
			(net 5 "GND")
			(pintype "passive")
		)
	)
	(footprint "antmicro-footprints:R_0402_1005Metric"
		(layer "B.Cu")
		(at 208.306328 106.480008 -90)
		(descr "Resistor SMD 0402")
		(tags "resistor SMD 0402")
		(property "Reference" "R92"
			(at -0.980008 -1.293672 90)
			(layer "B.SilkS")
			(effects
				(font
					(size 0.7 0.7)
					(thickness 0.15)
				)
				(justify left bottom mirror)
			)
		)
		(property "Value" "R_2k2_0402"
			(at 0 -1.4 90)
			(layer "B.Fab")
			(effects
				(font
					(size 0.7 0.7)
					(thickness 0.15)
				)
				(justify left bottom mirror)
			)
		)
		(property "Description" "2k2 resistor in 0402 package with 1% tolerance"
			(at 0 0 270)
			(layer "F.Fab")
			(hide yes)
			(effects
				(font
					(size 1.27 1.27)
					(thickness 0.15)
				)
			)
		)
		(property "Author" "Antmicro"
			(at 101.82632 314.786336 0)
			(layer "B.Fab")
			(hide yes)
			(effects
				(font
					(size 1 1)
					(thickness 0.15)
				)
				(justify mirror)
			)
		)
		(property "License" "Apache-2.0"
			(at 101.82632 314.786336 0)
			(layer "B.Fab")
			(hide yes)
			(effects
				(font
					(size 1 1)
					(thickness 0.15)
				)
				(justify mirror)
			)
		)
		(property "MPN" "CR0402-FX-2201GLF"
			(at 101.82632 314.786336 0)
			(layer "B.Fab")
			(hide yes)
			(effects
				(font
					(size 1 1)
					(thickness 0.15)
				)
				(justify mirror)
			)
		)
		(property "Manufacturer" "Bourns"
			(at 101.82632 314.786336 0)
			(layer "B.Fab")
			(hide yes)
			(effects
				(font
					(size 1 1)
					(thickness 0.15)
				)
				(justify mirror)
			)
		)
		(property "Tolerance" "1%"
			(at 101.82632 314.786336 0)
			(layer "B.Fab")
			(hide yes)
			(effects
				(font
					(size 1 1)
					(thickness 0.15)
				)
				(justify mirror)
			)
		)
		(property "Val" "2k2"
			(at 101.82632 314.786336 0)
			(layer "B.Fab")
			(hide yes)
			(effects
				(font
					(size 1 1)
					(thickness 0.15)
				)
				(justify mirror)
			)
		)
		(sheetname "Ethernet")
		(sheetfile "ethernet.kicad_sch")
		(attr exclude_from_pos_files exclude_from_bom dnp)
		(fp_rect
			(start -0.93 0.47)
			(end 0.93 -0.47)
			(stroke
				(width 0.05)
				(type solid)
			)
			(fill no)
			(layer "B.CrtYd")
		)
		(fp_rect
			(start -0.5 0.25)
			(end 0.5 -0.25)
			(stroke
				(width 0.15)
				(type solid)
			)
			(fill no)
			(layer "B.Fab")
		)
		(pad "1" smd roundrect
			(at -0.485 0 270)
			(size 0.59 0.64)
			(layers "B.Cu" "B.Mask" "B.Paste")
			(roundrect_rratio 0.25)
			(net 13 "LED_SPD")
			(pintype "passive")
		)
		(pad "2" smd roundrect
			(at 0.485 0 270)
			(size 0.59 0.64)
			(layers "B.Cu" "B.Mask" "B.Paste")
			(roundrect_rratio 0.25)
			(net 5 "GND")
			(pintype "passive")
		)
	)
	(footprint "antmicro-footprints:R_0402_1005Metric"
		(layer "B.Cu")
		(at 208.306328 102.070008 90)
		(descr "Resistor SMD 0402")
		(tags "resistor SMD 0402")
		(property "Reference" "R93"
			(at 1.070008 1.293672 270)
			(layer "B.SilkS")
			(effects
				(font
					(size 0.7 0.7)
					(thickness 0.15)
				)
				(justify left bottom mirror)
			)
		)
		(property "Value" "R_2k2_0402"
			(at 0 -1.4 270)
			(layer "B.Fab")
			(effects
				(font
					(size 0.7 0.7)
					(thickness 0.15)
				)
				(justify left bottom mirror)
			)
		)
		(property "Description" "2k2 resistor in 0402 package with 1% tolerance"
			(at 0 0 90)
			(layer "F.Fab")
			(hide yes)
			(effects
				(font
					(size 1.27 1.27)
					(thickness 0.15)
				)
			)
		)
		(property "Author" "Antmicro"
			(at 310.376336 -106.23632 0)
			(layer "B.Fab")
			(hide yes)
			(effects
				(font
					(size 1 1)
					(thickness 0.15)
				)
				(justify mirror)
			)
		)
		(property "License" "Apache-2.0"
			(at 310.376336 -106.23632 0)
			(layer "B.Fab")
			(hide yes)
			(effects
				(font
					(size 1 1)
					(thickness 0.15)
				)
				(justify mirror)
			)
		)
		(property "MPN" "CR0402-FX-2201GLF"
			(at 310.376336 -106.23632 0)
			(layer "B.Fab")
			(hide yes)
			(effects
				(font
					(size 1 1)
					(thickness 0.15)
				)
				(justify mirror)
			)
		)
		(property "Manufacturer" "Bourns"
			(at 310.376336 -106.23632 0)
			(layer "B.Fab")
			(hide yes)
			(effects
				(font
					(size 1 1)
					(thickness 0.15)
				)
				(justify mirror)
			)
		)
		(property "Tolerance" "1%"
			(at 310.376336 -106.23632 0)
			(layer "B.Fab")
			(hide yes)
			(effects
				(font
					(size 1 1)
					(thickness 0.15)
				)
				(justify mirror)
			)
		)
		(property "Val" "2k2"
			(at 310.376336 -106.23632 0)
			(layer "B.Fab")
			(hide yes)
			(effects
				(font
					(size 1 1)
					(thickness 0.15)
				)
				(justify mirror)
			)
		)
		(sheetname "Ethernet")
		(sheetfile "ethernet.kicad_sch")
		(attr exclude_from_pos_files exclude_from_bom dnp)
		(fp_rect
			(start -0.93 0.47)
			(end 0.93 -0.47)
			(stroke
				(width 0.05)
				(type solid)
			)
			(fill no)
			(layer "B.CrtYd")
		)
		(fp_rect
			(start -0.5 0.25)
			(end 0.5 -0.25)
			(stroke
				(width 0.15)
				(type solid)
			)
			(fill no)
			(layer "B.Fab")
		)
		(pad "1" smd roundrect
			(at -0.485 0 90)
			(size 0.59 0.64)
			(layers "B.Cu" "B.Mask" "B.Paste")
			(roundrect_rratio 0.25)
			(net 12 "LED_LINK")
			(pintype "passive")
		)
		(pad "2" smd roundrect
			(at 0.485 0 90)
			(size 0.59 0.64)
			(layers "B.Cu" "B.Mask" "B.Paste")
			(roundrect_rratio 0.25)
			(net 5 "GND")
			(pintype "passive")
		)
	)
	(footprint "antmicro-footprints:R_0402_1005Metric"
		(layer "B.Cu")
		(at 198.376328 101.660008)
		(descr "Resistor SMD 0402")
		(tags "resistor SMD 0402")
		(property "Reference" "R91"
			(at -0.776328 0.339992 180)
			(layer "B.SilkS")
			(effects
				(font
					(size 0.7 0.7)
					(thickness 0.15)
				)
				(justify left bottom mirror)
			)
		)
		(property "Value" "R_2k2_0402"
			(at 0 -1.4 180)
			(layer "B.Fab")
			(effects
				(font
					(size 0.7 0.7)
					(thickness 0.15)
				)
				(justify left bottom mirror)
			)
		)
		(property "Description" "2k2 resistor in 0402 package with 1% tolerance"
			(at 0 0 0)
			(layer "F.Fab")
			(hide yes)
			(effects
				(font
					(size 1.27 1.27)
					(thickness 0.15)
				)
			)
		)
		(property "Author" "Antmicro"
			(at 0 0 0)
			(layer "B.Fab")
			(hide yes)
			(effects
				(font
					(size 1 1)
					(thickness 0.15)
				)
				(justify mirror)
			)
		)
		(property "License" "Apache-2.0"
			(at 0 0 0)
			(layer "B.Fab")
			(hide yes)
			(effects
				(font
					(size 1 1)
					(thickness 0.15)
				)
				(justify mirror)
			)
		)
		(property "MPN" "CR0402-FX-2201GLF"
			(at 0 0 0)
			(layer "B.Fab")
			(hide yes)
			(effects
				(font
					(size 1 1)
					(thickness 0.15)
				)
				(justify mirror)
			)
		)
		(property "Manufacturer" "Bourns"
			(at 0 0 0)
			(layer "B.Fab")
			(hide yes)
			(effects
				(font
					(size 1 1)
					(thickness 0.15)
				)
				(justify mirror)
			)
		)
		(property "Tolerance" "1%"
			(at 0 0 0)
			(layer "B.Fab")
			(hide yes)
			(effects
				(font
					(size 1 1)
					(thickness 0.15)
				)
				(justify mirror)
			)
		)
		(property "Val" "2k2"
			(at 0 0 0)
			(layer "B.Fab")
			(hide yes)
			(effects
				(font
					(size 1 1)
					(thickness 0.15)
				)
				(justify mirror)
			)
		)
		(sheetname "Ethernet")
		(sheetfile "ethernet.kicad_sch")
		(attr exclude_from_pos_files exclude_from_bom dnp)
		(fp_rect
			(start -0.93 0.47)
			(end 0.93 -0.47)
			(stroke
				(width 0.05)
				(type solid)
			)
			(fill no)
			(layer "B.CrtYd")
		)
		(fp_rect
			(start -0.5 0.25)
			(end 0.5 -0.25)
			(stroke
				(width 0.15)
				(type solid)
			)
			(fill no)
			(layer "B.Fab")
		)
		(pad "1" smd roundrect
			(at -0.485 0)
			(size 0.59 0.64)
			(layers "B.Cu" "B.Mask" "B.Paste")
			(roundrect_rratio 0.25)
			(net 26 "ETH_REF_CLK")
			(pintype "passive")
		)
		(pad "2" smd roundrect
			(at 0.485 0)
			(size 0.59 0.64)
			(layers "B.Cu" "B.Mask" "B.Paste")
			(roundrect_rratio 0.25)
			(net 5 "GND")
			(pintype "passive")
		)
	)
	(footprint "antmicro-footprints:R_0402_1005Metric"
		(layer "B.Cu")
		(at 193.486328 97.210008 180)
		(descr "Resistor SMD 0402")
		(tags "resistor SMD 0402")
		(property "Reference" "R89"
			(at 0.786328 -0.389992 0)
			(layer "B.SilkS")
			(effects
				(font
					(size 0.7 0.7)
					(thickness 0.15)
				)
				(justify left bottom mirror)
			)
		)
		(property "Value" "R_2k2_0402"
			(at 0 -1.4 0)
			(layer "B.Fab")
			(effects
				(font
					(size 0.7 0.7)
					(thickness 0.15)
				)
				(justify left bottom mirror)
			)
		)
		(property "Description" "2k2 resistor in 0402 package with 1% tolerance"
			(at 0 0 180)
			(layer "F.Fab")
			(hide yes)
			(effects
				(font
					(size 1.27 1.27)
					(thickness 0.15)
				)
			)
		)
		(property "Author" "Antmicro"
			(at 386.972656 194.420016 0)
			(layer "B.Fab")
			(hide yes)
			(effects
				(font
					(size 1 1)
					(thickness 0.15)
				)
				(justify mirror)
			)
		)
		(property "License" "Apache-2.0"
			(at 386.972656 194.420016 0)
			(layer "B.Fab")
			(hide yes)
			(effects
				(font
					(size 1 1)
					(thickness 0.15)
				)
				(justify mirror)
			)
		)
		(property "MPN" "CR0402-FX-2201GLF"
			(at 386.972656 194.420016 0)
			(layer "B.Fab")
			(hide yes)
			(effects
				(font
					(size 1 1)
					(thickness 0.15)
				)
				(justify mirror)
			)
		)
		(property "Manufacturer" "Bourns"
			(at 386.972656 194.420016 0)
			(layer "B.Fab")
			(hide yes)
			(effects
				(font
					(size 1 1)
					(thickness 0.15)
				)
				(justify mirror)
			)
		)
		(property "Tolerance" "1%"
			(at 386.972656 194.420016 0)
			(layer "B.Fab")
			(hide yes)
			(effects
				(font
					(size 1 1)
					(thickness 0.15)
				)
				(justify mirror)
			)
		)
		(property "Val" "2k2"
			(at 386.972656 194.420016 0)
			(layer "B.Fab")
			(hide yes)
			(effects
				(font
					(size 1 1)
					(thickness 0.15)
				)
				(justify mirror)
			)
		)
		(sheetname "Ethernet")
		(sheetfile "ethernet.kicad_sch")
		(attr smd)
		(fp_rect
			(start -0.93 0.47)
			(end 0.93 -0.47)
			(stroke
				(width 0.05)
				(type solid)
			)
			(fill no)
			(layer "B.CrtYd")
		)
		(fp_rect
			(start -0.5 0.25)
			(end 0.5 -0.25)
			(stroke
				(width 0.15)
				(type solid)
			)
			(fill no)
			(layer "B.Fab")
		)
		(pad "1" smd roundrect
			(at -0.485 0 180)
			(size 0.59 0.64)
			(layers "B.Cu" "B.Mask" "B.Paste")
			(roundrect_rratio 0.25)
			(net 34 "ETH_RX_DV")
			(pintype "passive")
		)
		(pad "2" smd roundrect
			(at 0.485 0 180)
			(size 0.59 0.64)
			(layers "B.Cu" "B.Mask" "B.Paste")
			(roundrect_rratio 0.25)
			(net 5 "GND")
			(pintype "passive")
		)
	)
	(footprint "antmicro-footprints:C_0201"
		(layer "B.Cu")
		(at 158.796328 89.180008)
		(descr "Capacitor SMD 0201")
		(tags "capacitor SMD 0201")
		(property "Reference" "C76"
			(at 1.003672 -0.280008 180)
			(layer "B.SilkS")
			(effects
				(font
					(size 0.7 0.7)
					(thickness 0.15)
				)
				(justify left bottom mirror)
			)
		)
		(property "Value" "C_100n_0201"
			(at 0 -1.4 180)
			(layer "B.Fab")
			(effects
				(font
					(size 0.7 0.7)
					(thickness 0.15)
				)
				(justify left bottom mirror)
			)
		)
		(property "Description" " "
			(at 0 0 0)
			(layer "F.Fab")
			(hide yes)
			(effects
				(font
					(size 1.27 1.27)
					(thickness 0.15)
				)
			)
		)
		(property "Author" "Antmicro"
			(at 0 0 0)
			(layer "B.Fab")
			(hide yes)
			(effects
				(font
					(size 1 1)
					(thickness 0.15)
				)
				(justify mirror)
			)
		)
		(property "Dielectric" ""
			(at 0 0 0)
			(layer "B.Fab")
			(hide yes)
			(effects
				(font
					(size 1 1)
					(thickness 0.15)
				)
				(justify mirror)
			)
		)
		(property "License" "Apache-2.0"
			(at 0 0 0)
			(layer "B.Fab")
			(hide yes)
			(effects
				(font
					(size 1 1)
					(thickness 0.15)
				)
				(justify mirror)
			)
		)
		(property "MPN" "CC0201KRX6S5BB104"
			(at 0 0 0)
			(layer "B.Fab")
			(hide yes)
			(effects
				(font
					(size 1 1)
					(thickness 0.15)
				)
				(justify mirror)
			)
		)
		(property "Manufacturer" "Yaego"
			(at 0 0 0)
			(layer "B.Fab")
			(hide yes)
			(effects
				(font
					(size 1 1)
					(thickness 0.15)
				)
				(justify mirror)
			)
		)
		(property "Val" "100n"
			(at 0 0 0)
			(layer "B.Fab")
			(hide yes)
			(effects
				(font
					(size 1 1)
					(thickness 0.15)
				)
				(justify mirror)
			)
		)
		(property "Voltage" ""
			(at 0 0 0)
			(layer "B.Fab")
			(hide yes)
			(effects
				(font
					(size 1 1)
					(thickness 0.15)
				)
				(justify mirror)
			)
		)
		(sheetname "FPGA power")
		(sheetfile "fpga-power.kicad_sch")
		(attr smd)
		(fp_rect
			(start -0.72 0.38)
			(end 0.72 -0.38)
			(stroke
				(width 0.05)
				(type solid)
			)
			(fill no)
			(layer "B.CrtYd")
		)
		(fp_rect
			(start 0.3 -0.15)
			(end -0.301 0.149)
			(stroke
				(width 0.15)
				(type solid)
			)
			(fill no)
			(layer "B.Fab")
		)
		(pad "" smd roundrect
			(at -0.349 0.002)
			(size 0.318 0.36)
			(layers "B.Paste")
			(roundrect_rratio 0.25)
		)
		(pad "" smd roundrect
			(at 0.341 0.002)
			(size 0.318 0.36)
			(layers "B.Paste")
			(roundrect_rratio 0.25)
		)
		(pad "1" smd roundrect
			(at -0.321 0.002)
			(size 0.46 0.4)
			(layers "B.Cu" "B.Mask")
			(roundrect_rratio 0.25)
			(net 66 "VDDQ")
			(pintype "passive")
		)
		(pad "2" smd roundrect
			(at 0.32 0.002)
			(size 0.46 0.4)
			(layers "B.Cu" "B.Mask")
			(roundrect_rratio 0.25)
			(net 5 "GND")
			(pintype "passive")
		)
	)
	(footprint "antmicro-footprints:C_0201"
		(layer "B.Cu")
		(at 161.006328 94.470008)
		(descr "Capacitor SMD 0201")
		(tags "capacitor SMD 0201")
		(property "Reference" "C80"
			(at -0.506328 0.429992 180)
			(layer "B.SilkS")
			(effects
				(font
					(size 0.7 0.7)
					(thickness 0.15)
				)
				(justify left bottom mirror)
			)
		)
		(property "Value" "C_100n_0201"
			(at 0 -1.4 180)
			(layer "B.Fab")
			(effects
				(font
					(size 0.7 0.7)
					(thickness 0.15)
				)
				(justify left bottom mirror)
			)
		)
		(property "Description" " "
			(at 0 0 0)
			(layer "F.Fab")
			(hide yes)
			(effects
				(font
					(size 1.27 1.27)
					(thickness 0.15)
				)
			)
		)
		(property "Author" "Antmicro"
			(at 0 0 0)
			(layer "B.Fab")
			(hide yes)
			(effects
				(font
					(size 1 1)
					(thickness 0.15)
				)
				(justify mirror)
			)
		)
		(property "Dielectric" ""
			(at 0 0 0)
			(layer "B.Fab")
			(hide yes)
			(effects
				(font
					(size 1 1)
					(thickness 0.15)
				)
				(justify mirror)
			)
		)
		(property "License" "Apache-2.0"
			(at 0 0 0)
			(layer "B.Fab")
			(hide yes)
			(effects
				(font
					(size 1 1)
					(thickness 0.15)
				)
				(justify mirror)
			)
		)
		(property "MPN" "CC0201KRX6S5BB104"
			(at 0 0 0)
			(layer "B.Fab")
			(hide yes)
			(effects
				(font
					(size 1 1)
					(thickness 0.15)
				)
				(justify mirror)
			)
		)
		(property "Manufacturer" "Yaego"
			(at 0 0 0)
			(layer "B.Fab")
			(hide yes)
			(effects
				(font
					(size 1 1)
					(thickness 0.15)
				)
				(justify mirror)
			)
		)
		(property "Val" "100n"
			(at 0 0 0)
			(layer "B.Fab")
			(hide yes)
			(effects
				(font
					(size 1 1)
					(thickness 0.15)
				)
				(justify mirror)
			)
		)
		(property "Voltage" ""
			(at 0 0 0)
			(layer "B.Fab")
			(hide yes)
			(effects
				(font
					(size 1 1)
					(thickness 0.15)
				)
				(justify mirror)
			)
		)
		(sheetname "FPGA power")
		(sheetfile "fpga-power.kicad_sch")
		(attr smd)
		(fp_rect
			(start -0.72 0.38)
			(end 0.72 -0.38)
			(stroke
				(width 0.05)
				(type solid)
			)
			(fill no)
			(layer "B.CrtYd")
		)
		(fp_rect
			(start 0.3 -0.15)
			(end -0.301 0.149)
			(stroke
				(width 0.15)
				(type solid)
			)
			(fill no)
			(layer "B.Fab")
		)
		(pad "" smd roundrect
			(at -0.349 0.002)
			(size 0.318 0.36)
			(layers "B.Paste")
			(roundrect_rratio 0.25)
		)
		(pad "" smd roundrect
			(at 0.341 0.002)
			(size 0.318 0.36)
			(layers "B.Paste")
			(roundrect_rratio 0.25)
		)
		(pad "1" smd roundrect
			(at -0.321 0.002)
			(size 0.46 0.4)
			(layers "B.Cu" "B.Mask")
			(roundrect_rratio 0.25)
			(net 66 "VDDQ")
			(pintype "passive")
		)
		(pad "2" smd roundrect
			(at 0.32 0.002)
			(size 0.46 0.4)
			(layers "B.Cu" "B.Mask")
			(roundrect_rratio 0.25)
			(net 5 "GND")
			(pintype "passive")
		)
	)
	(footprint "antmicro-footprints:R_0402_1005Metric"
		(layer "B.Cu")
		(at 125.6 67.65 180)
		(descr "Resistor SMD 0402")
		(tags "resistor SMD 0402")
		(property "Reference" "R158"
			(at -1.4 -1.25 0)
			(layer "B.SilkS")
			(effects
				(font
					(size 0.7 0.7)
					(thickness 0.15)
				)
				(justify left bottom mirror)
			)
		)
		(property "Value" "R_0R_0402"
			(at 0 -1.4 0)
			(layer "B.Fab")
			(effects
				(font
					(size 0.7 0.7)
					(thickness 0.15)
				)
				(justify left bottom mirror)
			)
		)
		(property "Description" "0R resistor in 0402 package with unspecified tolerance"
			(at 0 0 180)
			(layer "F.Fab")
			(hide yes)
			(effects
				(font
					(size 1.27 1.27)
					(thickness 0.15)
				)
			)
		)
		(property "Author" "Antmicro"
			(at 251.2 135.3 0)
			(layer "B.Fab")
			(hide yes)
			(effects
				(font
					(size 1 1)
					(thickness 0.15)
				)
				(justify mirror)
			)
		)
		(property "Current" "1A"
			(at 251.2 135.3 0)
			(layer "B.Fab")
			(hide yes)
			(effects
				(font
					(size 1 1)
					(thickness 0.15)
				)
				(justify mirror)
			)
		)
		(property "License" "Apache-2.0"
			(at 251.2 135.3 0)
			(layer "B.Fab")
			(hide yes)
			(effects
				(font
					(size 1 1)
					(thickness 0.15)
				)
				(justify mirror)
			)
		)
		(property "MPN" "ERJ2GE0R00X"
			(at 251.2 135.3 0)
			(layer "B.Fab")
			(hide yes)
			(effects
				(font
					(size 1 1)
					(thickness 0.15)
				)
				(justify mirror)
			)
		)
		(property "Manufacturer" "Panasonic"
			(at 251.2 135.3 0)
			(layer "B.Fab")
			(hide yes)
			(effects
				(font
					(size 1 1)
					(thickness 0.15)
				)
				(justify mirror)
			)
		)
		(property "Tolerance" ""
			(at 251.2 135.3 0)
			(layer "B.Fab")
			(hide yes)
			(effects
				(font
					(size 1 1)
					(thickness 0.15)
				)
				(justify mirror)
			)
		)
		(property "Val" "0R"
			(at 251.2 135.3 0)
			(layer "B.Fab")
			(hide yes)
			(effects
				(font
					(size 1 1)
					(thickness 0.15)
				)
				(justify mirror)
			)
		)
		(sheetname "Supply")
		(sheetfile "supply.kicad_sch")
		(attr exclude_from_pos_files exclude_from_bom dnp)
		(fp_rect
			(start -0.93 0.47)
			(end 0.93 -0.47)
			(stroke
				(width 0.05)
				(type solid)
			)
			(fill no)
			(layer "B.CrtYd")
		)
		(fp_rect
			(start -0.5 0.25)
			(end 0.5 -0.25)
			(stroke
				(width 0.15)
				(type solid)
			)
			(fill no)
			(layer "B.Fab")
		)
		(pad "1" smd roundrect
			(at -0.485 0 180)
			(size 0.59 0.64)
			(layers "B.Cu" "B.Mask" "B.Paste")
			(roundrect_rratio 0.25)
			(net 643 "FPGA_AB22_BALL")
			(pintype "passive")
		)
		(pad "2" smd roundrect
			(at 0.485 0 180)
			(size 0.59 0.64)
			(layers "B.Cu" "B.Mask" "B.Paste")
			(roundrect_rratio 0.25)
			(net 238 "Net-(Q13-G)")
			(pintype "passive")
		)
	)
	(footprint "antmicro-footprints:R_0402_1005Metric"
		(layer "B.Cu")
		(at 134.2 70)
		(descr "Resistor SMD 0402")
		(tags "resistor SMD 0402")
		(property "Reference" "R162"
			(at -0.7 0.4 180)
			(layer "B.SilkS")
			(effects
				(font
					(size 0.7 0.7)
					(thickness 0.15)
				)
				(justify left bottom mirror)
			)
		)
		(property "Value" "R_0R_0402"
			(at 0 -1.4 180)
			(layer "B.Fab")
			(effects
				(font
					(size 0.7 0.7)
					(thickness 0.15)
				)
				(justify left bottom mirror)
			)
		)
		(property "Description" "0R resistor in 0402 package with unspecified tolerance"
			(at 0 0 0)
			(layer "F.Fab")
			(hide yes)
			(effects
				(font
					(size 1.27 1.27)
					(thickness 0.15)
				)
			)
		)
		(property "Author" "Antmicro"
			(at 0 0 0)
			(layer "B.Fab")
			(hide yes)
			(effects
				(font
					(size 1 1)
					(thickness 0.15)
				)
				(justify mirror)
			)
		)
		(property "Current" "1A"
			(at 0 0 0)
			(layer "B.Fab")
			(hide yes)
			(effects
				(font
					(size 1 1)
					(thickness 0.15)
				)
				(justify mirror)
			)
		)
		(property "License" "Apache-2.0"
			(at 0 0 0)
			(layer "B.Fab")
			(hide yes)
			(effects
				(font
					(size 1 1)
					(thickness 0.15)
				)
				(justify mirror)
			)
		)
		(property "MPN" "ERJ2GE0R00X"
			(at 0 0 0)
			(layer "B.Fab")
			(hide yes)
			(effects
				(font
					(size 1 1)
					(thickness 0.15)
				)
				(justify mirror)
			)
		)
		(property "Manufacturer" "Panasonic"
			(at 0 0 0)
			(layer "B.Fab")
			(hide yes)
			(effects
				(font
					(size 1 1)
					(thickness 0.15)
				)
				(justify mirror)
			)
		)
		(property "Tolerance" ""
			(at 0 0 0)
			(layer "B.Fab")
			(hide yes)
			(effects
				(font
					(size 1 1)
					(thickness 0.15)
				)
				(justify mirror)
			)
		)
		(property "Val" "0R"
			(at 0 0 0)
			(layer "B.Fab")
			(hide yes)
			(effects
				(font
					(size 1 1)
					(thickness 0.15)
				)
				(justify mirror)
			)
		)
		(sheetname "Supply")
		(sheetfile "supply.kicad_sch")
		(attr exclude_from_pos_files exclude_from_bom dnp)
		(fp_rect
			(start -0.93 0.47)
			(end 0.93 -0.47)
			(stroke
				(width 0.05)
				(type solid)
			)
			(fill no)
			(layer "B.CrtYd")
		)
		(fp_rect
			(start -0.5 0.25)
			(end 0.5 -0.25)
			(stroke
				(width 0.15)
				(type solid)
			)
			(fill no)
			(layer "B.Fab")
		)
		(pad "1" smd roundrect
			(at -0.485 0)
			(size 0.59 0.64)
			(layers "B.Cu" "B.Mask" "B.Paste")
			(roundrect_rratio 0.25)
			(net 646 "FPGA_AA21_BALL")
			(pintype "passive")
		)
		(pad "2" smd roundrect
			(at 0.485 0)
			(size 0.59 0.64)
			(layers "B.Cu" "B.Mask" "B.Paste")
			(roundrect_rratio 0.25)
			(net 264 "Net-(U16-ON)")
			(pintype "passive")
		)
	)
	(footprint "antmicro-footprints:R_0402_1005Metric"
		(layer "B.Cu")
		(at 196.216328 98.210008)
		(descr "Resistor SMD 0402")
		(tags "resistor SMD 0402")
		(property "Reference" "R90"
			(at -3.926328 2.399992 0)
			(layer "B.SilkS")
			(effects
				(font
					(size 0.7 0.7)
					(thickness 0.15)
				)
				(justify right bottom mirror)
			)
		)
		(property "Value" "R_2k2_0402"
			(at 0 -1.4 0)
			(layer "B.Fab")
			(effects
				(font
					(size 0.7 0.7)
					(thickness 0.15)
				)
				(justify right bottom mirror)
			)
		)
		(property "Description" "2k2 resistor in 0402 package with 1% tolerance"
			(at 0 0 0)
			(layer "F.Fab")
			(hide yes)
			(effects
				(font
					(size 1.27 1.27)
					(thickness 0.15)
				)
			)
		)
		(property "Author" "Antmicro"
			(at 0 0 0)
			(layer "B.Fab")
			(hide yes)
			(effects
				(font
					(size 1 1)
					(thickness 0.15)
				)
				(justify mirror)
			)
		)
		(property "License" "Apache-2.0"
			(at 0 0 0)
			(layer "B.Fab")
			(hide yes)
			(effects
				(font
					(size 1 1)
					(thickness 0.15)
				)
				(justify mirror)
			)
		)
		(property "MPN" "CR0402-FX-2201GLF"
			(at 0 0 0)
			(layer "B.Fab")
			(hide yes)
			(effects
				(font
					(size 1 1)
					(thickness 0.15)
				)
				(justify mirror)
			)
		)
		(property "Manufacturer" "Bourns"
			(at 0 0 0)
			(layer "B.Fab")
			(hide yes)
			(effects
				(font
					(size 1 1)
					(thickness 0.15)
				)
				(justify mirror)
			)
		)
		(property "Tolerance" "1%"
			(at 0 0 0)
			(layer "B.Fab")
			(hide yes)
			(effects
				(font
					(size 1 1)
					(thickness 0.15)
				)
				(justify mirror)
			)
		)
		(property "Val" "2k2"
			(at 0 0 0)
			(layer "B.Fab")
			(hide yes)
			(effects
				(font
					(size 1 1)
					(thickness 0.15)
				)
				(justify mirror)
			)
		)
		(sheetname "Ethernet")
		(sheetfile "ethernet.kicad_sch")
		(attr smd)
		(fp_rect
			(start -0.93 0.47)
			(end 0.93 -0.47)
			(stroke
				(width 0.05)
				(type solid)
			)
			(fill no)
			(layer "B.CrtYd")
		)
		(fp_rect
			(start -0.5 0.25)
			(end 0.5 -0.25)
			(stroke
				(width 0.15)
				(type solid)
			)
			(fill no)
			(layer "B.Fab")
		)
		(pad "1" smd roundrect
			(at -0.485 0)
			(size 0.59 0.64)
			(layers "B.Cu" "B.Mask" "B.Paste")
			(roundrect_rratio 0.25)
			(net 36 "ETH_RX_CLK")
			(pintype "passive")
		)
		(pad "2" smd roundrect
			(at 0.485 0)
			(size 0.59 0.64)
			(layers "B.Cu" "B.Mask" "B.Paste")
			(roundrect_rratio 0.25)
			(net 5 "GND")
			(pintype "passive")
		)
	)
	(footprint "antmicro-footprints:R_0402_1005Metric"
		(layer "B.Cu")
		(at 122.7 68.95 180)
		(descr "Resistor SMD 0402")
		(tags "resistor SMD 0402")
		(property "Reference" "R159"
			(at -1.4 -1.25 0)
			(layer "B.SilkS")
			(effects
				(font
					(size 0.7 0.7)
					(thickness 0.15)
				)
				(justify left bottom mirror)
			)
		)
		(property "Value" "R_10k_0402"
			(at 0 -1.4 0)
			(layer "B.Fab")
			(effects
				(font
					(size 0.7 0.7)
					(thickness 0.15)
				)
				(justify left bottom mirror)
			)
		)
		(property "Description" "10k resistor in 0402 package with 1% tolerance"
			(at 0 0 180)
			(layer "F.Fab")
			(hide yes)
			(effects
				(font
					(size 1.27 1.27)
					(thickness 0.15)
				)
			)
		)
		(property "Author" "Antmicro"
			(at 245.4 137.9 0)
			(layer "B.Fab")
			(hide yes)
			(effects
				(font
					(size 1 1)
					(thickness 0.15)
				)
				(justify mirror)
			)
		)
		(property "License" "Apache-2.0"
			(at 245.4 137.9 0)
			(layer "B.Fab")
			(hide yes)
			(effects
				(font
					(size 1 1)
					(thickness 0.15)
				)
				(justify mirror)
			)
		)
		(property "MPN" "CR0402-FX-1002GLF"
			(at 245.4 137.9 0)
			(layer "B.Fab")
			(hide yes)
			(effects
				(font
					(size 1 1)
					(thickness 0.15)
				)
				(justify mirror)
			)
		)
		(property "Manufacturer" "Bourns"
			(at 245.4 137.9 0)
			(layer "B.Fab")
			(hide yes)
			(effects
				(font
					(size 1 1)
					(thickness 0.15)
				)
				(justify mirror)
			)
		)
		(property "Tolerance" "1%"
			(at 245.4 137.9 0)
			(layer "B.Fab")
			(hide yes)
			(effects
				(font
					(size 1 1)
					(thickness 0.15)
				)
				(justify mirror)
			)
		)
		(property "Val" "10k"
			(at 245.4 137.9 0)
			(layer "B.Fab")
			(hide yes)
			(effects
				(font
					(size 1 1)
					(thickness 0.15)
				)
				(justify mirror)
			)
		)
		(sheetname "Supply")
		(sheetfile "supply.kicad_sch")
		(attr exclude_from_pos_files exclude_from_bom dnp)
		(fp_rect
			(start -0.93 0.47)
			(end 0.93 -0.47)
			(stroke
				(width 0.05)
				(type solid)
			)
			(fill no)
			(layer "B.CrtYd")
		)
		(fp_rect
			(start -0.5 0.25)
			(end 0.5 -0.25)
			(stroke
				(width 0.15)
				(type solid)
			)
			(fill no)
			(layer "B.Fab")
		)
		(pad "1" smd roundrect
			(at -0.485 0 180)
			(size 0.59 0.64)
			(layers "B.Cu" "B.Mask" "B.Paste")
			(roundrect_rratio 0.25)
			(net 238 "Net-(Q13-G)")
			(pintype "passive")
		)
		(pad "2" smd roundrect
			(at 0.485 0 180)
			(size 0.59 0.64)
			(layers "B.Cu" "B.Mask" "B.Paste")
			(roundrect_rratio 0.25)
			(net 5 "GND")
			(pintype "passive")
		)
	)
	(footprint "antmicro-footprints:R_0402_1005Metric"
		(layer "B.Cu")
		(at 134.2 78.4)
		(descr "Resistor SMD 0402")
		(tags "resistor SMD 0402")
		(property "Reference" "R160"
			(at -0.7 0.4 180)
			(layer "B.SilkS")
			(effects
				(font
					(size 0.7 0.7)
					(thickness 0.15)
				)
				(justify left bottom mirror)
			)
		)
		(property "Value" "R_0R_0402"
			(at 0 -1.4 180)
			(layer "B.Fab")
			(effects
				(font
					(size 0.7 0.7)
					(thickness 0.15)
				)
				(justify left bottom mirror)
			)
		)
		(property "Description" "0R resistor in 0402 package with unspecified tolerance"
			(at 0 0 0)
			(layer "F.Fab")
			(hide yes)
			(effects
				(font
					(size 1.27 1.27)
					(thickness 0.15)
				)
			)
		)
		(property "Author" "Antmicro"
			(at 0 0 0)
			(layer "B.Fab")
			(hide yes)
			(effects
				(font
					(size 1 1)
					(thickness 0.15)
				)
				(justify mirror)
			)
		)
		(property "Current" "1A"
			(at 0 0 0)
			(layer "B.Fab")
			(hide yes)
			(effects
				(font
					(size 1 1)
					(thickness 0.15)
				)
				(justify mirror)
			)
		)
		(property "License" "Apache-2.0"
			(at 0 0 0)
			(layer "B.Fab")
			(hide yes)
			(effects
				(font
					(size 1 1)
					(thickness 0.15)
				)
				(justify mirror)
			)
		)
		(property "MPN" "ERJ2GE0R00X"
			(at 0 0 0)
			(layer "B.Fab")
			(hide yes)
			(effects
				(font
					(size 1 1)
					(thickness 0.15)
				)
				(justify mirror)
			)
		)
		(property "Manufacturer" "Panasonic"
			(at 0 0 0)
			(layer "B.Fab")
			(hide yes)
			(effects
				(font
					(size 1 1)
					(thickness 0.15)
				)
				(justify mirror)
			)
		)
		(property "Tolerance" ""
			(at 0 0 0)
			(layer "B.Fab")
			(hide yes)
			(effects
				(font
					(size 1 1)
					(thickness 0.15)
				)
				(justify mirror)
			)
		)
		(property "Val" "0R"
			(at 0 0 0)
			(layer "B.Fab")
			(hide yes)
			(effects
				(font
					(size 1 1)
					(thickness 0.15)
				)
				(justify mirror)
			)
		)
		(sheetname "Supply")
		(sheetfile "supply.kicad_sch")
		(attr exclude_from_pos_files exclude_from_bom dnp)
		(fp_rect
			(start -0.93 0.47)
			(end 0.93 -0.47)
			(stroke
				(width 0.05)
				(type solid)
			)
			(fill no)
			(layer "B.CrtYd")
		)
		(fp_rect
			(start -0.5 0.25)
			(end 0.5 -0.25)
			(stroke
				(width 0.15)
				(type solid)
			)
			(fill no)
			(layer "B.Fab")
		)
		(pad "1" smd roundrect
			(at -0.485 0)
			(size 0.59 0.64)
			(layers "B.Cu" "B.Mask" "B.Paste")
			(roundrect_rratio 0.25)
			(net 644 "FPGA_AB21_BALL")
			(pintype "passive")
		)
		(pad "2" smd roundrect
			(at 0.485 0)
			(size 0.59 0.64)
			(layers "B.Cu" "B.Mask" "B.Paste")
			(roundrect_rratio 0.25)
			(net 263 "Net-(U15-ON)")
			(pintype "passive")
		)
	)
	(footprint "antmicro-footprints:RENESAS-TDFN-8-1.5x2.0mm_P0.5mm"
		(layer "B.Cu")
		(at 136.3 69.5)
		(descr "8 Lead TDFN Package 1.5 x 2.0 mm (Fused Lead) JEDEC MO-252 ")
		(property "Reference" "U16"
			(at -3.458 -1.174 180)
			(unlocked yes)
			(layer "B.SilkS")
			(effects
				(font
					(size 0.7 0.7)
					(thickness 0.15)
				)
				(justify left bottom mirror)
			)
		)
		(property "Value" "SLG59M1457V"
			(at -9.7 -2.4 180)
			(unlocked yes)
			(layer "B.Fab")
			(effects
				(font
					(size 0.7 0.7)
					(thickness 0.15)
				)
				(justify left bottom mirror)
			)
		)
		(property "Description" "Power distribution switch/load driver"
			(at 0 0 0)
			(layer "F.Fab")
			(hide yes)
			(effects
				(font
					(size 1.27 1.27)
					(thickness 0.15)
				)
			)
		)
		(property "Author" "Antmicro"
			(at 0 0 0)
			(layer "B.Fab")
			(hide yes)
			(effects
				(font
					(size 1 1)
					(thickness 0.15)
				)
				(justify mirror)
			)
		)
		(property "License" "Apache-2.0"
			(at 0 0 0)
			(layer "B.Fab")
			(hide yes)
			(effects
				(font
					(size 1 1)
					(thickness 0.15)
				)
				(justify mirror)
			)
		)
		(property "MPN" "SLG59M1457V"
			(at 0 0 0)
			(layer "B.Fab")
			(hide yes)
			(effects
				(font
					(size 1 1)
					(thickness 0.15)
				)
				(justify mirror)
			)
		)
		(property "Manufacturer" "Dialog Semiconductor"
			(at 0 0 0)
			(layer "B.Fab")
			(hide yes)
			(effects
				(font
					(size 1 1)
					(thickness 0.15)
				)
				(justify mirror)
			)
		)
		(sheetname "Supply")
		(sheetfile "supply.kicad_sch")
		(attr exclude_from_pos_files exclude_from_bom dnp)
		(fp_line
			(start -0.946 1.101)
			(end 0.498 1.101)
			(stroke
				(width 0.15)
				(type solid)
			)
			(layer "B.SilkS")
		)
		(fp_line
			(start -0.5 -1.1)
			(end 0.498 -1.1)
			(stroke
				(width 0.15)
				(type solid)
			)
			(layer "B.SilkS")
		)
		(fp_circle
			(center -1.3 0.75)
			(end -1.249 0.75)
			(stroke
				(width 0.15)
				(type solid)
			)
			(fill yes)
			(layer "B.SilkS")
		)
		(fp_rect
			(start -1.25 1.5)
			(end 1.248 -1.498)
			(stroke
				(width 0.05)
				(type solid)
			)
			(fill no)
			(layer "B.CrtYd")
		)
		(fp_line
			(start -0.777 -1.03)
			(end 0.785 -1.03)
			(stroke
				(width 0.15)
				(type solid)
			)
			(layer "B.Fab")
		)
		(fp_line
			(start -0.777 0.75)
			(end -0.777 -1.03)
			(stroke
				(width 0.15)
				(type solid)
			)
			(layer "B.Fab")
		)
		(fp_line
			(start -0.495 1.031)
			(end -0.777 0.75)
			(stroke
				(width 0.15)
				(type solid)
			)
			(layer "B.Fab")
		)
		(fp_line
			(start 0.785 1.031)
			(end -0.495 1.031)
			(stroke
				(width 0.15)
				(type solid)
			)
			(layer "B.Fab")
		)
		(fp_line
			(start 0.785 1.031)
			(end 0.785 -1.03)
			(stroke
				(width 0.15)
				(type solid)
			)
			(layer "B.Fab")
		)
		(pad "1" smd rect
			(at -0.527 0.75 90)
			(size 0.28 0.85)
			(layers "B.Cu" "B.Mask" "B.Paste")
			(net 459 "3V3_SYS")
			(pinfunction "VDD")
			(pintype "power_in")
		)
		(pad "2" smd rect
			(at -0.576 0.25 90)
			(size 0.28 0.75)
			(layers "B.Cu" "B.Mask" "B.Paste")
			(net 264 "Net-(U16-ON)")
			(pinfunction "ON")
			(pintype "input")
		)
		(pad "3" smd custom
			(at -0.576 -0.248 90)
			(size 0.28 0.75)
			(layers "B.Cu" "B.Mask" "B.Paste")
			(net 460 "1V8_SYS")
			(pinfunction "IN")
			(pintype "power_in")
			(zone_connect 2)
			(options
				(clearance outline)
				(anchor rect)
			)
			(primitives
				(gr_poly
					(pts
						(xy -0.14 0.375) (xy -0.14 -0.05) (xy 0.64 -0.05) (xy 0.64 0.375)
					)
					(width 0)
					(fill yes)
				)
				(gr_rect
					(start 0.36 -0.375)
					(end 0.64 0.375)
					(width 0)
					(fill yes)
				)
			)
		)
		(pad "5" smd custom
			(at 0.574 -0.748 270)
			(size 0.28 0.75)
			(layers "B.Cu" "B.Mask" "B.Paste")
			(net 641 "1V8_DDR")
			(pinfunction "OUT")
			(pintype "power_out")
			(zone_connect 2)
			(options
				(clearance outline)
				(anchor rect)
			)
			(primitives
				(gr_poly
					(pts
						(xy -0.14 0.375) (xy -0.14 -0.05) (xy 0.64 -0.05) (xy 0.64 0.375)
					)
					(width 0)
					(fill yes)
				)
				(gr_rect
					(start 0.36 -0.375)
					(end 0.64 0.375)
					(width 0)
					(fill yes)
				)
			)
		)
		(pad "7" smd rect
			(at 0.574 0.25 90)
			(size 0.28 0.75)
			(layers "B.Cu" "B.Mask" "B.Paste")
			(net 62 "Net-(U16-CAP)")
			(pinfunction "CAP")
			(pintype "input")
		)
		(pad "8" smd rect
			(at 0.574 0.75 90)
			(size 0.28 0.75)
			(layers "B.Cu" "B.Mask" "B.Paste")
			(net 5 "GND")
			(pinfunction "GND")
			(pintype "passive")
		)
	)
	(footprint "antmicro-footprints:R_0402_1005Metric"
		(layer "B.Cu")
		(at 121 59.4)
		(descr "Resistor SMD 0402")
		(tags "resistor SMD 0402")
		(property "Reference" "R116"
			(at 1.4 1.3 180)
			(layer "B.SilkS")
			(effects
				(font
					(size 0.7 0.7)
					(thickness 0.15)
				)
				(justify left bottom mirror)
			)
		)
		(property "Value" "R_100k_0402"
			(at 0 -1.4 180)
			(layer "B.Fab")
			(effects
				(font
					(size 0.7 0.7)
					(thickness 0.15)
				)
				(justify left bottom mirror)
			)
		)
		(property "Description" "100k resistor in 0402 package with 1% tolerance"
			(at 0 0 0)
			(layer "F.Fab")
			(hide yes)
			(effects
				(font
					(size 1.27 1.27)
					(thickness 0.15)
				)
			)
		)
		(property "Author" "Antmicro"
			(at 0 0 0)
			(layer "B.Fab")
			(hide yes)
			(effects
				(font
					(size 1 1)
					(thickness 0.15)
				)
				(justify mirror)
			)
		)
		(property "License" "Apache-2.0"
			(at 0 0 0)
			(layer "B.Fab")
			(hide yes)
			(effects
				(font
					(size 1 1)
					(thickness 0.15)
				)
				(justify mirror)
			)
		)
		(property "MPN" "CR0402-FX-1003GLF"
			(at 0 0 0)
			(layer "B.Fab")
			(hide yes)
			(effects
				(font
					(size 1 1)
					(thickness 0.15)
				)
				(justify mirror)
			)
		)
		(property "Manufacturer" "Bourns"
			(at 0 0 0)
			(layer "B.Fab")
			(hide yes)
			(effects
				(font
					(size 1 1)
					(thickness 0.15)
				)
				(justify mirror)
			)
		)
		(property "Tolerance" "1%"
			(at 0 0 0)
			(layer "B.Fab")
			(hide yes)
			(effects
				(font
					(size 1 1)
					(thickness 0.15)
				)
				(justify mirror)
			)
		)
		(property "Val" "100k"
			(at 0 0 0)
			(layer "B.Fab")
			(hide yes)
			(effects
				(font
					(size 1 1)
					(thickness 0.15)
				)
				(justify mirror)
			)
		)
		(sheetname "Supply")
		(sheetfile "supply.kicad_sch")
		(attr exclude_from_pos_files exclude_from_bom dnp)
		(fp_rect
			(start -0.93 0.47)
			(end 0.93 -0.47)
			(stroke
				(width 0.05)
				(type solid)
			)
			(fill no)
			(layer "B.CrtYd")
		)
		(fp_rect
			(start -0.5 0.25)
			(end 0.5 -0.25)
			(stroke
				(width 0.15)
				(type solid)
			)
			(fill no)
			(layer "B.Fab")
		)
		(pad "1" smd roundrect
			(at -0.485 0)
			(size 0.59 0.64)
			(layers "B.Cu" "B.Mask" "B.Paste")
			(roundrect_rratio 0.25)
			(net 463 "VCC5V0_INT")
			(pintype "passive")
		)
		(pad "2" smd roundrect
			(at 0.485 0)
			(size 0.59 0.64)
			(layers "B.Cu" "B.Mask" "B.Paste")
			(roundrect_rratio 0.25)
			(net 630 "/Supply/LPDDR4_PGOOD")
			(pintype "passive")
		)
	)
	(footprint "antmicro-footprints:C_0402_1005Metric"
		(layer "B.Cu")
		(at 136.3 79.7)
		(descr "Capacitor SMD 0402")
		(tags "capacitor SMD 0402")
		(property "Reference" "C144"
			(at 1.4 1.3 180)
			(layer "B.SilkS")
			(effects
				(font
					(size 0.7 0.7)
					(thickness 0.15)
				)
				(justify left bottom mirror)
			)
		)
		(property "Value" "C_100n_6V3_0402"
			(at 0 -1.4 180)
			(layer "B.Fab")
			(effects
				(font
					(size 0.7 0.7)
					(thickness 0.15)
				)
				(justify left bottom mirror)
			)
		)
		(property "Description" " "
			(at 0 0 0)
			(layer "F.Fab")
			(hide yes)
			(effects
				(font
					(size 1.27 1.27)
					(thickness 0.15)
				)
			)
		)
		(property "Author" "Antmicro"
			(at 0 0 0)
			(layer "B.Fab")
			(hide yes)
			(effects
				(font
					(size 1 1)
					(thickness 0.15)
				)
				(justify mirror)
			)
		)
		(property "Dielectric" ""
			(at 0 0 0)
			(layer "B.Fab")
			(hide yes)
			(effects
				(font
					(size 1 1)
					(thickness 0.15)
				)
				(justify mirror)
			)
		)
		(property "License" "Apache-2.0"
			(at 0 0 0)
			(layer "B.Fab")
			(hide yes)
			(effects
				(font
					(size 1 1)
					(thickness 0.15)
				)
				(justify mirror)
			)
		)
		(property "MPN" "0402X104K6R3CT"
			(at 0 0 0)
			(layer "B.Fab")
			(hide yes)
			(effects
				(font
					(size 1 1)
					(thickness 0.15)
				)
				(justify mirror)
			)
		)
		(property "Manufacturer" "Walsin"
			(at 0 0 0)
			(layer "B.Fab")
			(hide yes)
			(effects
				(font
					(size 1 1)
					(thickness 0.15)
				)
				(justify mirror)
			)
		)
		(property "Val" "100n"
			(at 0 0 0)
			(layer "B.Fab")
			(hide yes)
			(effects
				(font
					(size 1 1)
					(thickness 0.15)
				)
				(justify mirror)
			)
		)
		(property "Voltage" ""
			(at 0 0 0)
			(layer "B.Fab")
			(hide yes)
			(effects
				(font
					(size 1 1)
					(thickness 0.15)
				)
				(justify mirror)
			)
		)
		(sheetname "Supply")
		(sheetfile "supply.kicad_sch")
		(attr exclude_from_pos_files exclude_from_bom dnp)
		(fp_rect
			(start -0.94 0.47)
			(end 0.94 -0.47)
			(stroke
				(width 0.05)
				(type solid)
			)
			(fill no)
			(layer "B.CrtYd")
		)
		(fp_rect
			(start -0.499 0.249)
			(end 0.499 -0.249)
			(stroke
				(width 0.15)
				(type solid)
			)
			(fill no)
			(layer "B.Fab")
		)
		(pad "1" smd roundrect
			(at -0.484 0)
			(size 0.59 0.64)
			(layers "B.Cu" "B.Mask" "B.Paste")
			(roundrect_rratio 0.25)
			(net 459 "3V3_SYS")
			(pintype "passive")
		)
		(pad "2" smd roundrect
			(at 0.484 0)
			(size 0.59 0.64)
			(layers "B.Cu" "B.Mask" "B.Paste")
			(roundrect_rratio 0.25)
			(net 5 "GND")
			(pintype "passive")
		)
	)
	(footprint "antmicro-footprints:R_0805_2012Metric"
		(layer "B.Cu")
		(at 136.4 67.2)
		(property "Reference" "R165"
			(at -1.6 0.4 180)
			(layer "B.SilkS")
			(effects
				(font
					(size 0.7 0.7)
					(thickness 0.15)
				)
				(justify left bottom mirror)
			)
		)
		(property "Value" "R_0R_0805"
			(at 0 -1.8 180)
			(layer "B.Fab")
			(effects
				(font
					(size 0.7 0.7)
					(thickness 0.15)
				)
				(justify left bottom mirror)
			)
		)
		(property "Description" "0R resistor in 0805 package with unspecified tolerance"
			(at 0 0 0)
			(layer "F.Fab")
			(hide yes)
			(effects
				(font
					(size 1.27 1.27)
					(thickness 0.15)
				)
			)
		)
		(property "Author" "Antmicro"
			(at 0 0 0)
			(layer "B.Fab")
			(hide yes)
			(effects
				(font
					(size 1 1)
					(thickness 0.15)
				)
				(justify mirror)
			)
		)
		(property "Current" "2.5A"
			(at 0 0 0)
			(layer "B.Fab")
			(hide yes)
			(effects
				(font
					(size 1 1)
					(thickness 0.15)
				)
				(justify mirror)
			)
		)
		(property "License" "Apache-2.0"
			(at 0 0 0)
			(layer "B.Fab")
			(hide yes)
			(effects
				(font
					(size 1 1)
					(thickness 0.15)
				)
				(justify mirror)
			)
		)
		(property "MPN" "CRCW08050000Z0EA"
			(at 0 0 0)
			(layer "B.Fab")
			(hide yes)
			(effects
				(font
					(size 1 1)
					(thickness 0.15)
				)
				(justify mirror)
			)
		)
		(property "Manufacturer" "Vishay"
			(at 0 0 0)
			(layer "B.Fab")
			(hide yes)
			(effects
				(font
					(size 1 1)
					(thickness 0.15)
				)
				(justify mirror)
			)
		)
		(property "Tolerance" ""
			(at 0 0 0)
			(layer "B.Fab")
			(hide yes)
			(effects
				(font
					(size 1 1)
					(thickness 0.15)
				)
				(justify mirror)
			)
		)
		(property "Val" "0R"
			(at 0 0 0)
			(layer "B.Fab")
			(hide yes)
			(effects
				(font
					(size 1 1)
					(thickness 0.15)
				)
				(justify mirror)
			)
		)
		(sheetname "Supply")
		(sheetfile "supply.kicad_sch")
		(attr smd)
		(fp_line
			(start -0.32 -0.699)
			(end 0.28 -0.699)
			(stroke
				(width 0.15)
				(type solid)
			)
			(layer "B.SilkS")
		)
		(fp_line
			(start -0.3 0.701)
			(end 0.298 0.701)
			(stroke
				(width 0.15)
				(type solid)
			)
			(layer "B.SilkS")
		)
		(fp_rect
			(start -1.75 0.85)
			(end 1.75 -0.85)
			(stroke
				(width 0.05)
				(type solid)
			)
			(fill no)
			(layer "B.CrtYd")
		)
		(fp_line
			(start -0.951 -0.68)
			(end 0.949 -0.68)
			(stroke
				(width 0.15)
				(type solid)
			)
			(layer "B.Fab")
		)
		(fp_line
			(start -0.951 0.677)
			(end -0.951 -0.675)
			(stroke
				(width 0.15)
				(type solid)
			)
			(layer "B.Fab")
		)
		(fp_line
			(start -0.951 0.682)
			(end 0.949 0.682)
			(stroke
				(width 0.15)
				(type solid)
			)
			(layer "B.Fab")
		)
		(fp_line
			(start 0.949 0.677)
			(end 0.949 -0.675)
			(stroke
				(width 0.15)
				(type solid)
			)
			(layer "B.Fab")
		)
		(pad "1" smd roundrect
			(at -1.1 0.001)
			(size 1 1.4)
			(layers "B.Cu" "B.Mask" "B.Paste")
			(roundrect_rratio 0.15)
			(net 460 "1V8_SYS")
			(pintype "passive")
		)
		(pad "2" smd roundrect
			(at 1.1 0.001)
			(size 1 1.4)
			(layers "B.Cu" "B.Mask" "B.Paste")
			(roundrect_rratio 0.15)
			(net 641 "1V8_DDR")
			(pintype "passive")
		)
	)
	(footprint "antmicro-footprints:R_0402_1005Metric"
		(layer "B.Cu")
		(at 134.2 71.3 180)
		(descr "Resistor SMD 0402")
		(tags "resistor SMD 0402")
		(property "Reference" "R163"
			(at 0.7 -0.4 0)
			(layer "B.SilkS")
			(effects
				(font
					(size 0.7 0.7)
					(thickness 0.15)
				)
				(justify left bottom mirror)
			)
		)
		(property "Value" "R_10k_0402"
			(at 0 -1.4 0)
			(layer "B.Fab")
			(effects
				(font
					(size 0.7 0.7)
					(thickness 0.15)
				)
				(justify left bottom mirror)
			)
		)
		(property "Description" "10k resistor in 0402 package with 1% tolerance"
			(at 0 0 180)
			(layer "F.Fab")
			(hide yes)
			(effects
				(font
					(size 1.27 1.27)
					(thickness 0.15)
				)
			)
		)
		(property "Author" "Antmicro"
			(at 268.4 142.6 0)
			(layer "B.Fab")
			(hide yes)
			(effects
				(font
					(size 1 1)
					(thickness 0.15)
				)
				(justify mirror)
			)
		)
		(property "License" "Apache-2.0"
			(at 268.4 142.6 0)
			(layer "B.Fab")
			(hide yes)
			(effects
				(font
					(size 1 1)
					(thickness 0.15)
				)
				(justify mirror)
			)
		)
		(property "MPN" "CR0402-FX-1002GLF"
			(at 268.4 142.6 0)
			(layer "B.Fab")
			(hide yes)
			(effects
				(font
					(size 1 1)
					(thickness 0.15)
				)
				(justify mirror)
			)
		)
		(property "Manufacturer" "Bourns"
			(at 268.4 142.6 0)
			(layer "B.Fab")
			(hide yes)
			(effects
				(font
					(size 1 1)
					(thickness 0.15)
				)
				(justify mirror)
			)
		)
		(property "Tolerance" "1%"
			(at 268.4 142.6 0)
			(layer "B.Fab")
			(hide yes)
			(effects
				(font
					(size 1 1)
					(thickness 0.15)
				)
				(justify mirror)
			)
		)
		(property "Val" "10k"
			(at 268.4 142.6 0)
			(layer "B.Fab")
			(hide yes)
			(effects
				(font
					(size 1 1)
					(thickness 0.15)
				)
				(justify mirror)
			)
		)
		(sheetname "Supply")
		(sheetfile "supply.kicad_sch")
		(attr exclude_from_pos_files exclude_from_bom dnp)
		(fp_rect
			(start -0.93 0.47)
			(end 0.93 -0.47)
			(stroke
				(width 0.05)
				(type solid)
			)
			(fill no)
			(layer "B.CrtYd")
		)
		(fp_rect
			(start -0.5 0.25)
			(end 0.5 -0.25)
			(stroke
				(width 0.15)
				(type solid)
			)
			(fill no)
			(layer "B.Fab")
		)
		(pad "1" smd roundrect
			(at -0.485 0 180)
			(size 0.59 0.64)
			(layers "B.Cu" "B.Mask" "B.Paste")
			(roundrect_rratio 0.25)
			(net 459 "3V3_SYS")
			(pintype "passive")
		)
		(pad "2" smd roundrect
			(at 0.485 0 180)
			(size 0.59 0.64)
			(layers "B.Cu" "B.Mask" "B.Paste")
			(roundrect_rratio 0.25)
			(net 264 "Net-(U16-ON)")
			(pintype "passive")
		)
	)
	(footprint "antmicro-footprints:C_0402_1005Metric"
		(layer "B.Cu")
		(at 137.9 79.2 -90)
		(descr "Capacitor SMD 0402")
		(tags "capacitor SMD 0402")
		(property "Reference" "C146"
			(at -1.4 -1.3 90)
			(layer "B.SilkS")
			(effects
				(font
					(size 0.7 0.7)
					(thickness 0.15)
				)
				(justify left bottom mirror)
			)
		)
		(property "Value" "C_1n8_0402"
			(at 0 -1.4 90)
			(layer "B.Fab")
			(effects
				(font
					(size 0.7 0.7)
					(thickness 0.15)
				)
				(justify left bottom mirror)
			)
		)
		(property "Description" " "
			(at 0 0 270)
			(layer "F.Fab")
			(hide yes)
			(effects
				(font
					(size 1.27 1.27)
					(thickness 0.15)
				)
			)
		)
		(property "Author" "Antmicro"
			(at 58.7 217.1 0)
			(layer "B.Fab")
			(hide yes)
			(effects
				(font
					(size 1 1)
					(thickness 0.15)
				)
				(justify mirror)
			)
		)
		(property "Dielectric" ""
			(at 58.7 217.1 0)
			(layer "B.Fab")
			(hide yes)
			(effects
				(font
					(size 1 1)
					(thickness 0.15)
				)
				(justify mirror)
			)
		)
		(property "License" "Apache-2.0"
			(at 58.7 217.1 0)
			(layer "B.Fab")
			(hide yes)
			(effects
				(font
					(size 1 1)
					(thickness 0.15)
				)
				(justify mirror)
			)
		)
		(property "MPN" "0402B182K500CT"
			(at 58.7 217.1 0)
			(layer "B.Fab")
			(hide yes)
			(effects
				(font
					(size 1 1)
					(thickness 0.15)
				)
				(justify mirror)
			)
		)
		(property "Manufacturer" "Walsin"
			(at 58.7 217.1 0)
			(layer "B.Fab")
			(hide yes)
			(effects
				(font
					(size 1 1)
					(thickness 0.15)
				)
				(justify mirror)
			)
		)
		(property "Val" "1n8"
			(at 58.7 217.1 0)
			(layer "B.Fab")
			(hide yes)
			(effects
				(font
					(size 1 1)
					(thickness 0.15)
				)
				(justify mirror)
			)
		)
		(property "Voltage" ""
			(at 58.7 217.1 0)
			(layer "B.Fab")
			(hide yes)
			(effects
				(font
					(size 1 1)
					(thickness 0.15)
				)
				(justify mirror)
			)
		)
		(sheetname "Supply")
		(sheetfile "supply.kicad_sch")
		(attr exclude_from_pos_files exclude_from_bom dnp)
		(fp_rect
			(start -0.94 0.47)
			(end 0.94 -0.47)
			(stroke
				(width 0.05)
				(type solid)
			)
			(fill no)
			(layer "B.CrtYd")
		)
		(fp_rect
			(start -0.499 0.249)
			(end 0.499 -0.249)
			(stroke
				(width 0.15)
				(type solid)
			)
			(fill no)
			(layer "B.Fab")
		)
		(pad "1" smd roundrect
			(at -0.484 0 270)
			(size 0.59 0.64)
			(layers "B.Cu" "B.Mask" "B.Paste")
			(roundrect_rratio 0.25)
			(net 60 "Net-(U15-CAP)")
			(pintype "passive")
		)
		(pad "2" smd roundrect
			(at 0.484 0 270)
			(size 0.59 0.64)
			(layers "B.Cu" "B.Mask" "B.Paste")
			(roundrect_rratio 0.25)
			(net 5 "GND")
			(pintype "passive")
		)
	)
	(footprint "antmicro-footprints:C_0402_1005Metric"
		(layer "B.Cu")
		(at 136.3 71.3)
		(descr "Capacitor SMD 0402")
		(tags "capacitor SMD 0402")
		(property "Reference" "C188"
			(at 1.4 1.3 180)
			(layer "B.SilkS")
			(effects
				(font
					(size 0.7 0.7)
					(thickness 0.15)
				)
				(justify left bottom mirror)
			)
		)
		(property "Value" "C_100n_6V3_0402"
			(at 0 -1.4 180)
			(layer "B.Fab")
			(effects
				(font
					(size 0.7 0.7)
					(thickness 0.15)
				)
				(justify left bottom mirror)
			)
		)
		(property "Description" " "
			(at 0 0 0)
			(layer "F.Fab")
			(hide yes)
			(effects
				(font
					(size 1.27 1.27)
					(thickness 0.15)
				)
			)
		)
		(property "Author" "Antmicro"
			(at 0 0 0)
			(layer "B.Fab")
			(hide yes)
			(effects
				(font
					(size 1 1)
					(thickness 0.15)
				)
				(justify mirror)
			)
		)
		(property "Dielectric" ""
			(at 0 0 0)
			(layer "B.Fab")
			(hide yes)
			(effects
				(font
					(size 1 1)
					(thickness 0.15)
				)
				(justify mirror)
			)
		)
		(property "License" "Apache-2.0"
			(at 0 0 0)
			(layer "B.Fab")
			(hide yes)
			(effects
				(font
					(size 1 1)
					(thickness 0.15)
				)
				(justify mirror)
			)
		)
		(property "MPN" "0402X104K6R3CT"
			(at 0 0 0)
			(layer "B.Fab")
			(hide yes)
			(effects
				(font
					(size 1 1)
					(thickness 0.15)
				)
				(justify mirror)
			)
		)
		(property "Manufacturer" "Walsin"
			(at 0 0 0)
			(layer "B.Fab")
			(hide yes)
			(effects
				(font
					(size 1 1)
					(thickness 0.15)
				)
				(justify mirror)
			)
		)
		(property "Val" "100n"
			(at 0 0 0)
			(layer "B.Fab")
			(hide yes)
			(effects
				(font
					(size 1 1)
					(thickness 0.15)
				)
				(justify mirror)
			)
		)
		(property "Voltage" ""
			(at 0 0 0)
			(layer "B.Fab")
			(hide yes)
			(effects
				(font
					(size 1 1)
					(thickness 0.15)
				)
				(justify mirror)
			)
		)
		(sheetname "Supply")
		(sheetfile "supply.kicad_sch")
		(attr exclude_from_pos_files exclude_from_bom dnp)
		(fp_rect
			(start -0.94 0.47)
			(end 0.94 -0.47)
			(stroke
				(width 0.05)
				(type solid)
			)
			(fill no)
			(layer "B.CrtYd")
		)
		(fp_rect
			(start -0.499 0.249)
			(end 0.499 -0.249)
			(stroke
				(width 0.15)
				(type solid)
			)
			(fill no)
			(layer "B.Fab")
		)
		(pad "1" smd roundrect
			(at -0.484 0)
			(size 0.59 0.64)
			(layers "B.Cu" "B.Mask" "B.Paste")
			(roundrect_rratio 0.25)
			(net 459 "3V3_SYS")
			(pintype "passive")
		)
		(pad "2" smd roundrect
			(at 0.484 0)
			(size 0.59 0.64)
			(layers "B.Cu" "B.Mask" "B.Paste")
			(roundrect_rratio 0.25)
			(net 5 "GND")
			(pintype "passive")
		)
	)
	(footprint "antmicro-footprints:R_0805_2012Metric"
		(layer "B.Cu")
		(at 136.3 75.6)
		(property "Reference" "R164"
			(at -1.6 0.4 180)
			(layer "B.SilkS")
			(effects
				(font
					(size 0.7 0.7)
					(thickness 0.15)
				)
				(justify left bottom mirror)
			)
		)
		(property "Value" "R_0R_0805"
			(at 0 -1.8 180)
			(layer "B.Fab")
			(effects
				(font
					(size 0.7 0.7)
					(thickness 0.15)
				)
				(justify left bottom mirror)
			)
		)
		(property "Description" "0R resistor in 0805 package with unspecified tolerance"
			(at 0 0 0)
			(layer "F.Fab")
			(hide yes)
			(effects
				(font
					(size 1.27 1.27)
					(thickness 0.15)
				)
			)
		)
		(property "Author" "Antmicro"
			(at 0 0 0)
			(layer "B.Fab")
			(hide yes)
			(effects
				(font
					(size 1 1)
					(thickness 0.15)
				)
				(justify mirror)
			)
		)
		(property "Current" "2.5A"
			(at 0 0 0)
			(layer "B.Fab")
			(hide yes)
			(effects
				(font
					(size 1 1)
					(thickness 0.15)
				)
				(justify mirror)
			)
		)
		(property "License" "Apache-2.0"
			(at 0 0 0)
			(layer "B.Fab")
			(hide yes)
			(effects
				(font
					(size 1 1)
					(thickness 0.15)
				)
				(justify mirror)
			)
		)
		(property "MPN" "CRCW08050000Z0EA"
			(at 0 0 0)
			(layer "B.Fab")
			(hide yes)
			(effects
				(font
					(size 1 1)
					(thickness 0.15)
				)
				(justify mirror)
			)
		)
		(property "Manufacturer" "Vishay"
			(at 0 0 0)
			(layer "B.Fab")
			(hide yes)
			(effects
				(font
					(size 1 1)
					(thickness 0.15)
				)
				(justify mirror)
			)
		)
		(property "Tolerance" ""
			(at 0 0 0)
			(layer "B.Fab")
			(hide yes)
			(effects
				(font
					(size 1 1)
					(thickness 0.15)
				)
				(justify mirror)
			)
		)
		(property "Val" "0R"
			(at 0 0 0)
			(layer "B.Fab")
			(hide yes)
			(effects
				(font
					(size 1 1)
					(thickness 0.15)
				)
				(justify mirror)
			)
		)
		(sheetname "Supply")
		(sheetfile "supply.kicad_sch")
		(attr smd)
		(fp_line
			(start -0.32 -0.699)
			(end 0.28 -0.699)
			(stroke
				(width 0.15)
				(type solid)
			)
			(layer "B.SilkS")
		)
		(fp_line
			(start -0.3 0.701)
			(end 0.298 0.701)
			(stroke
				(width 0.15)
				(type solid)
			)
			(layer "B.SilkS")
		)
		(fp_rect
			(start -1.75 0.85)
			(end 1.75 -0.85)
			(stroke
				(width 0.05)
				(type solid)
			)
			(fill no)
			(layer "B.CrtYd")
		)
		(fp_line
			(start -0.951 -0.68)
			(end 0.949 -0.68)
			(stroke
				(width 0.15)
				(type solid)
			)
			(layer "B.Fab")
		)
		(fp_line
			(start -0.951 0.677)
			(end -0.951 -0.675)
			(stroke
				(width 0.15)
				(type solid)
			)
			(layer "B.Fab")
		)
		(fp_line
			(start -0.951 0.682)
			(end 0.949 0.682)
			(stroke
				(width 0.15)
				(type solid)
			)
			(layer "B.Fab")
		)
		(fp_line
			(start 0.949 0.677)
			(end 0.949 -0.675)
			(stroke
				(width 0.15)
				(type solid)
			)
			(layer "B.Fab")
		)
		(pad "1" smd roundrect
			(at -1.1 0.001)
			(size 1 1.4)
			(layers "B.Cu" "B.Mask" "B.Paste")
			(roundrect_rratio 0.15)
			(net 461 "1V1_SYS")
			(pintype "passive")
		)
		(pad "2" smd roundrect
			(at 1.1 0.001)
			(size 1 1.4)
			(layers "B.Cu" "B.Mask" "B.Paste")
			(roundrect_rratio 0.15)
			(net 273 "1V1_DDR")
			(pintype "passive")
		)
	)
	(footprint "antmicro-footprints:R_0402_1005Metric"
		(layer "B.Cu")
		(at 134.2 79.7 180)
		(descr "Resistor SMD 0402")
		(tags "resistor SMD 0402")
		(property "Reference" "R161"
			(at 0.7 -0.4 0)
			(layer "B.SilkS")
			(effects
				(font
					(size 0.7 0.7)
					(thickness 0.15)
				)
				(justify left bottom mirror)
			)
		)
		(property "Value" "R_10k_0402"
			(at 0 -1.4 0)
			(layer "B.Fab")
			(effects
				(font
					(size 0.7 0.7)
					(thickness 0.15)
				)
				(justify left bottom mirror)
			)
		)
		(property "Description" "10k resistor in 0402 package with 1% tolerance"
			(at 0 0 180)
			(layer "F.Fab")
			(hide yes)
			(effects
				(font
					(size 1.27 1.27)
					(thickness 0.15)
				)
			)
		)
		(property "Author" "Antmicro"
			(at 268.4 159.4 0)
			(layer "B.Fab")
			(hide yes)
			(effects
				(font
					(size 1 1)
					(thickness 0.15)
				)
				(justify mirror)
			)
		)
		(property "License" "Apache-2.0"
			(at 268.4 159.4 0)
			(layer "B.Fab")
			(hide yes)
			(effects
				(font
					(size 1 1)
					(thickness 0.15)
				)
				(justify mirror)
			)
		)
		(property "MPN" "CR0402-FX-1002GLF"
			(at 268.4 159.4 0)
			(layer "B.Fab")
			(hide yes)
			(effects
				(font
					(size 1 1)
					(thickness 0.15)
				)
				(justify mirror)
			)
		)
		(property "Manufacturer" "Bourns"
			(at 268.4 159.4 0)
			(layer "B.Fab")
			(hide yes)
			(effects
				(font
					(size 1 1)
					(thickness 0.15)
				)
				(justify mirror)
			)
		)
		(property "Tolerance" "1%"
			(at 268.4 159.4 0)
			(layer "B.Fab")
			(hide yes)
			(effects
				(font
					(size 1 1)
					(thickness 0.15)
				)
				(justify mirror)
			)
		)
		(property "Val" "10k"
			(at 268.4 159.4 0)
			(layer "B.Fab")
			(hide yes)
			(effects
				(font
					(size 1 1)
					(thickness 0.15)
				)
				(justify mirror)
			)
		)
		(sheetname "Supply")
		(sheetfile "supply.kicad_sch")
		(attr exclude_from_pos_files exclude_from_bom dnp)
		(fp_rect
			(start -0.93 0.47)
			(end 0.93 -0.47)
			(stroke
				(width 0.05)
				(type solid)
			)
			(fill no)
			(layer "B.CrtYd")
		)
		(fp_rect
			(start -0.5 0.25)
			(end 0.5 -0.25)
			(stroke
				(width 0.15)
				(type solid)
			)
			(fill no)
			(layer "B.Fab")
		)
		(pad "1" smd roundrect
			(at -0.485 0 180)
			(size 0.59 0.64)
			(layers "B.Cu" "B.Mask" "B.Paste")
			(roundrect_rratio 0.25)
			(net 459 "3V3_SYS")
			(pintype "passive")
		)
		(pad "2" smd roundrect
			(at 0.485 0 180)
			(size 0.59 0.64)
			(layers "B.Cu" "B.Mask" "B.Paste")
			(roundrect_rratio 0.25)
			(net 263 "Net-(U15-ON)")
			(pintype "passive")
		)
	)
	(footprint "antmicro-footprints:C_0402_1005Metric"
		(layer "B.Cu")
		(at 137.9 70.8 -90)
		(descr "Capacitor SMD 0402")
		(tags "capacitor SMD 0402")
		(property "Reference" "C199"
			(at -1.4 -1.2 90)
			(layer "B.SilkS")
			(effects
				(font
					(size 0.7 0.7)
					(thickness 0.15)
				)
				(justify left bottom mirror)
			)
		)
		(property "Value" "C_1n8_0402"
			(at 0 -1.4 90)
			(layer "B.Fab")
			(effects
				(font
					(size 0.7 0.7)
					(thickness 0.15)
				)
				(justify left bottom mirror)
			)
		)
		(property "Description" " "
			(at 0 0 270)
			(layer "F.Fab")
			(hide yes)
			(effects
				(font
					(size 1.27 1.27)
					(thickness 0.15)
				)
			)
		)
		(property "Author" "Antmicro"
			(at 67.1 208.7 0)
			(layer "B.Fab")
			(hide yes)
			(effects
				(font
					(size 1 1)
					(thickness 0.15)
				)
				(justify mirror)
			)
		)
		(property "Dielectric" ""
			(at 67.1 208.7 0)
			(layer "B.Fab")
			(hide yes)
			(effects
				(font
					(size 1 1)
					(thickness 0.15)
				)
				(justify mirror)
			)
		)
		(property "License" "Apache-2.0"
			(at 67.1 208.7 0)
			(layer "B.Fab")
			(hide yes)
			(effects
				(font
					(size 1 1)
					(thickness 0.15)
				)
				(justify mirror)
			)
		)
		(property "MPN" "0402B182K500CT"
			(at 67.1 208.7 0)
			(layer "B.Fab")
			(hide yes)
			(effects
				(font
					(size 1 1)
					(thickness 0.15)
				)
				(justify mirror)
			)
		)
		(property "Manufacturer" "Walsin"
			(at 67.1 208.7 0)
			(layer "B.Fab")
			(hide yes)
			(effects
				(font
					(size 1 1)
					(thickness 0.15)
				)
				(justify mirror)
			)
		)
		(property "Val" "1n8"
			(at 67.1 208.7 0)
			(layer "B.Fab")
			(hide yes)
			(effects
				(font
					(size 1 1)
					(thickness 0.15)
				)
				(justify mirror)
			)
		)
		(property "Voltage" ""
			(at 67.1 208.7 0)
			(layer "B.Fab")
			(hide yes)
			(effects
				(font
					(size 1 1)
					(thickness 0.15)
				)
				(justify mirror)
			)
		)
		(sheetname "Supply")
		(sheetfile "supply.kicad_sch")
		(attr exclude_from_pos_files exclude_from_bom dnp)
		(fp_rect
			(start -0.94 0.47)
			(end 0.94 -0.47)
			(stroke
				(width 0.05)
				(type solid)
			)
			(fill no)
			(layer "B.CrtYd")
		)
		(fp_rect
			(start -0.499 0.249)
			(end 0.499 -0.249)
			(stroke
				(width 0.15)
				(type solid)
			)
			(fill no)
			(layer "B.Fab")
		)
		(pad "1" smd roundrect
			(at -0.484 0 270)
			(size 0.59 0.64)
			(layers "B.Cu" "B.Mask" "B.Paste")
			(roundrect_rratio 0.25)
			(net 62 "Net-(U16-CAP)")
			(pintype "passive")
		)
		(pad "2" smd roundrect
			(at 0.484 0 270)
			(size 0.59 0.64)
			(layers "B.Cu" "B.Mask" "B.Paste")
			(roundrect_rratio 0.25)
			(net 5 "GND")
			(pintype "passive")
		)
	)
	(footprint "antmicro-footprints:RENESAS-TDFN-8-1.5x2.0mm_P0.5mm"
		(layer "B.Cu")
		(at 136.3 77.9)
		(descr "8 Lead TDFN Package 1.5 x 2.0 mm (Fused Lead) JEDEC MO-252 ")
		(property "Reference" "U15"
			(at -3.458 -1.192 180)
			(unlocked yes)
			(layer "B.SilkS")
			(effects
				(font
					(size 0.7 0.7)
					(thickness 0.15)
				)
				(justify left bottom mirror)
			)
		)
		(property "Value" "SLG59M1457V"
			(at -9.7 -2.4 180)
			(unlocked yes)
			(layer "B.Fab")
			(effects
				(font
					(size 0.7 0.7)
					(thickness 0.15)
				)
				(justify left bottom mirror)
			)
		)
		(property "Description" "Power distribution switch/load driver"
			(at 0 0 0)
			(layer "F.Fab")
			(hide yes)
			(effects
				(font
					(size 1.27 1.27)
					(thickness 0.15)
				)
			)
		)
		(property "Author" "Antmicro"
			(at 0 0 0)
			(layer "B.Fab")
			(hide yes)
			(effects
				(font
					(size 1 1)
					(thickness 0.15)
				)
				(justify mirror)
			)
		)
		(property "License" "Apache-2.0"
			(at 0 0 0)
			(layer "B.Fab")
			(hide yes)
			(effects
				(font
					(size 1 1)
					(thickness 0.15)
				)
				(justify mirror)
			)
		)
		(property "MPN" "SLG59M1457V"
			(at 0 0 0)
			(layer "B.Fab")
			(hide yes)
			(effects
				(font
					(size 1 1)
					(thickness 0.15)
				)
				(justify mirror)
			)
		)
		(property "Manufacturer" "Dialog Semiconductor"
			(at 0 0 0)
			(layer "B.Fab")
			(hide yes)
			(effects
				(font
					(size 1 1)
					(thickness 0.15)
				)
				(justify mirror)
			)
		)
		(sheetname "Supply")
		(sheetfile "supply.kicad_sch")
		(attr exclude_from_pos_files exclude_from_bom dnp)
		(fp_line
			(start -0.946 1.101)
			(end 0.498 1.101)
			(stroke
				(width 0.15)
				(type solid)
			)
			(layer "B.SilkS")
		)
		(fp_line
			(start -0.5 -1.1)
			(end 0.498 -1.1)
			(stroke
				(width 0.15)
				(type solid)
			)
			(layer "B.SilkS")
		)
		(fp_circle
			(center -1.3 0.75)
			(end -1.249 0.75)
			(stroke
				(width 0.15)
				(type solid)
			)
			(fill yes)
			(layer "B.SilkS")
		)
		(fp_rect
			(start -1.25 1.5)
			(end 1.248 -1.498)
			(stroke
				(width 0.05)
				(type solid)
			)
			(fill no)
			(layer "B.CrtYd")
		)
		(fp_line
			(start -0.777 -1.03)
			(end 0.785 -1.03)
			(stroke
				(width 0.15)
				(type solid)
			)
			(layer "B.Fab")
		)
		(fp_line
			(start -0.777 0.75)
			(end -0.777 -1.03)
			(stroke
				(width 0.15)
				(type solid)
			)
			(layer "B.Fab")
		)
		(fp_line
			(start -0.495 1.031)
			(end -0.777 0.75)
			(stroke
				(width 0.15)
				(type solid)
			)
			(layer "B.Fab")
		)
		(fp_line
			(start 0.785 1.031)
			(end -0.495 1.031)
			(stroke
				(width 0.15)
				(type solid)
			)
			(layer "B.Fab")
		)
		(fp_line
			(start 0.785 1.031)
			(end 0.785 -1.03)
			(stroke
				(width 0.15)
				(type solid)
			)
			(layer "B.Fab")
		)
		(pad "1" smd rect
			(at -0.527 0.75 90)
			(size 0.28 0.85)
			(layers "B.Cu" "B.Mask" "B.Paste")
			(net 459 "3V3_SYS")
			(pinfunction "VDD")
			(pintype "power_in")
		)
		(pad "2" smd rect
			(at -0.576 0.25 90)
			(size 0.28 0.75)
			(layers "B.Cu" "B.Mask" "B.Paste")
			(net 263 "Net-(U15-ON)")
			(pinfunction "ON")
			(pintype "input")
		)
		(pad "3" smd custom
			(at -0.576 -0.248 90)
			(size 0.28 0.75)
			(layers "B.Cu" "B.Mask" "B.Paste")
			(net 461 "1V1_SYS")
			(pinfunction "IN")
			(pintype "power_in")
			(zone_connect 2)
			(options
				(clearance outline)
				(anchor rect)
			)
			(primitives
				(gr_poly
					(pts
						(xy -0.14 0.375) (xy -0.14 -0.05) (xy 0.64 -0.05) (xy 0.64 0.375)
					)
					(width 0)
					(fill yes)
				)
				(gr_rect
					(start 0.36 -0.375)
					(end 0.64 0.375)
					(width 0)
					(fill yes)
				)
			)
		)
		(pad "5" smd custom
			(at 0.574 -0.748 270)
			(size 0.28 0.75)
			(layers "B.Cu" "B.Mask" "B.Paste")
			(net 273 "1V1_DDR")
			(pinfunction "OUT")
			(pintype "power_out")
			(zone_connect 2)
			(options
				(clearance outline)
				(anchor rect)
			)
			(primitives
				(gr_poly
					(pts
						(xy -0.14 0.375) (xy -0.14 -0.05) (xy 0.64 -0.05) (xy 0.64 0.375)
					)
					(width 0)
					(fill yes)
				)
				(gr_rect
					(start 0.36 -0.375)
					(end 0.64 0.375)
					(width 0)
					(fill yes)
				)
			)
		)
		(pad "7" smd rect
			(at 0.574 0.25 90)
			(size 0.28 0.75)
			(layers "B.Cu" "B.Mask" "B.Paste")
			(net 60 "Net-(U15-CAP)")
			(pinfunction "CAP")
			(pintype "input")
		)
		(pad "8" smd rect
			(at 0.574 0.75 90)
			(size 0.28 0.75)
			(layers "B.Cu" "B.Mask" "B.Paste")
			(net 5 "GND")
			(pinfunction "GND")
			(pintype "passive")
		)
	)
	(footprint "antmicro-footprints:SOT-23-3"
		(layer "B.Cu")
		(at 122.7 66.55 90)
		(property "Reference" "Q13"
			(at 1.15 -1.8 90)
			(layer "B.SilkS")
			(effects
				(font
					(size 0.7 0.7)
					(thickness 0.15)
				)
				(justify left bottom mirror)
			)
		)
		(property "Value" "BSS123"
			(at -1.9 -2.7 270)
			(layer "B.Fab")
			(effects
				(font
					(size 0.7 0.7)
					(thickness 0.15)
				)
				(justify left bottom mirror)
			)
		)
		(property "Author" "Antmicro"
			(at 189.25 -56.15 0)
			(layer "B.Fab")
			(hide yes)
			(effects
				(font
					(size 1 1)
					(thickness 0.15)
				)
				(justify mirror)
			)
		)
		(property "License" "Apache-2.0"
			(at 189.25 -56.15 0)
			(layer "B.Fab")
			(hide yes)
			(effects
				(font
					(size 1 1)
					(thickness 0.15)
				)
				(justify mirror)
			)
		)
		(property "MPN" "BSS123"
			(at 189.25 -56.15 0)
			(layer "B.Fab")
			(hide yes)
			(effects
				(font
					(size 1 1)
					(thickness 0.15)
				)
				(justify mirror)
			)
		)
		(property "Manufacturer" "ON Semiconductor"
			(at 189.25 -56.15 0)
			(layer "B.Fab")
			(hide yes)
			(effects
				(font
					(size 1 1)
					(thickness 0.15)
				)
				(justify mirror)
			)
		)
		(sheetname "Supply")
		(sheetfile "supply.kicad_sch")
		(attr exclude_from_pos_files exclude_from_bom dnp)
		(fp_line
			(start 0.7 -1.5)
			(end -0.7 -1.5)
			(stroke
				(width 0.15)
				(type solid)
			)
			(layer "B.SilkS")
		)
		(fp_line
			(start -0.7 -1.5)
			(end -0.7 -1.35)
			(stroke
				(width 0.15)
				(type solid)
			)
			(layer "B.SilkS")
		)
		(fp_line
			(start 0.7 -0.4)
			(end 0.7 -1.5)
			(stroke
				(width 0.15)
				(type solid)
			)
			(layer "B.SilkS")
		)
		(fp_line
			(start 0.7 0.4)
			(end 0.7 1.5)
			(stroke
				(width 0.15)
				(type solid)
			)
			(layer "B.SilkS")
		)
		(fp_line
			(start -0.85 1.35)
			(end -0.7 1.5)
			(stroke
				(width 0.15)
				(type solid)
			)
			(layer "B.SilkS")
		)
		(fp_line
			(start -1.45 1.35)
			(end -0.85 1.35)
			(stroke
				(width 0.15)
				(type solid)
			)
			(layer "B.SilkS")
		)
		(fp_line
			(start 0.7 1.5)
			(end -0.7 1.5)
			(stroke
				(width 0.15)
				(type solid)
			)
			(layer "B.SilkS")
		)
		(fp_line
			(start 0.85 -1.65)
			(end -0.85 -1.65)
			(stroke
				(width 0.05)
				(type solid)
			)
			(layer "B.CrtYd")
		)
		(fp_line
			(start -0.85 -1.65)
			(end -0.85 -1.4)
			(stroke
				(width 0.05)
				(type solid)
			)
			(layer "B.CrtYd")
		)
		(fp_line
			(start -0.85 -1.4)
			(end -1.75 -1.4)
			(stroke
				(width 0.05)
				(type solid)
			)
			(layer "B.CrtYd")
		)
		(fp_line
			(start -1.75 -1.4)
			(end -1.75 -0.5)
			(stroke
				(width 0.05)
				(type solid)
			)
			(layer "B.CrtYd")
		)
		(fp_line
			(start -0.85 -0.5)
			(end -0.85 0.5)
			(stroke
				(width 0.05)
				(type solid)
			)
			(layer "B.CrtYd")
		)
		(fp_line
			(start -1.75 -0.5)
			(end -0.85 -0.5)
			(stroke
				(width 0.05)
				(type solid)
			)
			(layer "B.CrtYd")
		)
		(fp_line
			(start 1.75 -0.45)
			(end 0.85 -0.45)
			(stroke
				(width 0.05)
				(type solid)
			)
			(layer "B.CrtYd")
		)
		(fp_line
			(start 0.85 -0.45)
			(end 0.85 -1.65)
			(stroke
				(width 0.05)
				(type solid)
			)
			(layer "B.CrtYd")
		)
		(fp_line
			(start 1.75 0.45)
			(end 1.75 -0.45)
			(stroke
				(width 0.05)
				(type solid)
			)
			(layer "B.CrtYd")
		)
		(fp_line
			(start 0.825 0.45)
			(end 1.75 0.45)
			(stroke
				(width 0.05)
				(type solid)
			)
			(layer "B.CrtYd")
		)
		(fp_line
			(start -0.85 0.5)
			(end -1.75 0.5)
			(stroke
				(width 0.05)
				(type solid)
			)
			(layer "B.CrtYd")
		)
		(fp_line
			(start -1.75 0.5)
			(end -1.75 1.4)
			(stroke
				(width 0.05)
				(type solid)
			)
			(layer "B.CrtYd")
		)
		(fp_line
			(start -0.9 1.4)
			(end -1.75 1.4)
			(stroke
				(width 0.05)
				(type solid)
			)
			(layer "B.CrtYd")
		)
		(fp_line
			(start 0.825 1.6)
			(end 0.825 0.45)
			(stroke
				(width 0.05)
				(type solid)
			)
			(layer "B.CrtYd")
		)
		(fp_line
			(start -0.9 1.6)
			(end -0.9 1.4)
			(stroke
				(width 0.05)
				(type solid)
			)
			(layer "B.CrtYd")
		)
		(fp_line
			(start -0.9 1.6)
			(end 0.825 1.6)
			(stroke
				(width 0.05)
				(type solid)
			)
			(layer "B.CrtYd")
		)
		(fp_line
			(start 0.688 -1.519)
			(end 0.688 1.52)
			(stroke
				(width 0.15)
				(type solid)
			)
			(layer "B.Fab")
		)
		(fp_line
			(start -0.712 -1.519)
			(end 0.688 -1.519)
			(stroke
				(width 0.15)
				(type solid)
			)
			(layer "B.Fab")
		)
		(fp_line
			(start -0.712 1.325)
			(end -0.712 -1.523)
			(stroke
				(width 0.15)
				(type solid)
			)
			(layer "B.Fab")
		)
		(fp_line
			(start -0.437 1.526)
			(end -0.712 1.325)
			(stroke
				(width 0.15)
				(type solid)
			)
			(layer "B.Fab")
		)
		(fp_line
			(start -0.437 1.526)
			(end 0.688 1.526)
			(stroke
				(width 0.15)
				(type solid)
			)
			(layer "B.Fab")
		)
		(pad "1" smd roundrect
			(at -1.1 0.951 90)
			(size 1 0.6)
			(layers "B.Cu" "B.Mask" "B.Paste")
			(roundrect_rratio 0.15)
			(net 238 "Net-(Q13-G)")
			(pinfunction "G")
			(pintype "bidirectional")
		)
		(pad "2" smd roundrect
			(at -1.1 -0.949 90)
			(size 1 0.6)
			(layers "B.Cu" "B.Mask" "B.Paste")
			(roundrect_rratio 0.15)
			(net 5 "GND")
			(pinfunction "S")
			(pintype "bidirectional")
		)
		(pad "3" smd roundrect
			(at 1.1 0.0005 90)
			(size 1 0.6)
			(layers "B.Cu" "B.Mask" "B.Paste")
			(roundrect_rratio 0.15)
			(net 636 "/Supply/0V6_EN")
			(pinfunction "D")
			(pintype "bidirectional")
		)
	)
	(footprint "antmicro-footprints:C_0603_1608Metric"
		(layer "B.Cu")
		(at 154.15 66.5 90)
		(descr "Capacitor SMD 0603")
		(tags "capacitor 0603")
		(property "Reference" "C150"
			(at 1.3 1.35 270)
			(layer "B.SilkS")
			(effects
				(font
					(size 0.7 0.7)
					(thickness 0.15)
				)
				(justify left bottom mirror)
			)
		)
		(property "Value" "C_10n_0603"
			(at 0 -1.6 270)
			(layer "B.Fab")
			(effects
				(font
					(size 0.7 0.7)
					(thickness 0.15)
				)
				(justify left bottom mirror)
			)
		)
		(property "Description" " "
			(at 0 0 90)
			(layer "F.Fab")
			(hide yes)
			(effects
				(font
					(size 1.27 1.27)
					(thickness 0.15)
				)
			)
		)
		(property "Author" "Antmicro"
			(at 220.65 -87.65 0)
			(layer "B.Fab")
			(hide yes)
			(effects
				(font
					(size 1 1)
					(thickness 0.15)
				)
				(justify mirror)
			)
		)
		(property "Dielectric" ""
			(at 220.65 -87.65 0)
			(layer "B.Fab")
			(hide yes)
			(effects
				(font
					(size 1 1)
					(thickness 0.15)
				)
				(justify mirror)
			)
		)
		(property "License" "Apache-2.0"
			(at 220.65 -87.65 0)
			(layer "B.Fab")
			(hide yes)
			(effects
				(font
					(size 1 1)
					(thickness 0.15)
				)
				(justify mirror)
			)
		)
		(property "MPN" "06031C103JAT2A"
			(at 220.65 -87.65 0)
			(layer "B.Fab")
			(hide yes)
			(effects
				(font
					(size 1 1)
					(thickness 0.15)
				)
				(justify mirror)
			)
		)
		(property "Manufacturer" "AVX"
			(at 220.65 -87.65 0)
			(layer "B.Fab")
			(hide yes)
			(effects
				(font
					(size 1 1)
					(thickness 0.15)
				)
				(justify mirror)
			)
		)
		(property "Val" "10n"
			(at 220.65 -87.65 0)
			(layer "B.Fab")
			(hide yes)
			(effects
				(font
					(size 1 1)
					(thickness 0.15)
				)
				(justify mirror)
			)
		)
		(property "Voltage" ""
			(at 220.65 -87.65 0)
			(layer "B.Fab")
			(hide yes)
			(effects
				(font
					(size 1 1)
					(thickness 0.15)
				)
				(justify mirror)
			)
		)
		(sheetname "Supply")
		(sheetfile "supply.kicad_sch")
		(attr smd)
		(fp_line
			(start -0.3 -0.3)
			(end 0.3 -0.3)
			(stroke
				(width 0.15)
				(type solid)
			)
			(layer "B.SilkS")
		)
		(fp_line
			(start -0.3 0.3)
			(end 0.3 0.3)
			(stroke
				(width 0.15)
				(type solid)
			)
			(layer "B.SilkS")
		)
		(fp_rect
			(start -1.24 0.7)
			(end 1.24 -0.7)
			(stroke
				(width 0.05)
				(type solid)
			)
			(fill no)
			(layer "B.CrtYd")
		)
		(fp_rect
			(start -0.8 0.4)
			(end 0.8 -0.4)
			(stroke
				(width 0.15)
				(type solid)
			)
			(fill no)
			(layer "B.Fab")
		)
		(pad "1" smd roundrect
			(at -0.7 0 90)
			(size 0.6 0.8)
			(layers "B.Cu" "B.Mask" "B.Paste")
			(roundrect_rratio 0.2)
			(net 641 "1V8_DDR")
			(pintype "passive")
		)
		(pad "2" smd roundrect
			(at 0.7 0 90)
			(size 0.6 0.8)
			(layers "B.Cu" "B.Mask" "B.Paste")
			(roundrect_rratio 0.2)
			(net 5 "GND")
			(pintype "passive")
		)
	)
	(gr_line
		(start 217 46)
		(end 217 75)
		(stroke
			(width 0.12)
			(type solid)
		)
		(layer "Edge.Cuts")
	)
	(gr_line
		(start 217 75)
		(end 217 136)
		(stroke
			(width 0.12)
			(type solid)
		)
		(layer "Edge.Cuts")
	)
	(gr_line
		(start 107 46)
		(end 217 46)
		(stroke
			(width 0.12)
			(type solid)
		)
		(layer "Edge.Cuts")
	)
	(gr_line
		(start 107 136)
		(end 107 46)
		(stroke
			(width 0.12)
			(type solid)
		)
		(layer "Edge.Cuts")
	)
	(gr_line
		(start 217 136)
		(end 107 136)
		(stroke
			(width 0.12)
			(type solid)
		)
		(layer "Edge.Cuts")
	)
	(gr_text "Rev. 1.1.5\n"
		(at 195 55.5 0)
		(layer "F.Cu")
		(effects
			(font
				(size 0.85 0.85)
				(thickness 0.18)
			)
			(justify left)
		)
	)
	(gr_text "LPDDR4 Test Board\n"
		(at 195 54 0)
		(layer "F.Cu")
		(effects
			(font
				(size 0.85 0.85)
				(thickness 0.18)
			)
			(justify left)
		)
	)
	(gr_text "02/2024"
		(at 203 55.5 0)
		(layer "F.Cu")
		(effects
			(font
				(size 0.85 0.85)
				(thickness 0.18)
			)
			(justify left)
		)
	)
	(via
		(at 216.34 83.99396)
		(size 0.5)
		(drill 0.2)
		(layers "F.Cu" "B.Cu")
		(net 0)
	)
	(via
		(at 216.34 85.470564)
		(size 0.5)
		(drill 0.2)
		(layers "F.Cu" "B.Cu")
		(net 0)
	)
	(via
		(at 216.336328 82.509422)
		(size 0.5)
		(drill 0.2)
		(layers "F.Cu" "B.Cu")
		(net 0)
	)
	(via
		(at 216.34 81.033396)
		(size 0.5)
		(drill 0.2)
		(layers "F.Cu" "B.Cu")
		(net 0)
	)
	(via
		(at 216.34 86.947168)
		(size 0.5)
		(drill 0.2)
		(layers "F.Cu" "B.Cu")
		(net 0)
	)
	(via
		(at 216.34 79.556792)
		(size 0.5)
		(drill 0.2)
		(layers "F.Cu" "B.Cu")
		(net 0)
	)
	(via
		(at 216.34 88.423772)
		(size 0.5)
		(drill 0.2)
		(layers "F.Cu" "B.Cu")
		(net 0)
	)
	(segment
		(start 136.035 112.55)
		(end 135.585 112.1)
		(width 0.2)
		(layer "F.Cu")
		(net 2)
	)
	(segment
		(start 143 102.825)
		(end 143.165 102.66)
		(width 0.2)
		(layer "F.Cu")
		(net 2)
	)
	(segment
		(start 135.585 103.115)
		(end 135.6 103.1)
		(width 0.2)
		(layer "F.Cu")
		(net 2)
	)
	(segment
		(start 135.585 112.1)
		(end 135.585 111.485)
		(width 0.2)
		(layer "F.Cu")
		(net 2)
	)
	(segment
		(start 137.9 112.55)
		(end 136.035 112.55)
		(width 0.2)
		(layer "F.Cu")
		(net 2)
	)
	(segment
		(start 135.585 103.752157)
		(end 135.585 103.115)
		(width 0.2)
		(layer "F.Cu")
		(net 2)
	)
	(segment
		(start 143.165 102.66)
		(end 143.85 102.66)
		(width 0.15)
		(layer "F.Cu")
		(net 2)
	)
	(segment
		(start 138 112.45)
		(end 137.9 112.55)
		(width 0.2)
		(layer "F.Cu")
		(net 2)
	)
	(segment
		(start 138 111.7875)
		(end 138 112.45)
		(width 0.2)
		(layer "F.Cu")
		(net 2)
	)
	(segment
		(start 136.432843 104.6)
		(end 135.585 103.752157)
		(width 0.2)
		(layer "F.Cu")
		(net 2)
	)
	(segment
		(start 136.8125 104.6)
		(end 136.432843 104.6)
		(width 0.2)
		(layer "F.Cu")
		(net 2)
	)
	(segment
		(start 143 103.9125)
		(end 143 102.825)
		(width 0.2)
		(layer "F.Cu")
		(net 2)
	)
	(segment
		(start 135.585 111.485)
		(end 135.5 111.4)
		(width 0.2)
		(layer "F.Cu")
		(net 2)
	)
	(via
		(at 135.6 103.1)
		(size 0.5)
		(drill 0.2)
		(layers "F.Cu" "B.Cu")
		(net 2)
	)
	(via
		(at 143.86 102.67)
		(size 0.5)
		(drill 0.2)
		(layers "F.Cu" "B.Cu")
		(net 2)
	)
	(via
		(at 135.5 111.4)
		(size 0.5)
		(drill 0.2)
		(layers "F.Cu" "B.Cu")
		(net 2)
	)
	(segment
		(start 135.458485 112.95)
		(end 134.211328 114.197157)
		(width 0.15)
		(layer "F.Cu")
		(net 3)
	)
	(segment
		(start 138.5 111.7875)
		(end 138.5 112.75)
		(width 0.15)
		(layer "F.Cu")
		(net 3)
	)
	(segment
		(start 134.201328 115.512157)
		(end 134.211328 115.522157)
		(width 0.2)
		(layer "F.Cu")
		(net 3)
	)
	(segment
		(start 138.3 112.95)
		(end 135.458485 112.95)
		(width 0.15)
		(layer "F.Cu")
		(net 3)
	)
	(segment
		(start 134.211328 115.522157)
		(end 134.211328 114.197157)
		(width 0.15)
		(layer "F.Cu")
		(net 3)
	)
	(segment
		(start 132.661328 115.512157)
		(end 134.201328 115.512157)
		(width 0.2)
		(layer "F.Cu")
		(net 3)
	)
	(segment
		(start 138.5 112.75)
		(end 138.3 112.95)
		(width 0.15)
		(layer "F.Cu")
		(net 3)
	)
	(segment
		(start 137.536328 117.857157)
		(end 136.046328 117.857157)
		(width 0.2)
		(layer "F.Cu")
		(net 4)
	)
	(segment
		(start 136.046328 117.857157)
		(end 136.011328 117.822157)
		(width 0.2)
		(layer "F.Cu")
		(net 4)
	)
	(segment
		(start 135.161328 115.211328)
		(end 135.161328 116.872157)
		(width 0.1)
		(layer "F.Cu")
		(net 4)
	)
	(segment
		(start 135.161328 115.111328)
		(end 135.161328 115.211328)
		(width 0.15)
		(layer "F.Cu")
		(net 4)
	)
	(segment
		(start 136.011328 117.822157)
		(end 136.011328 117.722158)
		(width 0.15)
		(layer "F.Cu")
		(net 4)
	)
	(segment
		(start 138.45 113.3)
		(end 135.8 113.3)
		(width 0.15)
		(layer "F.Cu")
		(net 4)
	)
	(segment
		(start 136.011328 117.722158)
		(end 135.444585 117.155415)
		(width 0.15)
		(layer "F.Cu")
		(net 4)
	)
	(segment
		(start 135.161328 113.997157)
		(end 135.161328 115.211328)
		(width 0.1)
		(layer "F.Cu")
		(net 4)
	)
	(segment
		(start 135.161328 115.111328)
		(end 135.161328 116.872158)
		(width 0.15)
		(layer "F.Cu")
		(net 4)
	)
	(segment
		(start 135.161328 113.938672)
		(end 135.161328 115.111328)
		(width 0.15)
		(layer "F.Cu")
		(net 4)
	)
	(segment
		(start 139 111.7875)
		(end 139 112.75)
		(width 0.15)
		(layer "F.Cu")
		(net 4)
	)
	(segment
		(start 135.8 113.3)
		(end 135.161328 113.938672)
		(width 0.15)
		(layer "F.Cu")
		(net 4)
	)
	(segment
		(start 135.161328 116.872157)
		(end 135.444585 117.155415)
		(width 0.1)
		(layer "F.Cu")
		(net 4)
	)
	(segment
		(start 139 112.75)
		(end 138.45 113.3)
		(width 0.15)
		(layer "F.Cu")
		(net 4)
	)
	(segment
		(start 135.161328 116.872158)
		(end 135.444585 117.155415)
		(width 0.15)
		(layer "F.Cu")
		(net 4)
	)
	(segment
		(start 160.786328 70.597157)
		(end 160.786328 69.247157)
		(width 0.1)
		(layer "F.Cu")
		(net 5)
	)
	(segment
		(start 184.361328 62.747157)
		(end 184.361328 59.422157)
		(width 0.2)
		(layer "F.Cu")
		(net 5)
	)
	(segment
		(start 160.536327 89.497156)
		(end 160.036327 89.997156)
		(width 0.15)
		(layer "F.Cu")
		(net 5)
	)
	(segment
		(start 159.536329 106.497156)
		(end 159.036329 106.997157)
		(width 0.15)
		(layer "F.Cu")
		(net 5)
	)
	(segment
		(start 158.536328 103.497156)
		(end 159.036328 103.997155)
		(width 0.15)
		(layer "F.Cu")
		(net 5)
	)
	(segment
		(start 158.536327 93.497158)
		(end 159.036327 93.997157)
		(width 0.15)
		(layer "F.Cu")
		(net 5)
	)
	(segment
		(start 159.536327 96.497156)
		(end 159.036328 96.997156)
		(width 0.15)
		(layer "F.Cu")
		(net 5)
	)
	(segment
		(start 172.536329 105.497156)
		(end 173.036329 105.997157)
		(width 0.15)
		(layer "F.Cu")
		(net 5)
	)
	(segment
		(start 168.786328 70.597157)
		(end 168.786328 69.247157)
		(width 0.1)
		(layer "F.Cu")
		(net 5)
	)
	(segment
		(start 179.536327 106.497158)
		(end 179.036327 105.997157)
		(width 0.15)
		(layer "F.Cu")
		(net 5)
	)
	(segment
		(start 159.536328 86.497156)
		(end 159.036328 85.997156)
		(width 0.15)
		(layer "F.Cu")
		(net 5)
	)
	(segment
		(start 168.536329 96.497156)
		(end 168.036329 96.997156)
		(width 0.15)
		(layer "F.Cu")
		(net 5)
	)
	(segment
		(start 170.536329 95.497156)
		(end 171.036329 94.997156)
		(width 0.15)
		(layer "F.Cu")
		(net 5)
	)
	(segment
		(start 169.536329 95.497156)
		(end 169.036329 94.997156)
		(width 0.15)
		(layer "F.Cu")
		(net 5)
	)
	(segment
		(start 169.536329 96.497157)
		(end 170.036329 96.997157)
		(width 0.15)
		(layer "F.Cu")
		(net 5)
	)
	(segment
		(start 168.536329 95.497157)
		(end 168.036329 94.997157)
		(width 0.15)
		(layer "F.Cu")
		(net 5)
	)
	(segment
		(start 177.536329 91.497157)
		(end 178.036329 90.997157)
		(width 0.15)
		(layer "F.Cu")
		(net 5)
	)
	(segment
		(start 177.536329 89.497157)
		(end 178.036329 88.997157)
		(width 0.15)
		(layer "F.Cu")
		(net 5)
	)
	(segment
		(start 176.536329 91.497157)
		(end 177.036329 90.997157)
		(width 0.15)
		(layer "F.Cu")
		(net 5)
	)
	(segment
		(start 175.536329 91.497157)
		(end 176.036329 90.997156)
		(width 0.15)
		(layer "F.Cu")
		(net 5)
	)
	(segment
		(start 175.536328 89.497157)
		(end 176.036328 88.997157)
		(width 0.15)
		(layer "F.Cu")
		(net 5)
	)
	(segment
		(start 175.536327 94.497156)
		(end 175.036328 93.997157)
		(width 0.15)
		(layer "F.Cu")
		(net 5)
	)
	(segment
		(start 174.536328 91.497156)
		(end 174.036327 90.997156)
		(width 0.15)
		(layer "F.Cu")
		(net 5)
	)
	(segment
		(start 173.536329 89.497157)
		(end 174.036329 88.997157)
		(width 0.15)
		(layer "F.Cu")
		(net 5)
	)
	(segment
		(start 172.536329 89.497157)
		(end 173.036329 88.997157)
		(width 0.15)
		(layer "F.Cu")
		(net 5)
	)
	(segment
		(start 172.536329 95.497157)
		(end 173.036329 94.997157)
		(width 0.15)
		(layer "F.Cu")
		(net 5)
	)
	(segment
		(start 172.53633 87.497157)
		(end 173.036329 86.997157)
		(width 0.15)
		(layer "F.Cu")
		(net 5)
	)
	(segment
		(start 172.536329 88.497156)
		(end 173.036329 87.997156)
		(width 0.15)
		(layer "F.Cu")
		(net 5)
	)
	(segment
		(start 171.536329 92.497157)
		(end 172.036329 91.997157)
		(width 0.15)
		(layer "F.Cu")
		(net 5)
	)
	(segment
		(start 171.536329 94.497157)
		(end 172.036329 93.997157)
		(width 0.15)
		(layer "F.Cu")
		(net 5)
	)
	(segment
		(start 170.536329 93.497157)
		(end 171.036329 92.997157)
		(width 0.15)
		(layer "F.Cu")
		(net 5)
	)
	(segment
		(start 170.53633 89.497157)
		(end 171.036329 88.997157)
		(width 0.15)
		(layer "F.Cu")
		(net 5)
	)
	(segment
		(start 169.536329 92.497157)
		(end 170.036329 91.997157)
		(width 0.15)
		(layer "F.Cu")
		(net 5)
	)
	(segment
		(start 169.536329 94.497157)
		(end 170.036329 93.997157)
		(width 0.15)
		(layer "F.Cu")
		(net 5)
	)
	(segment
		(start 164.536328 91.497157)
		(end 164.036329 90.997157)
		(width 0.15)
		(layer "F.Cu")
		(net 5)
	)
	(segment
		(start 166.536329 87.497157)
		(end 166.036329 86.997157)
		(width 0.15)
		(layer "F.Cu")
		(net 5)
	)
	(segment
		(start 162.536329 95.497156)
		(end 162.036329 94.997156)
		(width 0.15)
		(layer "F.Cu")
		(net 5)
	)
	(segment
		(start 166.536329 95.497156)
		(end 166.036329 94.997156)
		(width 0.15)
		(layer "F.Cu")
		(net 5)
	)
	(segment
		(start 166.536329 93.497157)
		(end 166.036329 92.997157)
		(width 0.15)
		(layer "F.Cu")
		(net 5)
	)
	(segment
		(start 168.536329 93.497156)
		(end 168.036329 92.997156)
		(width 0.15)
		(layer "F.Cu")
		(net 5)
	)
	(segment
		(start 165.536329 94.497157)
		(end 165.036329 93.997157)
		(width 0.15)
		(layer "F.Cu")
		(net 5)
	)
	(segment
		(start 165.536329 92.497157)
		(end 165.036329 91.997157)
		(width 0.15)
		(layer "F.Cu")
		(net 5)
	)
	(segment
		(start 167.536329 95.497156)
		(end 167.036329 94.997156)
		(width 0.15)
		(layer "F.Cu")
		(net 5)
	)
	(segment
		(start 167.536329 92.497157)
		(end 167.036329 91.997157)
		(width 0.15)
		(layer "F.Cu")
		(net 5)
	)
	(segment
		(start 167.536329 90.497157)
		(end 167.036329 89.997157)
		(width 0.15)
		(layer "F.Cu")
		(net 5)
	)
	(segment
		(start 167.536329 94.497157)
		(end 167.036329 93.997157)
		(width 0.15)
		(layer "F.Cu")
		(net 5)
	)
	(segment
		(start 163.536329 88.497156)
		(end 163.036329 87.997156)
		(width 0.15)
		(layer "F.Cu")
		(net 5)
	)
	(segment
		(start 167.536329 100.497157)
		(end 167.036329 100.997157)
		(width 0.15)
		(layer "F.Cu")
		(net 5)
	)
	(segment
		(start 167.536329 96.497157)
		(end 167.036329 96.997157)
		(width 0.15)
		(layer "F.Cu")
		(net 5)
	)
	(segment
		(start 166.536329 99.497156)
		(end 166.036329 99.997156)
		(width 0.15)
		(layer "F.Cu")
		(net 5)
	)
	(segment
		(start 165.536329 98.497157)
		(end 165.036329 98.997157)
		(width 0.15)
		(layer "F.Cu")
		(net 5)
	)
	(segment
		(start 165.536329 96.497157)
		(end 165.036329 96.997157)
		(width 0.15)
		(layer "F.Cu")
		(net 5)
	)
	(segment
		(start 165.536327 104.497156)
		(end 166.036328 104.997156)
		(width 0.15)
		(layer "F.Cu")
		(net 5)
	)
	(segment
		(start 167.536329 98.497157)
		(end 167.036329 98.997157)
		(width 0.15)
		(layer "F.Cu")
		(net 5)
	)
	(segment
		(start 168.536329 97.497156)
		(end 168.036329 97.997156)
		(width 0.15)
		(layer "F.Cu")
		(net 5)
	)
	(segment
		(start 168.536329 99.497157)
		(end 168.036329 99.997157)
		(width 0.15)
		(layer "F.Cu")
		(net 5)
	)
	(segment
		(start 166.536329 97.497157)
		(end 166.036329 97.997157)
		(width 0.15)
		(layer "F.Cu")
		(net 5)
	)
	(segment
		(start 168.536328 103.497158)
		(end 168.036328 102.997158)
		(width 0.15)
		(layer "F.Cu")
		(net 5)
	)
	(segment
		(start 163.536328 98.497158)
		(end 163.036328 97.997158)
		(width 0.15)
		(layer "F.Cu")
		(net 5)
	)
	(segment
		(start 161.536328 102.497158)
		(end 161.036328 101.997159)
		(width 0.15)
		(layer "F.Cu")
		(net 5)
	)
	(segment
		(start 171.536329 96.497157)
		(end 172.036329 96.997157)
		(width 0.15)
		(layer "F.Cu")
		(net 5)
	)
	(segment
		(start 171.536329 98.497157)
		(end 172.036329 98.997157)
		(width 0.15)
		(layer "F.Cu")
		(net 5)
	)
	(segment
		(start 169.536329 98.497157)
		(end 170.036329 98.997157)
		(width 0.15)
		(layer "F.Cu")
		(net 5)
	)
	(segment
		(start 171.536327 102.497158)
		(end 171.036327 101.997157)
		(width 0.15)
		(layer "F.Cu")
		(net 5)
	)
	(segment
		(start 175.536327 104.497158)
		(end 175.036327 103.997157)
		(width 0.15)
		(layer "F.Cu")
		(net 5)
	)
	(segment
		(start 170.536329 99.497156)
		(end 171.036329 99.997156)
		(width 0.15)
		(layer "F.Cu")
		(net 5)
	)
	(segment
		(start 173.536329 98.497157)
		(end 174.036329 98.997157)
		(width 0.15)
		(layer "F.Cu")
		(net 5)
	)
	(segment
		(start 170.536329 97.497157)
		(end 171.036329 97.997157)
		(width 0.15)
		(layer "F.Cu")
		(net 5)
	)
	(segment
		(start 174.536327 101.497157)
		(end 174.036327 100.997157)
		(width 0.15)
		(layer "F.Cu")
		(net 5)
	)
	(segment
		(start 177.536327 100.497157)
		(end 177.036328 99.997157)
		(width 0.15)
		(layer "F.Cu")
		(net 5)
	)
	(segment
		(start 174.536329 87.497157)
		(end 175.036329 86.997157)
		(width 0.15)
		(layer "F.Cu")
		(net 5)
	)
	(segment
		(start 174.536329 88.497157)
		(end 175.036329 87.997157)
		(width 0.15)
		(layer "F.Cu")
		(net 5)
	)
	(segment
		(start 176.536329 87.497157)
		(end 177.03633 86.997157)
		(width 0.15)
		(layer "F.Cu")
		(net 5)
	)
	(segment
		(start 176.536329 88.497156)
		(end 177.036329 87.997156)
		(width 0.15)
		(layer "F.Cu")
		(net 5)
	)
	(segment
		(start 178.536329 93.497156)
		(end 179.036329 92.997157)
		(width 0.15)
		(layer "F.Cu")
		(net 5)
	)
	(segment
		(start 179.036329 92.997157)
		(end 180.536329 92.997156)
		(width 0.15)
		(layer "F.Cu")
		(net 5)
	)
	(segment
		(start 179.036329 90.997156)
		(end 180.536328 90.997156)
		(width 0.15)
		(layer "F.Cu")
		(net 5)
	)
	(segment
		(start 178.536329 91.497157)
		(end 179.036329 90.997156)
		(width 0.15)
		(layer "F.Cu")
		(net 5)
	)
	(segment
		(start 179.536329 91.497157)
		(end 181.536329 91.497157)
		(width 0.15)
		(layer "F.Cu")
		(net 5)
	)
	(segment
		(start 179.036329 102.997157)
		(end 180.536329 102.997157)
		(width 0.15)
		(layer "F.Cu")
		(net 5)
	)
	(segment
		(start 178.536329 103.497157)
		(end 179.036329 102.997157)
		(width 0.15)
		(layer "F.Cu")
		(net 5)
	)
	(segment
		(start 149.677599 97.255201)
		(end 150.177599 97.7552)
		(width 0.15)
		(layer "F.Cu")
		(net 5)
	)
	(segment
		(start 161.028 99.9918)
		(end 160.528 99.4918)
		(width 0.15)
		(layer "F.Cu")
		(net 5)
	)
	(segment
		(start 150.666558 99.295073)
		(end 151.166557 98.795073)
		(width 0.15)
		(layer "F.Cu")
		(net 5)
	)
	(segment
		(start 152.709401 95.276799)
		(end 152.209401 94.7768)
		(width 0.15)
		(layer "F.Cu")
		(net 5)
	)
	(segment
		(start 176.536329 97.497156)
		(end 177.036329 97.997156)
		(width 0.15)
		(layer "F.Cu")
		(net 5)
	)
	(segment
		(start 196.536328 66.247157)
		(end 196.536328 65.497157)
		(width 0.2)
		(layer "F.Cu")
		(net 5)
	)
	(segment
		(start 200.936328 66.247157)
		(end 200.936328 65.497157)
		(width 0.2)
		(layer "F.Cu")
		(net 5)
	)
	(segment
		(start 191.386328 75.647157)
		(end 191.386328 76.447157)
		(width 0.1)
		(layer "F.Cu")
		(net 5)
	)
	(segment
		(start 205.336328 66.247157)
		(end 205.336328 65.497157)
		(width 0.2)
		(layer "F.Cu")
		(net 5)
	)
	(segment
		(start 192.136328 66.247157)
		(end 192.136328 65.497157)
		(width 0.2)
		(layer "F.Cu")
		(net 5)
	)
	(segment
		(start 163.036328 77.513672)
		(end 163.05 77.5)
		(width 0.2)
		(layer "F.Cu")
		(net 5)
	)
	(segment
		(start 136.011328 114.397157)
		(end 136.036328 114.372157)
		(width 0.2)
		(layer "F.Cu")
		(net 5)
	)
	(segment
		(start 137.801328 113.969157)
		(end 137.314328 113.969157)
		(width 0.2)
		(layer "F.Cu")
		(net 5)
	)
	(segment
		(start 169.536327 106.497158)
		(end 170.036327 105.997157)
		(width 0.15)
		(layer "F.Cu")
		(net 5)
	)
	(segment
		(start 199.3 85.5)
		(end 198.9 85.1)
		(width 0.1)
		(layer "F.Cu")
		(net 5)
	)
	(segment
		(start 169.536328 86.497157)
		(end 169.036328 86.997157)
		(width 0.15)
		(layer "F.Cu")
		(net 5)
	)
	(segment
		(start 134.615 108.1)
		(end 134.615 108.785)
		(width 0.2)
		(layer "F.Cu")
		(net 5)
	)
	(segment
		(start 143.0325 91.6)
		(end 143.0325 91)
		(width 0.2)
		(layer "F.Cu")
		(net 5)
	)
	(segment
		(start 206.586328 103.289306)
		(end 206.586328 102.720008)
		(width 0.2)
		(layer "F.Cu")
		(net 5)
	)
	(segment
		(start 190.886328 99.820008)
		(end 191.386328 100.320008)
		(width 0.2)
		(layer "F.Cu")
		(net 5)
	)
	(segment
		(start 111.455 101.45)
		(end 111.455 98.735)
		(width 0.2)
		(layer "F.Cu")
		(net 5)
	)
	(segment
		(start 143.0325 84.2)
		(end 143.0325 83.6)
		(width 0.2)
		(layer "F.Cu")
		(net 5)
	)
	(segment
		(start 157.61 117.618485)
		(end 157.621328 117.607157)
		(width 0.2)
		(layer "F.Cu")
		(net 5)
	)
	(segment
		(start 190.404171 123.218485)
		(end 190.364171 123.258485)
		(width 0.2)
		(layer "F.Cu")
		(net 5)
	)
	(segment
		(start 124.997157 56.867672)
		(end 123.707328 56.867672)
		(width 0.3)
		(layer "F.Cu")
		(net 5)
	)
	(segment
		(start 124.6 63.1)
		(end 123.9 63.1)
		(width 0.4)
		(layer "F.Cu")
		(net 5)
	)
	(segment
		(start 114.286328 116.297157)
		(end 116.286328 116.297157)
		(width 0.2)
		(layer "F.Cu")
		(net 5)
	)
	(segment
		(start 186 118.67)
		(end 186 119.285)
		(width 0.2)
		(layer "F.Cu")
		(net 5)
	)
	(segment
		(start 193.586328 106.959306)
		(end 193.586328 107.620008)
		(width 0.2)
		(layer "F.Cu")
		(net 5)
	)
	(segment
		(start 136.2 105.6)
		(end 135.9 105.9)
		(width 0.2)
		(layer "F.Cu")
		(net 5)
	)
	(segment
		(start 151.703 93.5878)
		(end 151.7142 93.599)
		(width 0.15)
		(layer "F.Cu")
		(net 5)
	)
	(segment
		(start 117.453672 116.975)
		(end 117.438672 116.99)
		(width 0.2)
		(layer "F.Cu")
		(net 5)
	)
	(segment
		(start 133.847843 103.752157)
		(end 133.8 103.8)
		(width 0.2)
		(layer "F.Cu")
		(net 5)
	)
	(segment
		(start 136.985 97.515)
		(end 137 97.5)
		(width 0.2)
		(layer "F.Cu")
		(net 5)
	)
	(segment
		(start 154.61 117.578485)
		(end 154.621328 117.567157)
		(width 0.2)
		(layer "F.Cu")
		(net 5)
	)
	(segment
		(start 134.211328 117.822157)
		(end 133.211328 117.822157)
		(width 0.2)
		(layer "F.Cu")
		(net 5)
	)
	(segment
		(start 112.035 121.41)
		(end 112.035 120.735)
		(width 0.1)
		(layer "F.Cu")
		(net 5)
	)
	(segment
		(start 137.557 129.329)
		(end 137.557 128.192829)
		(width 0.2)
		(layer "F.Cu")
		(net 5)
	)
	(segment
		(start 156.11 117.568485)
		(end 156.111328 117.567157)
		(width 0.2)
		(layer "F.Cu")
		(net 5)
	)
	(segment
		(start 185.1 111.365)
		(end 187.815 111.365)
		(width 0.2)
		(layer "F.Cu")
		(net 5)
	)
	(segment
		(start 154.64 124.88)
		(end 154.64 126.678485)
		(width 0.2)
		(layer "F.Cu")
		(net 5)
	)
	(segment
		(start 162.536327 105.497156)
		(end 163.036328 105.997156)
		(width 0.15)
		(layer "F.Cu")
		(net 5)
	)
	(segment
		(start 120.8 52.775)
		(end 120.8 52.1)
		(width 0.5)
		(layer "F.Cu")
		(net 5)
	)
	(segment
		(start 162.536329 85.497157)
		(end 162.536329 84.896694)
		(width 0.15)
		(layer "F.Cu")
		(net 5)
	)
	(segment
		(start 137.585 65.7)
		(end 138.3 65.7)
		(width 0.2)
		(layer "F.Cu")
		(net 5)
	)
	(segment
		(start 109.801328 117.872157)
		(end 109.036328 117.872157)
		(width 0.3)
		(layer "F.Cu")
		(net 5)
	)
	(segment
		(start 123.875 61.475)
		(end 124.6 61.475)
		(width 0.4)
		(layer "F.Cu")
		(net 5)
	)
	(segment
		(start 137.536328 116.887157)
		(end 137.536328 116.247157)
		(width 0.2)
		(layer "F.Cu")
		(net 5)
	)
	(segment
		(start 137.1 97.4)
		(end 137 97.5)
		(width 0.2)
		(layer "F.Cu")
		(net 5)
	)
	(segment
		(start 125.760735 54.160735)
		(end 125.65 54.05)
		(width 0.2)
		(layer "F.Cu")
		(net 5)
	)
	(segment
		(start 189.836328 102.874306)
		(end 189.486328 103.224306)
		(width 0.2)
		(layer "F.Cu")
		(net 5)
	)
	(segment
		(start 191.840626 99.874306)
		(end 191.786328 99.820008)
		(width 0.2)
		(layer "F.Cu")
		(net 5)
	)
	(segment
		(start 135.9 105.9)
		(end 135.4 105.9)
		(width 0.2)
		(layer "F.Cu")
		(net 5)
	)
	(segment
		(start 133.996328 125.977157)
		(end 133.996328 125.032157)
		(width 0.2)
		(layer "F.Cu")
		(net 5)
	)
	(segment
		(start 171.536329 87.497157)
		(end 172.036329 86.997157)
		(width 0.15)
		(layer "F.Cu")
		(net 5)
	)
	(segment
		(start 116.611328 62.747157)
		(end 116.611328 59.422157)
		(width 0.2)
		(layer "F.Cu")
		(net 5)
	)
	(segment
		(start 195.41938 75.622052)
		(end 195.41938 75.905209)
		(width 0.1)
		(layer "F.Cu")
		(net 5)
	)
	(segment
		(start 123.165 89.975)
		(end 123.165 87.14)
		(width 0.2)
		(layer "F.Cu")
		(net 5)
	)
	(segment
		(start 136.625 95.825)
		(end 137.1 96.3)
		(width 0.2)
		(layer "F.Cu")
		(net 5)
	)
	(segment
		(start 133.211328 117.822157)
		(end 133.161328 117.872157)
		(width 0.2)
		(layer "F.Cu")
		(net 5)
	)
	(segment
		(start 162.536329 84.896694)
		(end 162.506054 84.866419)
		(width 0.15)
		(layer "F.Cu")
		(net 5)
	)
	(segment
		(start 156.14 126.685829)
		(end 156.141328 126.687157)
		(width 0.2)
		(layer "F.Cu")
		(net 5)
	)
	(segment
		(start 201.186328 98.320008)
		(end 201.187841 98.320008)
		(width 0.15)
		(layer "F.Cu")
		(net 5)
	)
	(segment
		(start 157.64 126.685829)
		(end 157.641328 126.687157)
		(width 0.2)
		(layer "F.Cu")
		(net 5)
	)
	(segment
		(start 154.64 126.678485)
		(end 154.631328 126.687157)
		(width 0.2)
		(layer "F.Cu")
		(net 5)
	)
	(segment
		(start 198.886328 87.7)
		(end 198.736328 87.7)
		(width 0.1)
		(layer "F.Cu")
		(net 5)
	)
	(segment
		(start 191.386328 100.889306)
		(end 192.486328 100.889306)
		(width 0.2)
		(layer "F.Cu")
		(net 5)
	)
	(segment
		(start 124.6 59.85)
		(end 124.6 59.861774)
		(width 0.4)
		(layer "F.Cu")
		(net 5)
	)
	(segment
		(start 199.386328 75.647157)
		(end 199.386328 74.970008)
		(width 0.1)
		(layer "F.Cu")
		(net 5)
	)
	(segment
		(start 124.997157 56.867672)
		(end 126.192672 56.867672)
		(width 0.2)
		(layer "F.Cu")
		(net 5)
	)
	(segment
		(start 191.074306 107.674306)
		(end 191.1 107.7)
		(width 0.2)
		(layer "F.Cu")
		(net 5)
	)
	(segment
		(start 113.5 109)
		(end 113 109.5)
		(width 0.2)
		(layer "F.Cu")
		(net 5)
	)
	(segment
		(start 116.286328 116.297157)
		(end 117.302843 116.297157)
		(width 0.2)
		(layer "F.Cu")
		(net 5)
	)
	(segment
		(start 140.5 101.715)
		(end 139.895 101.715)
		(width 0.15)
		(layer "F.Cu")
		(net 5)
	)
	(segment
		(start 127.9 66.8)
		(end 127.25 66.8)
		(width 0.4)
		(layer "F.Cu")
		(net 5)
	)
	(segment
		(start 190.471328 107.674306)
		(end 191.074306 107.674306)
		(width 0.2)
		(layer "F.Cu")
		(net 5)
	)
	(segment
		(start 206.386328 79.805008)
		(end 206.386328 80.520012)
		(width 0.1)
		(layer "F.Cu")
		(net 5)
	)
	(segment
		(start 164.786328 70.772157)
		(end 164.786328 72.625)
		(width 0.1)
		(layer "F.Cu")
		(net 5)
	)
	(segment
		(start 190.404171 122.574485)
		(end 190.404171 123.218485)
		(width 0.2)
		(layer "F.Cu")
		(net 5)
	)
	(segment
		(start 135.881328 125.442157)
		(end 135.881328 124.957157)
		(width 0.13)
		(layer "F.Cu")
		(net 5)
	)
	(segment
		(start 180.6735 115.731)
		(end 181.4585 115.731)
		(width 0.1)
		(layer "F.Cu")
		(net 5)
	)
	(segment
		(start 171.536329 86.497157)
		(end 172.036329 85.997157)
		(width 0.15)
		(layer "F.Cu")
		(net 5)
	)
	(segment
		(start 134.815 65.685)
		(end 134.8 65.7)
		(width 0.2)
		(layer "F.Cu")
		(net 5)
	)
	(segment
		(start 132.661328 116.482157)
		(end 132.661328 117.122157)
		(width 0.2)
		(layer "F.Cu")
		(net 5)
	)
	(segment
		(start 125.760735 55.014265)
		(end 125.760735 54.160735)
		(width 0.2)
		(layer "F.Cu")
		(net 5)
	)
	(segment
		(start 159.11 118.68)
		(end 159.11 117.648485)
		(width 0.2)
		(layer "F.Cu")
		(net 5)
	)
	(segment
		(start 178.536329 88.497157)
		(end 179.036329 87.997157)
		(width 0.15)
		(layer "F.Cu")
		(net 5)
	)
	(segment
		(start 125.19 51.41)
		(end 125.2 51.4)
		(width 0.5)
		(layer "F.Cu")
		(net 5)
	)
	(segment
		(start 118.415 116.975)
		(end 117.453672 116.975)
		(width 0.2)
		(layer "F.Cu")
		(net 5)
	)
	(segment
		(start 213.193336 98.12168)
		(end 214.510851 98.12168)
		(width 0.2)
		(layer "F.Cu")
		(net 5)
	)
	(segment
		(start 136.985 98.25)
		(end 136.985 97.515)
		(width 0.2)
		(layer "F.Cu")
		(net 5)
	)
	(segment
		(start 159.05 77.5)
		(end 159.036328 77.463672)
		(width 0.2)
		(layer "F.Cu")
		(net 5)
	)
	(segment
		(start 143.165 101.69)
		(end 143.79 101.69)
		(width 0.15)
		(layer "F.Cu")
		(net 5)
	)
	(segment
		(start 137.801328 115.108157)
		(end 137.300328 115.108157)
		(width 0.2)
		(layer "F.Cu")
		(net 5)
	)
	(segment
		(start 133.015 94.5)
		(end 133.015 93.615)
		(width 0.2)
		(layer "F.Cu")
		(net 5)
	)
	(segment
		(start 123.1625 98.735)
		(end 123.3475 98.55)
		(width 0.2)
		(layer "F.Cu")
		(net 5)
	)
	(segment
		(start 154.61 118.68)
		(end 154.61 117.578485)
		(width 0.2)
		(layer "F.Cu")
		(net 5)
	)
	(segment
		(start 172.359 112.152)
		(end 172.359 112.81)
		(width 0.2)
		(layer "F.Cu")
		(net 5)
	)
	(segment
		(start 157.286328 70.597157)
		(end 157.286328 69.247157)
		(width 0.1)
		(layer "F.Cu")
		(net 5)
	)
	(segment
		(start 176.23 110.6)
		(end 176.4 110.6)
		(width 0.2)
		(layer "F.Cu")
		(net 5)
	)
	(segment
		(start 179.536329 85.497157)
		(end 180.036329 84.997157)
		(width 0.15)
		(layer "F.Cu")
		(net 5)
	)
	(segment
		(start 134.615 104.8)
		(end 133.8 104.8)
		(width 0.2)
		(layer "F.Cu")
		(net 5)
	)
	(segment
		(start 206.586328 99.889306)
		(end 206.586328 99.320008)
		(width 0.2)
		(layer "F.Cu")
		(net 5)
	)
	(segment
		(start 207.386328 75.647157)
		(end 207.895577 75.647157)
		(width 0.1)
		(layer "F.Cu")
		(net 5)
	)
	(segment
		(start 205.486328 106.659306)
		(end 205.486328 107.220008)
		(width 0.2)
		(layer "F.Cu")
		(net 5)
	)
	(segment
		(start 201.187841 98.320008)
		(end 201.193894 98.313955)
		(width 0.15)
		(layer "F.Cu")
		(net 5)
	)
	(segment
		(start 193.586328 100.889306)
		(end 192.486328 100.889306)
		(width 0.2)
		(layer "F.Cu")
		(net 5)
	)
	(segment
		(start 171.536329 85.497157)
		(end 172.036329 84.997157)
		(width 0.15)
		(layer "F.Cu")
		(net 5)
	)
	(segment
		(start 180.995 111.32868)
		(end 180.986328 111.320008)
		(width 0.2)
		(layer "F.Cu")
		(net 5)
	)
	(segment
		(start 139.895 101.715)
		(end 139.865 101.745)
		(width 0.15)
		(layer "F.Cu")
		(net 5)
	)
	(segment
		(start 207.895577 75.647157)
		(end 207.904527 75.638207)
		(width 0.1)
		(layer "F.Cu")
		(net 5)
	)
	(segment
		(start 111.455 98.735)
		(end 111.64 98.55)
		(width 0.2)
		(layer "F.Cu")
		(net 5)
	)
	(segment
		(start 179.536329 96.497157)
		(end 179.566329 96.527157)
		(width 0.15)
		(layer "F.Cu")
		(net 5)
	)
	(segment
		(start 130.4675 100.55)
		(end 131.0825 100.55)
		(width 0.2)
		(layer "F.Cu")
		(net 5)
	)
	(segment
		(start 117.438672 116.238672)
		(end 117.4 116.2)
		(width 0.2)
		(layer "F.Cu")
		(net 5)
	)
	(segment
		(start 192.601328 99.874306)
		(end 191.840626 99.874306)
		(width 0.2)
		(layer "F.Cu")
		(net 5)
	)
	(segment
		(start 134.615 112.1)
		(end 134.615 111.415)
		(width 0.2)
		(layer "F.Cu")
		(net 5)
	)
	(segment
		(start 134.615 111.415)
		(end 134.6 111.4)
		(width 0.2)
		(layer "F.Cu")
		(net 5)
	)
	(segment
		(start 195.41938 75.905209)
		(end 195.169381 76.155208)
		(width 0.1)
		(layer "F.Cu")
		(net 5)
	)
	(segment
		(start 127.9 68.3)
		(end 127.25 68.3)
		(width 0.4)
		(layer "F.Cu")
		(net 5)
	)
	(segment
		(start 179.566329 96.527157)
		(end 180.191328 96.527157)
		(width 0.15)
		(layer "F.Cu")
		(net 5)
	)
	(segment
		(start 137.1 96.3)
		(end 137.1 97.4)
		(width 0.2)
		(layer "F.Cu")
		(net 5)
	)
	(segment
		(start 142 113.605829)
		(end 142.551328 114.157157)
		(width 0.15)
		(layer "F.Cu")
		(net 5)
	)
	(segment
		(start 114.515 109)
		(end 113.5 109)
		(width 0.2)
		(layer "F.Cu")
		(net 5)
	)
	(segment
		(start 143.0325 89.1)
		(end 143.0325 88.5)
		(width 0.2)
		(layer "F.Cu")
		(net 5)
	)
	(segment
		(start 117.438672 116.99)
		(end 117.438672 116.238672)
		(width 0.2)
		(layer "F.Cu")
		(net 5)
	)
	(segment
		(start 135.05 105.55)
		(end 135.05 105.235)
		(width 0.2)
		(layer "F.Cu")
		(net 5)
	)
	(segment
		(start 135.6 65.685)
		(end 134.815 65.685)
		(width 0.2)
		(layer "F.Cu")
		(net 5)
	)
	(segment
		(start 111.36 111.36)
		(end 111.375 111.375)
		(width 0.2)
		(layer "F.Cu")
		(net 5)
	)
	(segment
		(start 156.14 124.88)
		(end 156.14 126.685829)
		(width 0.2)
		(layer "F.Cu")
		(net 5)
	)
	(segment
		(start 143.106328 115.237157)
		(end 143.116328 115.227157)
		(width 0.15)
		(layer "F.Cu")
		(net 5)
	)
	(segment
		(start 137.300328 115.108157)
		(end 137.286328 115.122157)
		(width 0.2)
		(layer "F.Cu")
		(net 5)
	)
	(segment
		(start 173.536329 85.497157)
		(end 174.036329 84.997157)
		(width 0.15)
		(layer "F.Cu")
		(net 5)
	)
	(segment
		(start 116.515 120)
		(end 115.4 120)
		(width 0.2)
		(layer "F.Cu")
		(net 5)
	)
	(segment
		(start 187.815 111.365)
		(end 188 111.55)
		(width 0.2)
		(layer "F.Cu")
		(net 5)
	)
	(segment
		(start 134.615 103.752157)
		(end 133.847843 103.752157)
		(width 0.2)
		(layer "F.Cu")
		(net 5)
	)
	(segment
		(start 118.182806 89.075)
		(end 118.797806 89.075)
		(width 0.2)
		(layer "F.Cu")
		(net 5)
	)
	(segment
		(start 191.83203 98.874306)
		(end 191.786328 98.920008)
		(width 0.2)
		(layer "F.Cu")
		(net 5)
	)
	(segment
		(start 206.586328 106.659306)
		(end 206.586328 107.220008)
		(width 0.2)
		(layer "F.Cu")
		(net 5)
	)
	(segment
		(start 167.536328 77.506162)
		(end 167.534152 77.503986)
		(width 0.2)
		(layer "F.Cu")
		(net 5)
	)
	(segment
		(start 115.4 120)
		(end 115.25 120)
		(width 0.2)
		(layer "F.Cu")
		(net 5)
	)
	(segment
		(start 157.61 118.68)
		(end 157.61 117.618485)
		(width 0.2)
		(layer "F.Cu")
		(net 5)
	)
	(segment
		(start 171.536328 78.847157)
		(end 171.536328 80.247157)
		(width 0.15)
		(layer "F.Cu")
		(net 5)
	)
	(segment
		(start 151.64 126.695829)
		(end 151.661328 126.717157)
		(width 0.2)
		(layer "F.Cu")
		(net 5)
	)
	(segment
		(start 123.525 57.05)
		(end 122.3 57.05)
		(width 0.3)
		(layer "F.Cu")
		(net 5)
	)
	(segment
		(start 159.11 117.648485)
		(end 159.111328 117.647157)
		(width 0.2)
		(layer "F.Cu")
		(net 5)
	)
	(segment
		(start 175.536329 85.497157)
		(end 176.036329 84.997157)
		(width 0.15)
		(layer "F.Cu")
		(net 5)
	)
	(segment
		(start 110.877806 89.975)
		(end 110.877806 87.26)
		(width 0.2)
		(layer "F.Cu")
		(net 5)
	)
	(segment
		(start 143.116328 114.157157)
		(end 143.136328 114.137157)
		(width 0.15)
		(layer "F.Cu")
		(net 5)
	)
	(segment
		(start 138 102.3)
		(end 138 103.9125)
		(width 0.2)
		(layer "F.Cu")
		(net 5)
	)
	(segment
		(start 191.786328 106.124306)
		(end 191.786328 107.320008)
		(width 0.2)
		(layer "F.Cu")
		(net 5)
	)
	(segment
		(start 159.14 124.88)
		(end 159.14 126.675829)
		(width 0.2)
		(layer "F.Cu")
		(net 5)
	)
	(segment
		(start 126.392672 57.067672)
		(end 126.927157 57.067672)
		(width 0.2)
		(layer "F.Cu")
		(net 5)
	)
	(segment
		(start 201.186328 99.620008)
		(end 201.186328 98.320008)
		(width 0.15)
		(layer "F.Cu")
		(net 5)
	)
	(segment
		(start 126.192672 56.867672)
		(end 126.392672 57.067672)
		(width 0.2)
		(layer "F.Cu")
		(net 5)
	)
	(segment
		(start 138.8 98.25)
		(end 138.8 97.55)
		(width 0.2)
		(layer "F.Cu")
		(net 5)
	)
	(segment
		(start 122.3 52.775)
		(end 122.3 52.1)
		(width 0.5)
		(layer "F.Cu")
		(net 5)
	)
	(segment
		(start 130.435 89.075)
		(end 131.09 89.075)
		(width 0.2)
		(layer "F.Cu")
		(net 5)
	)
	(segment
		(start 179.536329 89.497157)
		(end 180.036329 88.997157)
		(width 0.15)
		(layer "F.Cu")
		(net 5)
	)
	(segment
		(start 143.0325 86.6)
		(end 143.0325 86)
		(width 0.2)
		(layer "F.Cu")
		(net 5)
	)
	(segment
		(start 112.035 120.735)
		(end 112 120.7)
		(width 0.1)
		(layer "F.Cu")
		(net 5)
	)
	(segment
		(start 110.877806 87.26)
		(end 111.062806 87.075)
		(width 0.2)
		(layer "F.Cu")
		(net 5)
	)
	(segment
		(start 142.551328 114.157157)
		(end 143.116328 114.157157)
		(width 0.15)
		(layer "F.Cu")
		(net 5)
	)
	(segment
		(start 170.6 119.541)
		(end 169.3935 119.541)
		(width 0.1)
		(layer "F.Cu")
		(net 5)
	)
	(segment
		(start 116.611328 59.422157)
		(end 116.661328 59.372157)
		(width 0.2)
		(layer "F.Cu")
		(net 5)
	)
	(segment
		(start 146.05 108.1)
		(end 144.6875 108.1)
		(width 0.2)
		(layer "F.Cu")
		(net 5)
	)
	(segment
		(start 149.146328 108.782157)
		(end 149.626328 108.782157)
		(width 0.1)
		(layer "F.Cu")
		(net 5)
	)
	(segment
		(start 156.11 118.68)
		(end 156.11 117.568485)
		(width 0.2)
		(layer "F.Cu")
		(net 5)
	)
	(segment
		(start 151.64 124.88)
		(end 151.64 126.695829)
		(width 0.2)
		(layer "F.Cu")
		(net 5)
	)
	(segment
		(start 191.386328 100.889306)
		(end 191.386328 100.320008)
		(width 0.2)
		(layer "F.Cu")
		(net 5)
	)
	(segment
		(start 157.64 124.88)
		(end 157.64 126.685829)
		(width 0.2)
		(layer "F.Cu")
		(net 5)
	)
	(segment
		(start 125.19 52.1)
		(end 125.19 51.41)
		(width 0.5)
		(layer "F.Cu")
		(net 5)
	)
	(segment
		(start 167.536328 78.847157)
		(end 167.536328 77.506162)
		(width 0.2)
		(layer "F.Cu")
		(net 5)
	)
	(segment
		(start 123.707328 56.867672)
		(end 123.525 57.05)
		(width 0.3)
		(layer "F.Cu")
		(net 5)
	)
	(segment
		(start 192.601328 98.874306)
		(end 191.83203 98.874306)
		(width 0.2)
		(layer "F.Cu")
		(net 5)
	)
	(segment
		(start 124.6 59.861774)
		(end 124.015504 60.44627)
		(width 0.4)
		(layer "F.Cu")
		(net 5)
	)
	(segment
		(start 142.551328 115.237157)
		(end 143.106328 115.237157)
		(width 0.15)
		(layer "F.Cu")
		(net 5)
	)
	(segment
		(start 135.4 105.9)
		(end 135.05 105.55)
		(width 0.2)
		(layer "F.Cu")
		(net 5)
	)
	(segment
		(start 175.026 131.668)
		(end 175.026 130.844)
		(width 0.2)
		(layer "F.Cu")
		(net 5)
	)
	(segment
		(start 178.536329 87.497157)
		(end 179.036329 86.997157)
		(width 0.15)
		(layer "F.Cu")
		(net 5)
	)
	(segment
		(start 118.76 100.55)
		(end 119.375 100.55)
		(width 0.2)
		(layer "F.Cu")
		(net 5)
	)
	(segment
		(start 142 111.7875)
		(end 142 113.605829)
		(width 0.15)
		(layer "F.Cu")
		(net 5)
	)
	(segment
		(start 203.086328 79.805008)
		(end 203.086328 80.520008)
		(width 0.1)
		(layer "F.Cu")
		(net 5)
	)
	(segment
		(start 163.036328 78.847157)
		(end 163.036328 77.513672)
		(width 0.2)
		(layer "F.Cu")
		(net 5)
	)
	(segment
		(start 137.314328 113.969157)
		(end 137.286328 113.997157)
		(width 0.2)
		(layer "F.Cu")
		(net 5)
	)
	(segment
		(start 214.510851 98.12168)
		(end 214.559179 98.170008)
		(width 0.2)
		(layer "F.Cu")
		(net 5)
	)
	(segment
		(start 138.8 97.55)
		(end 138.75 97.5)
		(width 0.2)
		(layer "F.Cu")
		(net 5)
	)
	(segment
		(start 176.4 110.6)
		(end 177.5 111.7)
		(width 0.2)
		(layer "F.Cu")
		(net 5)
	)
	(segment
		(start 151.703 92.456)
		(end 151.703 93.5878)
		(width 0.15)
		(layer "F.Cu")
		(net 5)
	)
	(segment
		(start 161.536329 92.497158)
		(end 162.036329 91.997158)
		(width 0.15)
		(layer "F.Cu")
		(net 5)
	)
	(segment
		(start 137.557 128.192829)
		(end 137.551328 128.187157)
		(width 0.2)
		(layer "F.Cu")
		(net 5)
	)
	(segment
		(start 159.14 126.675829)
		(end 159.151328 126.687157)
		(width 0.2)
		(layer "F.Cu")
		(net 5)
	)
	(segment
		(start 134.615 108.785)
		(end 134.6 108.8)
		(width 0.2)
		(layer "F.Cu")
		(net 5)
	)
	(segment
		(start 157.2 56.4)
		(end 157.2 55.7)
		(width 0.5)
		(layer "F.Cu")
		(net 5)
	)
	(segment
		(start 198.9 85.1)
		(end 198.736328 85.1)
		(width 0.1)
		(layer "F.Cu")
		(net 5)
	)
	(segment
		(start 139.776328 115.112157)
		(end 139.776328 115.797157)
		(width 0.15)
		(layer "F.Cu")
		(net 5)
	)
	(segment
		(start 177.536329 85.497157)
		(end 178.036329 84.997157)
		(width 0.15)
		(layer "F.Cu")
		(net 5)
	)
	(segment
		(start 171.286328 70.772157)
		(end 171.286328 72.625)
		(width 0.1)
		(layer "F.Cu")
		(net 5)
	)
	(segment
		(start 133.996328 125.032157)
		(end 134.001328 125.027157)
		(width 0.2)
		(layer "F.Cu")
		(net 5)
	)
	(segment
		(start 117.302843 116.297157)
		(end 117.4 116.2)
		(width 0.2)
		(layer "F.Cu")
		(net 5)
	)
	(segment
		(start 189.486328 104.324306)
		(end 189.486328 103.224306)
		(width 0.2)
		(layer "F.Cu")
		(net 5)
	)
	(segment
		(start 136.8125 105.6)
		(end 136.2 105.6)
		(width 0.2)
		(layer "F.Cu")
		(net 5)
	)
	(segment
		(start 205.486328 103.289306)
		(end 206.586328 103.289306)
		(width 0.2)
		(layer "F.Cu")
		(net 5)
	)
	(segment
		(start 123.165 87.14)
		(end 123.15 87.125)
		(width 0.2)
		(layer "F.Cu")
		(net 5)
	)
	(segment
		(start 138.085 59.7)
		(end 138.9 59.7)
		(width 0.2)
		(layer "F.Cu")
		(net 5)
	)
	(segment
		(start 179.6 56.4)
		(end 179.6 55.7)
		(width 0.5)
		(layer "F.Cu")
		(net 5)
	)
	(segment
		(start 136.024143 95.825)
		(end 136.625 95.825)
		(width 0.2)
		(layer "F.Cu")
		(net 5)
	)
	(segment
		(start 180.995 111.944)
		(end 180.995 111.32868)
		(width 0.2)
		(layer "F.Cu")
		(net 5)
	)
	(segment
		(start 133.015 93.615)
		(end 133 93.6)
		(width 0.2)
		(layer "F.Cu")
		(net 5)
	)
	(segment
		(start 109.801328 116.747157)
		(end 109.036328 116.747157)
		(width 0.3)
		(layer "F.Cu")
		(net 5)
	)
	(segment
		(start 164.536328 101.497157)
		(end 164.036329 101.997156)
		(width 0.15)
		(layer "F.Cu")
		(net 5)
	)
	(segment
		(start 124.05 51.99)
		(end 123.41 51.99)
		(width 0.5)
		(layer "F.Cu")
		(net 5)
	)
	(segment
		(start 159.036328 77.463672)
		(end 159.036328 78.847157)
		(width 0.2)
		(layer "F.Cu")
		(net 5)
	)
	(segment
		(start 135.05 105.235)
		(end 134.615 104.8)
		(width 0.2)
		(layer "F.Cu")
		(net 5)
	)
	(segment
		(start 199.268164 87.318164)
		(end 198.886328 87.7)
		(width 0.1)
		(layer "F.Cu")
		(net 5)
	)
	(segment
		(start 190.701328 102.874306)
		(end 189.836328 102.874306)
		(width 0.2)
		(layer "F.Cu")
		(net 5)
	)
	(segment
		(start 123.1625 101.45)
		(end 123.1625 98.735)
		(width 0.2)
		(layer "F.Cu")
		(net 5)
	)
	(segment
		(start 149.626328 108.782157)
		(end 149.661328 108.747157)
		(width 0.1)
		(layer "F.Cu")
		(net 5)
	)
	(segment
		(start 123.9 61.5)
		(end 123.875 61.475)
		(width 0.4)
		(layer "F.Cu")
		(net 5)
	)
	(segment
		(start 203.386328 75.647157)
		(end 203.386328 74.970008)
		(width 0.1)
		(layer "F.Cu")
		(net 5)
	)
	(segment
		(start 136.011328 115.522157)
		(end 136.011328 114.397157)
		(width 0.2)
		(layer "F.Cu")
		(net 5)
	)
	(segment
		(start 123.41 51.99)
		(end 123.4 52)
		(width 0.5)
		(layer "F.Cu")
		(net 5)
	)
	(via blind
		(at 160.786328 69.247157)
		(size 0.5)
		(drill 0.2)
		(layers "F.Cu" "In1.Cu")
		(net 5)
	)
	(via
		(at 184.411328 59.372157)
		(size 0.5)
		(drill 0.2)
		(layers "F.Cu" "B.Cu")
		(net 5)
	)
	(via blind
		(at 160.036327 89.997156)
		(size 0.5)
		(drill 0.2)
		(layers "F.Cu" "In1.Cu")
		(net 5)
	)
	(via
		(at 159.036329 106.997157)
		(size 0.5)
		(drill 0.2)
		(layers "F.Cu" "B.Cu")
		(net 5)
	)
	(via
		(at 159.036328 103.997155)
		(size 0.5)
		(drill 0.2)
		(layers "F.Cu" "B.Cu")
		(net 5)
	)
	(via
		(at 159.036327 93.997157)
		(size 0.5)
		(drill 0.2)
		(layers "F.Cu" "B.Cu")
		(net 5)
	)
	(via blind
		(at 159.036328 96.997156)
		(size 0.5)
		(drill 0.2)
		(layers "F.Cu" "In1.Cu")
		(net 5)
	)
	(via
		(at 173.036329 105.997157)
		(size 0.5)
		(drill 0.2)
		(layers "F.Cu" "B.Cu")
		(net 5)
	)
	(via blind
		(at 171.286328 72.625)
		(size 0.5)
		(drill 0.2)
		(layers "F.Cu" "In2.Cu")
		(net 5)
	)
	(via blind
		(at 168.786328 69.247157)
		(size 0.5)
		(drill 0.2)
		(layers "F.Cu" "In1.Cu")
		(net 5)
	)
	(via
		(at 179.036327 105.997157)
		(size 0.5)
		(drill 0.2)
		(layers "F.Cu" "B.Cu")
		(net 5)
	)
	(via blind
		(at 159.036328 85.997156)
		(size 0.5)
		(drill 0.2)
		(layers "F.Cu" "In1.Cu")
		(net 5)
	)
	(via blind
		(at 164.786328 72.625)
		(size 0.5)
		(drill 0.2)
		(layers "F.Cu" "In2.Cu")
		(net 5)
	)
	(via
		(at 168.036329 96.997156)
		(size 0.5)
		(drill 0.2)
		(layers "F.Cu" "B.Cu")
		(net 5)
	)
	(via
		(at 171.036329 94.997156)
		(size 0.5)
		(drill 0.2)
		(layers "F.Cu" "B.Cu")
		(net 5)
	)
	(via
		(at 168.9935 94.997156)
		(size 0.5)
		(drill 0.2)
		(layers "F.Cu" "B.Cu")
		(net 5)
	)
	(via
		(at 170.036329 96.997157)
		(size 0.5)
		(drill 0.2)
		(layers "F.Cu" "B.Cu")
		(net 5)
	)
	(via
		(at 168.036329 94.997157)
		(size 0.5)
		(drill 0.2)
		(layers "F.Cu" "B.Cu")
		(net 5)
	)
	(via blind
		(at 178.036329 90.997157)
		(size 0.5)
		(drill 0.2)
		(layers "F.Cu" "In1.Cu")
		(net 5)
	)
	(via blind
		(at 178.036329 88.997157)
		(size 0.5)
		(drill 0.2)
		(layers "F.Cu" "In1.Cu")
		(net 5)
	)
	(via blind
		(at 177.036329 90.997157)
		(size 0.5)
		(drill 0.2)
		(layers "F.Cu" "In1.Cu")
		(net 5)
	)
	(via blind
		(at 176.036329 90.997156)
		(size 0.5)
		(drill 0.2)
		(layers "F.Cu" "In1.Cu")
		(net 5)
	)
	(via blind
		(at 176.036328 88.997157)
		(size 0.5)
		(drill 0.2)
		(layers "F.Cu" "In1.Cu")
		(net 5)
	)
	(via
		(at 175.036328 93.997157)
		(size 0.5)
		(drill 0.2)
		(layers "F.Cu" "B.Cu")
		(net 5)
	)
	(via
		(at 174.036327 90.997156)
		(size 0.5)
		(drill 0.2)
		(layers "F.Cu" "B.Cu")
		(net 5)
	)
	(via blind
		(at 174.036329 88.997157)
		(size 0.5)
		(drill 0.2)
		(layers "F.Cu" "In1.Cu")
		(net 5)
	)
	(via blind
		(at 173.036329 88.997157)
		(size 0.5)
		(drill 0.2)
		(layers "F.Cu" "In1.Cu")
		(net 5)
	)
	(via
		(at 173.036329 94.997157)
		(size 0.5)
		(drill 0.2)
		(layers "F.Cu" "B.Cu")
		(net 5)
	)
	(via blind
		(at 173.036329 86.997157)
		(size 0.5)
		(drill 0.2)
		(layers "F.Cu" "In1.Cu")
		(net 5)
	)
	(via
		(at 173.036329 87.997156)
		(size 0.5)
		(drill 0.2)
		(layers "F.Cu" "B.Cu")
		(net 5)
	)
	(via
		(at 172.036329 91.997157)
		(size 0.5)
		(drill 0.2)
		(layers "F.Cu" "B.Cu")
		(net 5)
	)
	(via blind
		(at 172.036329 93.997157)
		(size 0.5)
		(drill 0.2)
		(layers "F.Cu" "In1.Cu")
		(net 5)
	)
	(via blind
		(at 171.036329 92.997157)
		(size 0.5)
		(drill 0.2)
		(layers "F.Cu" "In1.Cu")
		(net 5)
	)
	(via
		(at 171.036329 88.997157)
		(size 0.5)
		(drill 0.2)
		(layers "F.Cu" "B.Cu")
		(net 5)
	)
	(via blind
		(at 170.036329 91.997157)
		(size 0.5)
		(drill 0.2)
		(layers "F.Cu" "In1.Cu")
		(net 5)
	)
	(via
		(at 170.036329 93.997157)
		(size 0.5)
		(drill 0.2)
		(layers "F.Cu" "B.Cu")
		(net 5)
	)
	(via
		(at 164.036329 90.997157)
		(size 0.5)
		(drill 0.2)
		(layers "F.Cu" "B.Cu")
		(net 5)
	)
	(via
		(at 166.036329 86.997157)
		(size 0.5)
		(drill 0.2)
		(layers "F.Cu" "B.Cu")
		(net 5)
	)
	(via
		(at 162.036329 94.997156)
		(size 0.5)
		(drill 0.2)
		(layers "F.Cu" "B.Cu")
		(net 5)
	)
	(via
		(at 166.036329 94.997156)
		(size 0.5)
		(drill 0.2)
		(layers "F.Cu" "B.Cu")
		(net 5)
	)
	(via
		(at 168.036329 92.997156)
		(size 0.5)
		(drill 0.2)
		(layers "F.Cu" "B.Cu")
		(net 5)
	)
	(via blind
		(at 166.036329 92.997157)
		(size 0.5)
		(drill 0.2)
		(layers "F.Cu" "In1.Cu")
		(net 5)
	)
	(via blind
		(at 165.036329 93.997157)
		(size 0.5)
		(drill 0.2)
		(layers "F.Cu" "In1.Cu")
		(net 5)
	)
	(via blind
		(at 167.036329 94.997156)
		(size 0.5)
		(drill 0.2)
		(layers "F.Cu" "In1.Cu")
		(net 5)
	)
	(via blind
		(at 167.036329 91.997157)
		(size 0.5)
		(drill 0.2)
		(layers "F.Cu" "In1.Cu")
		(net 5)
	)
	(via
		(at 167.036329 89.997157)
		(size 0.5)
		(drill 0.2)
		(layers "F.Cu" "B.Cu")
		(net 5)
	)
	(via
		(at 165.036329 91.997157)
		(size 0.5)
		(drill 0.2)
		(layers "F.Cu" "B.Cu")
		(net 5)
	)
	(via blind
		(at 167.036329 93.997157)
		(size 0.5)
		(drill 0.2)
		(layers "F.Cu" "In1.Cu")
		(net 5)
	)
	(via blind
		(at 163.036329 87.997156)
		(size 0.5)
		(drill 0.2)
		(layers "F.Cu" "In1.Cu")
		(net 5)
	)
	(via blind
		(at 167.036329 100.997157)
		(size 0.5)
		(drill 0.2)
		(layers "F.Cu" "In1.Cu")
		(net 5)
	)
	(via
		(at 167.036329 96.997157)
		(size 0.5)
		(drill 0.2)
		(layers "F.Cu" "B.Cu")
		(net 5)
	)
	(via
		(at 168.036329 99.997157)
		(size 0.5)
		(drill 0.2)
		(layers "F.Cu" "B.Cu")
		(net 5)
	)
	(via blind
		(at 168.036329 97.997156)
		(size 0.5)
		(drill 0.2)
		(layers "F.Cu" "In1.Cu")
		(net 5)
	)
	(via
		(at 165.036329 98.997157)
		(size 0.5)
		(drill 0.2)
		(layers "F.Cu" "B.Cu")
		(net 5)
	)
	(via
		(at 165.036329 96.997157)
		(size 0.5)
		(drill 0.2)
		(layers "F.Cu" "B.Cu")
		(net 5)
	)
	(via
		(at 168.036328 102.997158)
		(size 0.5)
		(drill 0.2)
		(layers "F.Cu" "B.Cu")
		(net 5)
	)
	(via
		(at 166.036329 99.997156)
		(size 0.5)
		(drill 0.2)
		(layers "F.Cu" "B.Cu")
		(net 5)
	)
	(via blind
		(at 166.036329 97.997157)
		(size 0.5)
		(drill 0.2)
		(layers "F.Cu" "In1.Cu")
		(net 5)
	)
	(via
		(at 166.036328 104.997156)
		(size 0.5)
		(drill 0.2)
		(layers "F.Cu" "B.Cu")
		(net 5)
	)
	(via
		(at 163.036328 97.997158)
		(size 0.5)
		(drill 0.2)
		(layers "F.Cu" "B.Cu")
		(net 5)
	)
	(via
		(at 167.036329 98.997157)
		(size 0.5)
		(drill 0.2)
		(layers "F.Cu" "B.Cu")
		(net 5)
	)
	(via
		(at 161.036328 101.997159)
		(size 0.5)
		(drill 0.2)
		(layers "F.Cu" "B.Cu")
		(net 5)
	)
	(via
		(at 164.036329 101.997156)
		(size 0.5)
		(drill 0.2)
		(layers "F.Cu" "B.Cu")
		(net 5)
	)
	(via
		(at 172.036329 96.997157)
		(size 0.5)
		(drill 0.2)
		(layers "F.Cu" "B.Cu")
		(net 5)
	)
	(via
		(at 170.036329 98.997157)
		(size 0.5)
		(drill 0.2)
		(layers "F.Cu" "B.Cu")
		(net 5)
	)
	(via
		(at 172.036329 98.997157)
		(size 0.5)
		(drill 0.2)
		(layers "F.Cu" "B.Cu")
		(net 5)
	)
	(via
		(at 175.036327 103.997157)
		(size 0.5)
		(drill 0.2)
		(layers "F.Cu" "B.Cu")
		(net 5)
	)
	(via
		(at 171.036329 99.997156)
		(size 0.5)
		(drill 0.2)
		(layers "F.Cu" "B.Cu")
		(net 5)
	)
	(via
		(at 171.036327 101.997157)
		(size 0.5)
		(drill 0.2)
		(layers "F.Cu" "B.Cu")
		(net 5)
	)
	(via
		(at 174.036329 98.997157)
		(size 0.5)
		(drill 0.2)
		(layers "F.Cu" "B.Cu")
		(net 5)
	)
	(via blind
		(at 171.036329 97.997157)
		(size 0.5)
		(drill 0.2)
		(layers "F.Cu" "In1.Cu")
		(net 5)
	)
	(via
		(at 174.036327 100.997157)
		(size 0.5)
		(drill 0.2)
		(layers "F.Cu" "B.Cu")
		(net 5)
	)
	(via
		(at 177.036328 99.997157)
		(size 0.5)
		(drill 0.2)
		(layers "F.Cu" "B.Cu")
		(net 5)
	)
	(via blind
		(at 175.036329 86.997157)
		(size 0.5)
		(drill 0.2)
		(layers "F.Cu" "In1.Cu")
		(net 5)
	)
	(via
		(at 175.036329 87.997157)
		(size 0.5)
		(drill 0.2)
		(layers "F.Cu" "B.Cu")
		(net 5)
	)
	(via blind
		(at 177.03633 86.997157)
		(size 0.5)
		(drill 0.2)
		(layers "F.Cu" "In1.Cu")
		(net 5)
	)
	(via blind
		(at 177.036329 87.997156)
		(size 0.5)
		(drill 0.2)
		(layers "F.Cu" "In1.Cu")
		(net 5)
	)
	(via blind
		(at 180.536329 92.997156)
		(size 0.5)
		(drill 0.2)
		(layers "F.Cu" "In1.Cu")
		(net 5)
	)
	(via blind
		(at 180.536328 90.997156)
		(size 0.5)
		(drill 0.2)
		(layers "F.Cu" "In1.Cu")
		(net 5)
	)
	(via blind
		(at 181.536329 91.497157)
		(size 0.5)
		(drill 0.2)
		(layers "F.Cu" "In1.Cu")
		(net 5)
	)
	(via
		(at 180.536329 102.997157)
		(size 0.5)
		(drill 0.2)
		(layers "F.Cu" "B.Cu")
		(net 5)
	)
	(via
		(at 150.186242 97.758328)
		(size 0.5)
		(drill 0.2)
		(layers "F.Cu" "B.Cu")
		(net 5)
	)
	(via
		(at 161.029728 99.978358)
		(size 0.5)
		(drill 0.2)
		(layers "F.Cu" "B.Cu")
		(net 5)
	)
	(via
		(at 151.184758 98.786872)
		(size 0.5)
		(drill 0.2)
		(layers "F.Cu" "B.Cu")
		(net 5)
	)
	(via
		(at 152.200758 94.773672)
		(size 0.5)
		(drill 0.2)
		(layers "F.Cu" "B.Cu")
		(net 5)
	)
	(via
		(at 151.7142 93.599)
		(size 0.5)
		(drill 0.2)
		(layers "F.Cu" "B.Cu")
		(net 5)
	)
	(via
		(at 177.036329 97.997156)
		(size 0.5)
		(drill 0.2)
		(layers "F.Cu" "B.Cu")
		(net 5)
	)
	(via
		(at 196.536328 65.497157)
		(size 0.5)
		(drill 0.2)
		(layers "F.Cu" "B.Cu")
		(net 5)
	)
	(via
		(at 200.936328 65.497157)
		(size 0.5)
		(drill 0.2)
		(layers "F.Cu" "B.Cu")
		(net 5)
	)
	(via
		(at 191.386328 76.447157)
		(size 0.5)
		(drill 0.2)
		(layers "F.Cu" "B.Cu")
		(net 5)
	)
	(via
		(at 205.336328 65.497157)
		(size 0.5)
		(drill 0.2)
		(layers "F.Cu" "B.Cu")
		(net 5)
	)
	(via
		(at 192.136328 65.497157)
		(size 0.5)
		(drill 0.2)
		(layers "F.Cu" "B.Cu")
		(net 5)
	)
	(via
		(at 216.336328 115.001279)
		(size 0.5)
		(drill 0.2)
		(layers "F.Cu" "B.Cu")
		(net 5)
	)
	(via
		(at 208.951768 46.897157)
		(size 0.5)
		(drill 0.2)
		(layers "F.Cu" "B.Cu")
		(net 5)
	)
	(via
		(at 133.161328 117.872157)
		(size 0.5)
		(drill 0.2)
		(layers "F.Cu" "B.Cu")
		(net 5)
	)
	(via
		(at 169.72782 135.197157)
		(size 0.5)
		(drill 0.2)
		(layers "F.Cu" "B.Cu")
		(net 5)
	)
	(via
		(at 204.314242 135.197157)
		(size 0.5)
		(drill 0.2)
		(layers "F.Cu" "B.Cu")
		(net 5)
	)
	(via
		(at 112.947806 90.425)
		(size 0.5)
		(drill 0.2)
		(layers "F.Cu" "B.Cu")
		(free yes)
		(net 5)
	)
	(via
		(at 180.741 126.526)
		(size 0.5)
		(drill 0.2)
		(layers "F.Cu" "B.Cu")
		(net 5)
	)
	(via blind
		(at 167.534152 77.503986)
		(size 0.5)
		(drill 0.2)
		(layers "F.Cu" "In1.Cu")
		(net 5)
	)
	(via
		(at 131.632932 46.897157)
		(size 0.5)
		(drill 0.2)
		(layers "F.Cu" "B.Cu")
		(net 5)
	)
	(via
		(at 179.7 121)
		(size 0.5)
		(drill 0.2)
		(layers "F.Cu" "B.Cu")
		(net 5)
	)
	(via
		(at 107.936328 60.748133)
		(size 0.5)
		(drill 0.2)
		(layers "F.Cu" "B.Cu")
		(net 5)
	)
	(via
		(at 137.8 53.2)
		(size 0.5)
		(drill 0.2)
		(layers "F.Cu" "B.Cu")
		(free yes)
		(net 5)
	)
	(via
		(at 122 58.6)
		(size 0.5)
		(drill 0.2)
		(layers "F.Cu" "B.Cu")
		(free yes)
		(net 5)
	)
	(via
		(at 140.2 62)
		(size 0.5)
		(drill 0.2)
		(layers "F.Cu" "B.Cu")
		(free yes)
		(net 5)
	)
	(via
		(at 107.936328 97.106945)
		(size 0.5)
		(drill 0.2)
		(layers "F.Cu" "B.Cu")
		(net 5)
	)
	(via
		(at 163.036328 90.997157)
		(size 0.5)
		(drill 0.2)
		(layers "F.Cu" "B.Cu")
		(net 5)
	)
	(via
		(at 199.386328 74.970008)
		(size 0.5)
		(drill 0.2)
		(layers "F.Cu" "B.Cu")
		(net 5)
	)
	(via
		(at 140.602412 135.197157)
		(size 0.5)
		(drill 0.2)
		(layers "F.Cu" "B.Cu")
		(net 5)
	)
	(via
		(at 188 113.2)
		(size 0.5)
		(drill 0.2)
		(layers "F.Cu" "B.Cu")
		(free yes)
		(net 5)
	)
	(via
		(at 124.4 86.675)
		(size 0.5)
		(drill 0.2)
		(layers "F.Cu" "B.Cu")
		(free yes)
		(net 5)
	)
	(via
		(at 134.6 61.9)
		(size 0.5)
		(drill 0.2)
		(layers "F.Cu" "B.Cu")
		(free yes)
		(net 5)
	)
	(via
		(at 156.141328 126.687157)
		(size 0.5)
		(drill 0.2)
		(layers "F.Cu" "B.Cu")
		(net 5)
	)
	(via
		(at 107.936328 90.181457)
		(size 0.5)
		(drill 0.2)
		(layers "F.Cu" "B.Cu")
		(net 5)
	)
	(via
		(at 127.25 66.8)
		(size 0.5)
		(drill 0.2)
		(layers "F.Cu" "B.Cu")
		(net 5)
	)
	(via
		(at 113.3 118.1)
		(size 0.5)
		(drill 0.2)
		(layers "F.Cu" "B.Cu")
		(free yes)
		(net 5)
	)
	(via blind
		(at 179.036329 86.997157)
		(size 0.5)
		(drill 0.2)
		(layers "F.Cu" "In1.Cu")
		(net 5)
	)
	(via
		(at 177.5 111.7)
		(size 0.5)
		(drill 0.2)
		(layers "F.Cu" "B.Cu")
		(net 5)
	)
	(via
		(at 114.5 118.7)
		(size 0.5)
		(drill 0.2)
		(layers "F.Cu" "B.Cu")
		(free yes)
		(net 5)
	)
	(via
		(at 113.525 102.5)
		(size 0.5)
		(drill 0.2)
		(layers "F.Cu" "B.Cu")
		(free yes)
		(net 5)
	)
	(via
		(at 130 52.2)
		(size 0.5)
		(drill 0.2)
		(layers "F.Cu" "B.Cu")
		(free yes)
		(net 5)
	)
	(via
		(at 169.036328 86.997157)
		(size 0.5)
		(drill 0.2)
		(layers "F.Cu" "B.Cu")
		(net 5)
	)
	(via
		(at 203.086328 80.520008)
		(size 0.5)
		(drill 0.2)
		(layers "F.Cu" "B.Cu")
		(net 5)
	)
	(via
		(at 155.165116 135.197157)
		(size 0.5)
		(drill 0.2)
		(layers "F.Cu" "B.Cu")
		(net 5)
	)
	(via
		(at 216.34 91.37698)
		(size 0.5)
		(drill 0.2)
		(layers "F.Cu" "B.Cu")
		(net 5)
	)
	(via
		(at 124 129.375)
		(size 0.5)
		(drill 0.2)
		(layers "F.Cu" "B.Cu")
		(net 5)
	)
	(via
		(at 107.936328 52.091273)
		(size 0.5)
		(drill 0.2)
		(layers "F.Cu" "B.Cu")
		(net 5)
	)
	(via
		(at 107.936328 105.763805)
		(size 0.5)
		(drill 0.2)
		(layers "F.Cu" "B.Cu")
		(net 5)
	)
	(via
		(at 117.4 72.4)
		(size 0.5)
		(drill 0.2)
		(layers "F.Cu" "B.Cu")
		(free yes)
		(net 5)
	)
	(via
		(at 216.336328 122.384299)
		(size 0.5)
		(drill 0.2)
		(layers "F.Cu" "B.Cu")
		(net 5)
	)
	(via
		(at 107.936328 62.479505)
		(size 0.5)
		(drill 0.2)
		(layers "F.Cu" "B.Cu")
		(net 5)
	)
	(via
		(at 162.446468 135.197157)
		(size 0.5)
		(drill 0.2)
		(layers "F.Cu" "B.Cu")
		(net 5)
	)
	(via
		(at 124.015504 60.44627)
		(size 0.5)
		(drill 0.2)
		(layers "F.Cu" "B.Cu")
		(net 5)
	)
	(via
		(at 118.4 111.2)
		(size 0.5)
		(drill 0.2)
		(layers "F.Cu" "B.Cu")
		(free yes)
		(net 5)
	)
	(via
		(at 216.34 94.330188)
		(size 0.5)
		(drill 0.2)
		(layers "F.Cu" "B.Cu")
		(net 5)
	)
	(via
		(at 153.344778 135.197157)
		(size 0.5)
		(drill 0.2)
		(layers "F.Cu" "B.Cu")
		(net 5)
	)
	(via
		(at 120.95 67.6)
		(size 0.5)
		(drill 0.2)
		(layers "F.Cu" "B.Cu")
		(net 5)
	)
	(via
		(at 131.09 89.075)
		(size 0.5)
		(drill 0.2)
		(layers "F.Cu" "B.Cu")
		(net 5)
	)
	(via
		(at 147.769 85.0512)
		(size 0.5)
		(drill 0.2)
		(layers "F.Cu" "B.Cu")
		(net 5)
	)
	(via
		(at 216.336328 129.767319)
		(size 0.5)
		(drill 0.2)
		(layers "F.Cu" "B.Cu")
		(net 5)
	)
	(via
		(at 113.327852 46.897157)
		(size 0.5)
		(drill 0.2)
		(layers "F.Cu" "B.Cu")
		(net 5)
	)
	(via
		(at 123.7975 98.1)
		(size 0.5)
		(drill 0.2)
		(layers "F.Cu" "B.Cu")
		(free yes)
		(net 5)
	)
	(via
		(at 107.936328 88.450085)
		(size 0.5)
		(drill 0.2)
		(layers "F.Cu" "B.Cu")
		(net 5)
	)
	(via
		(at 195.169381 76.155208)
		(size 0.5)
		(drill 0.2)
		(layers "F.Cu" "B.Cu")
		(net 5)
	)
	(via
		(at 216.336328 106.141655)
		(size 0.5)
		(drill 0.2)
		(layers "F.Cu" "B.Cu")
		(net 5)
	)
	(via
		(at 118.2 76.2)
		(size 0.5)
		(drill 0.2)
		(layers "F.Cu" "B.Cu")
		(free yes)
		(net 5)
	)
	(via
		(at 192.336571 46.897157)
		(size 0.5)
		(drill 0.2)
		(layers "F.Cu" "B.Cu")
		(net 5)
	)
	(via
		(at 140.7 61.6)
		(size 0.5)
		(drill 0.2)
		(layers "F.Cu" "B.Cu")
		(free yes)
		(net 5)
	)
	(via
		(at 116.938018 135.197157)
		(size 0.5)
		(drill 0.2)
		(layers "F.Cu" "B.Cu")
		(net 5)
	)
	(via
		(at 140.785472 46.897157)
		(size 0.5)
		(drill 0.2)
		(layers "F.Cu" "B.Cu")
		(net 5)
	)
	(via
		(at 122 128.875)
		(size 0.5)
		(drill 0.2)
		(layers "F.Cu" "B.Cu")
		(net 5)
	)
	(via
		(at 216.336328 65.663197)
		(size 0.5)
		(drill 0.2)
		(layers "F.Cu" "B.Cu")
		(net 5)
	)
	(via
		(at 199.721103 46.897157)
		(size 0.5)
		(drill 0.2)
		(layers "F.Cu" "B.Cu")
		(net 5)
	)
	(via
		(at 107.936328 130.003013)
		(size 0.5)
		(drill 0.2)
		(layers "F.Cu" "B.Cu")
		(net 5)
	)
	(via
		(at 146.276996 46.897157)
		(size 0.5)
		(drill 0.2)
		(layers "F.Cu" "B.Cu")
		(net 5)
	)
	(via
		(at 143.116328 115.227157)
		(size 0.5)
		(drill 0.2)
		(layers "F.Cu" "B.Cu")
		(net 5)
	)
	(via blind
		(at 179.036329 87.997157)
		(size 0.5)
		(drill 0.2)
		(layers "F.Cu" "In1.Cu")
		(net 5)
	)
	(via
		(at 173.875241 46.897157)
		(size 0.5)
		(drill 0.2)
		(layers "F.Cu" "B.Cu")
		(net 5)
	)
	(via
		(at 177.009172 135.197157)
		(size 0.5)
		(drill 0.2)
		(layers "F.Cu" "B.Cu")
		(net 5)
	)
	(via
		(at 126.6 76.2)
		(size 0.5)
		(drill 0.2)
		(layers "F.Cu" "B.Cu")
		(free yes)
		(net 5)
	)
	(via
		(at 107.936328 53.822645)
		(size 0.5)
		(drill 0.2)
		(layers "F.Cu" "B.Cu")
		(net 5)
	)
	(via
		(at 207.105635 46.897157)
		(size 0.5)
		(drill 0.2)
		(layers "F.Cu" "B.Cu")
		(net 5)
	)
	(via
		(at 188.45 111.15)
		(size 0.5)
		(drill 0.2)
		(layers "F.Cu" "B.Cu")
		(free yes)
		(net 5)
	)
	(via
		(at 122.625 129.375)
		(size 0.5)
		(drill 0.2)
		(layers "F.Cu" "B.Cu")
		(net 5)
	)
	(via
		(at 125.8 76.2)
		(size 0.5)
		(drill 0.2)
		(layers "F.Cu" "B.Cu")
		(free yes)
		(net 5)
	)
	(via
		(at 114.125 102.5)
		(size 0.5)
		(drill 0.2)
		(layers "F.Cu" "B.Cu")
		(free yes)
		(net 5)
	)
	(via
		(at 107.936328 78.061853)
		(size 0.5)
		(drill 0.2)
		(layers "F.Cu" "B.Cu")
		(net 5)
	)
	(via
		(at 186.798172 46.897157)
		(size 0.5)
		(drill 0.2)
		(layers "F.Cu" "B.Cu")
		(net 5)
	)
	(via
		(at 123.3475 98.55)
		(size 0.5)
		(drill 0.2)
		(layers "F.Cu" "B.Cu")
		(free yes)
		(net 5)
	)
	(via
		(at 117.4 76.2)
		(size 0.5)
		(drill 0.2)
		(layers "F.Cu" "B.Cu")
		(free yes)
		(net 5)
	)
	(via
		(at 122.480392 46.897157)
		(size 0.5)
		(drill 0.2)
		(layers "F.Cu" "B.Cu")
		(net 5)
	)
	(via
		(at 216.34 67.74396)
		(size 0.5)
		(drill 0.2)
		(layers "F.Cu" "B.Cu")
		(net 5)
	)
	(via
		(at 157.2 55.7)
		(size 0.45)
		(drill 0.15)
		(layers "F.Cu" "B.Cu")
		(net 5)
	)
	(via
		(at 109.15 104.35)
		(size 0.5)
		(drill 0.2)
		(layers "F.Cu" "B.Cu")
		(net 5)
	)
	(via
		(at 179.41364 46.897157)
		(size 0.5)
		(drill 0.2)
		(layers "F.Cu" "B.Cu")
		(net 5)
	)
	(via
		(at 135.293948 46.897157)
		(size 0.5)
		(drill 0.2)
		(layers "F.Cu" "B.Cu")
		(net 5)
	)
	(via
		(at 203.386328 74.970008)
		(size 0.5)
		(drill 0.2)
		(layers "F.Cu" "B.Cu")
		(net 5)
	)
	(via
		(at 107.936328 64.210877)
		(size 0.5)
		(drill 0.2)
		(layers "F.Cu" "B.Cu")
		(net 5)
	)
	(via
		(at 184.65 114.035)
		(size 0.5)
		(drill 0.2)
		(layers "F.Cu" "B.Cu")
		(free yes)
		(net 5)
	)
	(via
		(at 107.936328 74.599109)
		(size 0.5)
		(drill 0.2)
		(layers "F.Cu" "B.Cu")
		(net 5)
	)
	(via
		(at 199.186328 110.120008)
		(size 0.5)
		(drill 0.2)
		(layers "F.Cu" "B.Cu")
		(net 5)
	)
	(via
		(at 120.2 58.2)
		(size 0.5)
		(drill 0.2)
		(layers "F.Cu" "B.Cu")
		(free yes)
		(net 5)
	)
	(via
		(at 125.65 87.125)
		(size 0.5)
		(drill 0.2)
		(layers "F.Cu" "B.Cu")
		(free yes)
		(net 5)
	)
	(via
		(at 107.936328 102.301061)
		(size 0.5)
		(drill 0.2)
		(layers "F.Cu" "B.Cu")
		(net 5)
	)
	(via
		(at 107.936328 126.540269)
		(size 0.5)
		(drill 0.2)
		(layers "F.Cu" "B.Cu")
		(net 5)
	)
	(via
		(at 199.486328 101.020008)
		(size 0.5)
		(drill 0.2)
		(layers "F.Cu" "B.Cu")
		(net 5)
	)
	(via
		(at 111.8 109.5)
		(size 0.5)
		(drill 0.2)
		(layers "F.Cu" "B.Cu")
		(free yes)
		(net 5)
	)
	(via
		(at 112.49 98.55)
		(size 0.5)
		(drill 0.2)
		(layers "F.Cu" "B.Cu")
		(free yes)
		(net 5)
	)
	(via
		(at 167.907482 135.197157)
		(size 0.5)
		(drill 0.2)
		(layers "F.Cu" "B.Cu")
		(net 5)
	)
	(via
		(at 125.4475 98.1)
		(size 0.5)
		(drill 0.2)
		(layers "F.Cu" "B.Cu")
		(free yes)
		(net 5)
	)
	(via blind
		(at 149.661328 108.747157)
		(size 0.5)
		(drill 0.2)
		(layers "F.Cu" "In1.Cu")
		(net 5)
	)
	(via
		(at 138.4 105.4)
		(size 0.5)
		(drill 0.2)
		(layers "F.Cu" "B.Cu")
		(net 5)
	)
	(via
		(at 125 73.2)
		(size 0.5)
		(drill 0.2)
		(layers "F.Cu" "B.Cu")
		(free yes)
		(net 5)
	)
	(via
		(at 133 93.6)
		(size 0.5)
		(drill 0.2)
		(layers "F.Cu" "B.Cu")
		(net 5)
	)
	(via
		(at 125.2 91.025)
		(size 0.5)
		(drill 0.2)
		(layers "F.Cu" "B.Cu")
		(free yes)
		(net 5)
	)
	(via
		(at 182.470186 135.197157)
		(size 0.5)
		(drill 0.2)
		(layers "F.Cu" "B.Cu")
		(net 5)
	)
	(via
		(at 111.912806 87.075)
		(size 0.5)
		(drill 0.2)
		(layers "F.Cu" "B.Cu")
		(free yes)
		(net 5)
	)
	(via
		(at 114.9 119.3)
		(size 0.5)
		(drill 0.2)
		(layers "F.Cu" "B.Cu")
		(free yes)
		(net 5)
	)
	(via
		(at 110.6 109.5)
		(size 0.5)
		(drill 0.2)
		(layers "F.Cu" "B.Cu")
		(free yes)
		(net 5)
	)
	(via
		(at 190.364171 123.258485)
		(size 0.5)
		(drill 0.2)
		(layers "F.Cu" "B.Cu")
		(net 5)
	)
	(via
		(at 137.2 53.6)
		(size 0.5)
		(drill 0.2)
		(layers "F.Cu" "B.Cu")
		(free yes)
		(net 5)
	)
	(via
		(at 216.336328 107.618259)
		(size 0.5)
		(drill 0.2)
		(layers "F.Cu" "B.Cu")
		(net 5)
	)
	(via
		(at 114.14 98.55)
		(size 0.5)
		(drill 0.2)
		(layers "F.Cu" "B.Cu")
		(free yes)
		(net 5)
	)
	(via
		(at 125.8325 101.9)
		(size 0.5)
		(drill 0.2)
		(layers "F.Cu" "B.Cu")
		(free yes)
		(net 5)
	)
	(via
		(at 107.936328 65.942249)
		(size 0.5)
		(drill 0.2)
		(layers "F.Cu" "B.Cu")
		(net 5)
	)
	(via
		(at 216.336328 104.665051)
		(size 0.5)
		(drill 0.2)
		(layers "F.Cu" "B.Cu")
		(net 5)
	)
	(via
		(at 122 57.8)
		(size 0.5)
		(drill 0.2)
		(layers "F.Cu" "B.Cu")
		(free yes)
		(net 5)
	)
	(via
		(at 216.34 76.603584)
		(size 0.5)
		(drill 0.2)
		(layers "F.Cu" "B.Cu")
		(net 5)
	)
	(via
		(at 196.028837 46.897157)
		(size 0.5)
		(drill 0.2)
		(layers "F.Cu" "B.Cu")
		(net 5)
	)
	(via
		(at 213.086328 119.620008)
		(size 0.5)
		(drill 0.2)
		(layers "F.Cu" "B.Cu")
		(net 5)
	)
	(via
		(at 117.4 77)
		(size 0.5)
		(drill 0.2)
		(layers "F.Cu" "B.Cu")
		(free yes)
		(net 5)
	)
	(via
		(at 160.036328 87.997157)
		(size 0.5)
		(drill 0.2)
		(layers "F.Cu" "B.Cu")
		(net 5)
	)
	(via
		(at 123.15 87.125)
		(size 0.5)
		(drill 0.2)
		(layers "F.Cu" "B.Cu")
		(free yes)
		(net 5)
	)
	(via
		(at 113.525 101.9)
		(size 0.5)
		(drill 0.2)
		(layers "F.Cu" "B.Cu")
		(free yes)
		(net 5)
	)
	(via
		(at 193.392214 135.197157)
		(size 0.5)
		(drill 0.2)
		(layers "F.Cu" "B.Cu")
		(net 5)
	)
	(via
		(at 133.6 52.2)
		(size 0.5)
		(drill 0.2)
		(layers "F.Cu" "B.Cu")
		(free yes)
		(net 5)
	)
	(via
		(at 118.819376 46.897157)
		(size 0.5)
		(drill 0.2)
		(layers "F.Cu" "B.Cu")
		(net 5)
	)
	(via
		(at 216.336328 63.722525)
		(size 0.5)
		(drill 0.2)
		(layers "F.Cu" "B.Cu")
		(net 5)
	)
	(via
		(at 173.236328 83.297157)
		(size 0.5)
		(drill 0.2)
		(layers "F.Cu" "B.Cu")
		(net 5)
	)
	(via
		(at 127.860046 135.197157)
		(size 0.5)
		(drill 0.2)
		(layers "F.Cu" "B.Cu")
		(net 5)
	)
	(via
		(at 116.988868 46.897157)
		(size 0.5)
		(drill 0.2)
		(layers "F.Cu" "B.Cu")
		(net 5)
	)
	(via
		(at 114.012806 87.625)
		(size 0.5)
		(drill 0.2)
		(layers "F.Cu" "B.Cu")
		(free yes)
		(net 5)
	)
	(via
		(at 189.751538 135.197157)
		(size 0.5)
		(drill 0.2)
		(layers "F.Cu" "B.Cu")
		(net 5)
	)
	(via
		(at 124.8 87.125)
		(size 0.5)
		(drill 0.2)
		(layers "F.Cu" "B.Cu")
		(free yes)
		(net 5)
	)
	(via
		(at 126.6 73.2)
		(size 0.5)
		(drill 0.2)
		(layers "F.Cu" "B.Cu")
		(free yes)
		(net 5)
	)
	(via
		(at 144.243088 135.197157)
		(size 0.5)
		(drill 0.2)
		(layers "F.Cu" "B.Cu")
		(net 5)
	)
	(via
		(at 118.2 73.2)
		(size 0.5)
		(drill 0.2)
		(layers "F.Cu" "B.Cu")
		(free yes)
		(net 5)
	)
	(via
		(at 177.567507 46.897157)
		(size 0.5)
		(drill 0.2)
		(layers "F.Cu" "B.Cu")
		(net 5)
	)
	(via
		(at 191.786328 107.320008)
		(size 0.5)
		(drill 0.2)
		(layers "F.Cu" "B.Cu")
		(net 5)
	)
	(via
		(at 177.85 65.15)
		(size 0.5)
		(drill 0.2)
		(layers "F.Cu" "B.Cu")
		(net 5)
	)
	(via
		(at 157.621328 117.607157)
		(size 0.5)
		(drill 0.2)
		(layers "F.Cu" "B.Cu")
		(net 5)
	)
	(via blind
		(at 172.036329 85.997157)
		(size 0.5)
		(drill 0.2)
		(layers "F.Cu" "In1.Cu")
		(net 5)
	)
	(via
		(at 143.136328 114.137157)
		(size 0.5)
		(drill 0.2)
		(layers "F.Cu" "B.Cu")
		(net 5)
	)
	(via
		(at 146.05 108.1)
		(size 0.5)
		(drill 0.2)
		(layers "F.Cu" "B.Cu")
		(net 5)
	)
	(via
		(at 107.936328 57.285389)
		(size 0.5)
		(drill 0.2)
		(layers "F.Cu" "B.Cu")
		(net 5)
	)
	(via
		(at 107.936328 109.226549)
		(size 0.5)
		(drill 0.2)
		(layers "F.Cu" "B.Cu")
		(net 5)
	)
	(via
		(at 138.75 97.5)
		(size 0.5)
		(drill 0.2)
		(layers "F.Cu" "B.Cu")
		(net 5)
	)
	(via
		(at 136.8 72)
		(size 0.5)
		(drill 0.2)
		(layers "F.Cu" "B.Cu")
		(net 5)
	)
	(via
		(at 143.0325 86)
		(size 0.5)
		(drill 0.2)
		(layers "F.Cu" "B.Cu")
		(net 5)
	)
	(via
		(at 126.6 77)
		(size 0.5)
		(drill 0.2)
		(layers "F.Cu" "B.Cu")
		(free yes)
		(net 5)
	)
	(via
		(at 127.4 73.2)
		(size 0.5)
		(drill 0.2)
		(layers "F.Cu" "B.Cu")
		(free yes)
		(net 5)
	)
	(via
		(at 201.193894 98.313955)
		(size 0.5)
		(drill 0.2)
		(layers "F.Cu" "B.Cu")
		(net 5)
	)
	(via
		(at 216.336328 54.01917)
		(size 0.5)
		(drill 0.2)
		(layers "F.Cu" "B.Cu")
		(net 5)
	)
	(via blind
		(at 162.506054 84.866419)
		(size 0.5)
		(drill 0.2)
		(layers "F.Cu" "In1.Cu")
		(net 5)
	)
	(via
		(at 190.490438 46.897157)
		(size 0.5)
		(drill 0.2)
		(layers "F.Cu" "B.Cu")
		(net 5)
	)
	(via
		(at 216.336328 98.758635)
		(size 0.5)
		(drill 0.2)
		(layers "F.Cu" "B.Cu")
		(net 5)
	)
	(via
		(at 136.961736 135.197157)
		(size 0.5)
		(drill 0.2)
		(layers "F.Cu" "B.Cu")
		(net 5)
	)
	(via
		(at 175.026 130.844)
		(size 0.5)
		(drill 0.2)
		(layers "F.Cu" "B.Cu")
		(net 5)
	)
	(via
		(at 216.336328 113.524675)
		(size 0.5)
		(drill 0.2)
		(layers "F.Cu" "B.Cu")
		(net 5)
	)
	(via
		(at 134.1 61.6)
		(size 0.5)
		(drill 0.2)
		(layers "F.Cu" "B.Cu")
		(free yes)
		(net 5)
	)
	(via
		(at 120.649884 46.897157)
		(size 0.5)
		(drill 0.2)
		(layers "F.Cu" "B.Cu")
		(net 5)
	)
	(via
		(at 188.644305 46.897157)
		(size 0.5)
		(drill 0.2)
		(layers "F.Cu" "B.Cu")
		(net 5)
	)
	(via
		(at 137.9 72)
		(size 0.5)
		(drill 0.2)
		(layers "F.Cu" "B.Cu")
		(net 5)
	)
	(via
		(at 134.001328 125.027157)
		(size 0.5)
		(drill 0.2)
		(layers "F.Cu" "B.Cu")
		(net 5)
	)
	(via
		(at 206.586328 99.320008)
		(size 0.5)
		(drill 0.2)
		(layers "F.Cu" "B.Cu")
		(net 5)
	)
	(via
		(at 107.936328 124.808897)
		(size 0.5)
		(drill 0.2)
		(layers "F.Cu" "B.Cu")
		(net 5)
	)
	(via
		(at 107.936328 121.346153)
		(size 0.5)
		(drill 0.2)
		(layers "F.Cu" "B.Cu")
		(net 5)
	)
	(via
		(at 216.34 69.220564)
		(size 0.5)
		(drill 0.2)
		(layers "F.Cu" "B.Cu")
		(net 5)
	)
	(via
		(at 138.9 59.7)
		(size 0.5)
		(drill 0.2)
		(layers "F.Cu" "B.Cu")
		(net 5)
	)
	(via
		(at 118.2 77)
		(size 0.5)
		(drill 0.2)
		(layers "F.Cu" "B.Cu")
		(free yes)
		(net 5)
	)
	(via
		(at 138 102.3)
		(size 0.5)
		(drill 0.2)
		(layers "F.Cu" "B.Cu")
		(net 5)
	)
	(via
		(at 216.336328 120.907695)
		(size 0.5)
		(drill 0.2)
		(layers "F.Cu" "B.Cu")
		(net 5)
	)
	(via
		(at 107.936328 79.793225)
		(size 0.5)
		(drill 0.2)
		(layers "F.Cu" "B.Cu")
		(net 5)
	)
	(via
		(at 164.644576 46.897157)
		(size 0.5)
		(drill 0.2)
		(layers "F.Cu" "B.Cu")
		(net 5)
	)
	(via
		(at 147.883764 135.197157)
		(size 0.5)
		(drill 0.2)
		(layers "F.Cu" "B.Cu")
		(net 5)
	)
	(via
		(at 126.6 72.4)
		(size 0.5)
		(drill 0.2)
		(layers "F.Cu" "B.Cu")
		(free yes)
		(net 5)
	)
	(via
		(at 154.631328 126.687157)
		(size 0.5)
		(drill 0.2)
		(layers "F.Cu" "B.Cu")
		(net 5)
	)
	(via
		(at 117.4 116.2)
		(size 0.5)
		(drill 0.2)
		(layers "F.Cu" "B.Cu")
		(net 5)
	)
	(via
		(at 137.551328 128.187157)
		(size 0.5)
		(drill 0.2)
		(layers "F.Cu" "B.Cu")
		(net 5)
	)
	(via
		(at 112.947806 91.025)
		(size 0.5)
		(drill 0.2)
		(layers "F.Cu" "B.Cu")
		(free yes)
		(net 5)
	)
	(via
		(at 127.4 72.4)
		(size 0.5)
		(drill 0.2)
		(layers "F.Cu" "B.Cu")
		(free yes)
		(net 5)
	)
	(via
		(at 131.0825 100.55)
		(size 0.5)
		(drill 0.2)
		(layers "F.Cu" "B.Cu")
		(net 5)
	)
	(via
		(at 216.34 70.697168)
		(size 0.5)
		(drill 0.2)
		(layers "F.Cu" "B.Cu")
		(net 5)
	)
	(via blind
		(at 174.036329 84.997157)
		(size 0.5)
		(drill 0.2)
		(layers "F.Cu" "In1.Cu")
		(net 5)
	)
	(via
		(at 138.782074 135.197157)
		(size 0.5)
		(drill 0.2)
		(layers "F.Cu" "B.Cu")
		(net 5)
	)
	(via
		(at 107.936328 93.644201)
		(size 0.5)
		(drill 0.2)
		(layers "F.Cu" "B.Cu")
		(net 5)
	)
	(via
		(at 113.962806 86.625)
		(size 0.5)
		(drill 0.2)
		(layers "F.Cu" "B.Cu")
		(free yes)
		(net 5)
	)
	(via
		(at 147.4142 85.6156)
		(size 0.5)
		(drill 0.2)
		(layers "F.Cu" "B.Cu")
		(net 5)
	)
	(via
		(at 121.375 129.375)
		(size 0.5)
		(drill 0.2)
		(layers "F.Cu" "B.Cu")
		(net 5)
	)
	(via
		(at 112.89 98.1)
		(size 0.5)
		(drill 0.2)
		(layers "F.Cu" "B.Cu")
		(free yes)
		(net 5)
	)
	(via
		(at 183.536328 86.597157)
		(size 0.5)
		(drill 0.2)
		(layers "F.Cu" "B.Cu")
		(net 5)
	)
	(via
		(at 186 119.285)
		(size 0.5)
		(drill 0.2)
		(layers "F.Cu" "B.Cu")
		(net 5)
	)
	(via
		(at 138.4 110.2)
		(size 0.5)
		(drill 0.2)
		(layers "F.Cu" "B.Cu")
		(net 5)
	)
	(via
		(at 216.336328 100.235239)
		(size 0.5)
		(drill 0.2)
		(layers "F.Cu" "B.Cu")
		(net 5)
	)
	(via
		(at 107.936328 119.614781)
		(size 0.5)
		(drill 0.2)
		(layers "F.Cu" "B.Cu")
		(net 5)
	)
	(via
		(at 120.8 57)
		(size 0.5)
		(drill 0.2)
		(layers "F.Cu" "B.Cu")
		(free yes)
		(net 5)
	)
	(via
		(at 209.775256 135.197157)
		(size 0.5)
		(drill 0.2)
		(layers "F.Cu" "B.Cu")
		(net 5)
	)
	(via
		(at 114.9 118.1)
		(size 0.5)
		(drill 0.2)
		(layers "F.Cu" "B.Cu")
		(free yes)
		(net 5)
	)
	(via
		(at 122.9475 98.1)
		(size 0.5)
		(drill 0.2)
		(layers "F.Cu" "B.Cu")
		(free yes)
		(net 5)
	)
	(via
		(at 121.4 56.6)
		(size 0.5)
		(drill 0.2)
		(layers "F.Cu" "B.Cu")
		(free yes)
		(net 5)
	)
	(via
		(at 216.336328 123.860903)
		(size 0.5)
		(drill 0.2)
		(layers "F.Cu" "B.Cu")
		(net 5)
	)
	(via
		(at 188.45 112)
		(size 0.5)
		(drill 0.2)
		(layers "F.Cu" "B.Cu")
		(free yes)
		(net 5)
	)
	(via
		(at 118.797806 89.075)
		(size 0.5)
		(drill 0.2)
		(layers "F.Cu" "B.Cu")
		(net 5)
	)
	(via
		(at 200.673566 135.197157)
		(size 0.5)
		(drill 0.2)
		(layers "F.Cu" "B.Cu")
		(net 5)
	)
	(via
		(at 120.8 52.1)
		(size 0.5)
		(drill 0.2)
		(layers "F.Cu" "B.Cu")
		(net 5)
	)
	(via
		(at 171.548158 135.197157)
		(size 0.5)
		(drill 0.2)
		(layers "F.Cu" "B.Cu")
		(net 5)
	)
	(via
		(at 216.34 95.806792)
		(size 0.5)
		(drill 0.2)
		(layers "F.Cu" "B.Cu")
		(net 5)
	)
	(via
		(at 129.680384 135.197157)
		(size 0.5)
		(drill 0.2)
		(layers "F.Cu" "B.Cu")
		(net 5)
	)
	(via
		(at 197.686328 109.820008)
		(size 0.5)
		(drill 0.2)
		(layers "F.Cu" "B.Cu")
		(net 5)
	)
	(via
		(at 166.087144 135.197157)
		(size 0.5)
		(drill 0.2)
		(layers "F.Cu" "B.Cu")
		(net 5)
	)
	(via
		(at 177.185 131.479)
		(size 0.5)
		(drill 0.2)
		(layers "F.Cu" "B.Cu")
		(net 5)
	)
	(via blind
		(at 163.05 77.5)
		(size 0.5)
		(drill 0.2)
		(layers "F.Cu" "In1.Cu")
		(net 5)
	)
	(via
		(at 208.311328 100.745008)
		(size 0.5)
		(drill 0.2)
		(layers "F.Cu" "B.Cu")
		(net 5)
	)
	(via
		(at 216.336328 125.337507)
		(size 0.5)
		(drill 0.2)
		(layers "F.Cu" "B.Cu")
		(net 5)
	)
	(via
		(at 134.6 62.6)
		(size 0.5)
		(drill 0.2)
		(layers "F.Cu" "B.Cu")
		(free yes)
		(net 5)
	)
	(via
		(at 107.936328 59.016761)
		(size 0.5)
		(drill 0.2)
		(layers "F.Cu" "B.Cu")
		(net 5)
	)
	(via
		(at 216.336328 126.814111)
		(size 0.5)
		(drill 0.2)
		(layers "F.Cu" "B.Cu")
		(net 5)
	)
	(via
		(at 160.95231 46.897157)
		(size 0.5)
		(drill 0.2)
		(layers "F.Cu" "B.Cu")
		(net 5)
	)
	(via
		(at 116.661328 59.372157)
		(size 0.5)
		(drill 0.2)
		(layers "F.Cu" "B.Cu")
		(net 5)
	)
	(via
		(at 194.182704 46.897157)
		(size 0.5)
		(drill 0.2)
		(layers "F.Cu" "B.Cu")
		(net 5)
	)
	(via
		(at 208.306328 107.800008)
		(size 0.5)
		(drill 0.2)
		(layers "F.Cu" "B.Cu")
		(net 5)
	)
	(via
		(at 170.036327 105.997157)
		(size 0.5)
		(drill 0.2)
		(layers "F.Cu" "B.Cu")
		(net 5)
	)
	(via
		(at 147.4142 84.5156)
		(size 0.5)
		(drill 0.2)
		(layers "F.Cu" "B.Cu")
		(net 5)
	)
	(via
		(at 124.2 72.4)
		(size 0.5)
		(drill 0.2)
		(layers "F.Cu" "B.Cu")
		(free yes)
		(net 5)
	)
	(via
		(at 125.2 51.4)
		(size 0.5)
		(drill 0.2)
		(layers "F.Cu" "B.Cu")
		(net 5)
	)
	(via
		(at 129.802424 46.897157)
		(size 0.5)
		(drill 0.2)
		(layers "F.Cu" "B.Cu")
		(net 5)
	)
	(via
		(at 214.559179 98.170008)
		(size 0.5)
		(drill 0.2)
		(layers "F.Cu" "B.Cu")
		(net 5)
	)
	(via
		(at 126.141408 46.897157)
		(size 0.5)
		(drill 0.2)
		(layers "F.Cu" "B.Cu")
		(net 5)
	)
	(via
		(at 191.786328 98.920008)
		(size 0.5)
		(drill 0.2)
		(layers "F.Cu" "B.Cu")
		(net 5)
	)
	(via
		(at 201.567236 46.897157)
		(size 0.5)
		(drill 0.2)
		(layers "F.Cu" "B.Cu")
		(net 5)
	)
	(via
		(at 125 76.2)
		(size 0.5)
		(drill 0.2)
		(layers "F.Cu" "B.Cu")
		(free yes)
		(net 5)
	)
	(via
		(at 157.260044 46.897157)
		(size 0.5)
		(drill 0.2)
		(layers "F.Cu" "B.Cu")
		(net 5)
	)
	(via
		(at 122.3 52.1)
		(size 0.5)
		(drill 0.2)
		(layers "F.Cu" "B.Cu")
		(net 5)
	)
	(via
		(at 159.111328 117.647157)
		(size 0.5)
		(drill 0.2)
		(layers "F.Cu" "B.Cu")
		(net 5)
	)
	(via
		(at 107.936328 100.569689)
		(size 0.5)
		(drill 0.2)
		(layers "F.Cu" "B.Cu")
		(net 5)
	)
	(via
		(at 170.182975 46.897157)
		(size 0.5)
		(drill 0.2)
		(layers "F.Cu" "B.Cu")
		(net 5)
	)
	(via
		(at 120.8 58.6)
		(size 0.5)
		(drill 0.2)
		(layers "F.Cu" "B.Cu")
		(free yes)
		(net 5)
	)
	(via
		(at 188.45 113.65)
		(size 0.5)
		(drill 0.2)
		(layers "F.Cu" "B.Cu")
		(free yes)
		(net 5)
	)
	(via
		(at 201.086328 103.620008)
		(size 0.5)
		(drill 0.2)
		(layers "F.Cu" "B.Cu")
		(net 5)
	)
	(via
		(at 124.625 128.875)
		(size 0.5)
		(drill 0.2)
		(layers "F.Cu" "B.Cu")
		(net 5)
	)
	(via blind
		(at 157.286328 69.247157)
		(size 0.5)
		(drill 0.2)
		(layers "F.Cu" "In1.Cu")
		(net 5)
	)
	(via
		(at 216.336328 101.711843)
		(size 0.5)
		(drill 0.2)
		(layers "F.Cu" "B.Cu")
		(net 5)
	)
	(via
		(at 187.9312 135.197157)
		(size 0.5)
		(drill 0.2)
		(layers "F.Cu" "B.Cu")
		(net 5)
	)
	(via
		(at 139.865 101.745)
		(size 0.5)
		(drill 0.2)
		(layers "F.Cu" "B.Cu")
		(net 5)
	)
	(via
		(at 107.936328 55.554017)
		(size 0.5)
		(drill 0.2)
		(layers "F.Cu" "B.Cu")
		(net 5)
	)
	(via
		(at 137.8 54)
		(size 0.5)
		(drill 0.2)
		(layers "F.Cu" "B.Cu")
		(free yes)
		(net 5)
	)
	(via
		(at 125.25 86.675)
		(size 0.5)
		(drill 0.2)
		(layers "F.Cu" "B.Cu")
		(free yes)
		(net 5)
	)
	(via
		(at 131.8 51.8)
		(size 0.5)
		(drill 0.2)
		(layers "F.Cu" "B.Cu")
		(free yes)
		(net 5)
	)
	(via
		(at 118.4 112)
		(size 0.5)
		(drill 0.2)
		(layers "F.Cu" "B.Cu")
		(free yes)
		(net 5)
	)
	(via
		(at 119.375 100.55)
		(size 0.5)
		(drill 0.2)
		(layers "F.Cu" "B.Cu")
		(net 5)
	)
	(via
		(at 206.386328 80.520012)
		(size 0.5)
		(drill 0.2)
		(layers "F.Cu" "B.Cu")
		(net 5)
	)
	(via
		(at 125.8325 102.5)
		(size 0.5)
		(drill 0.2)
		(layers "F.Cu" "B.Cu")
		(free yes)
		(net 5)
	)
	(via
		(at 197.03289 135.197157)
		(size 0.5)
		(drill 0.2)
		(layers "F.Cu" "B.Cu")
		(net 5)
	)
	(via
		(at 216.336328 110.571467)
		(size 0.5)
		(drill 0.2)
		(layers "F.Cu" "B.Cu")
		(net 5)
	)
	(via
		(at 111.64 98.55)
		(size 0.5)
		(drill 0.2)
		(layers "F.Cu" "B.Cu")
		(free yes)
		(net 5)
	)
	(via
		(at 209.886328 69.920008)
		(size 0.5)
		(drill 0.2)
		(layers "F.Cu" "B.Cu")
		(net 5)
	)
	(via
		(at 125 77)
		(size 0.5)
		(drill 0.2)
		(layers "F.Cu" "B.Cu")
		(free yes)
		(net 5)
	)
	(via
		(at 191.1 107.7)
		(size 0.5)
		(drill 0.2)
		(layers "F.Cu" "B.Cu")
		(net 5)
	)
	(via
		(at 120.8 57.8)
		(size 0.5)
		(drill 0.2)
		(layers "F.Cu" "B.Cu")
		(free yes)
		(net 5)
	)
	(via
		(at 160.62613 135.197157)
		(size 0.5)
		(drill 0.2)
		(layers "F.Cu" "B.Cu")
		(net 5)
	)
	(via
		(at 193.586328 107.620008)
		(size 0.5)
		(drill 0.2)
		(layers "F.Cu" "B.Cu")
		(net 5)
	)
	(via
		(at 133.32106 135.197157)
		(size 0.5)
		(drill 0.2)
		(layers "F.Cu" "B.Cu")
		(net 5)
	)
	(via
		(at 199.268164 87.318164)
		(size 0.5)
		(drill 0.2)
		(layers "F.Cu" "B.Cu")
		(net 5)
	)
	(via
		(at 118.4 110.4)
		(size 0.5)
		(drill 0.2)
		(layers "F.Cu" "B.Cu")
		(free yes)
		(net 5)
	)
	(via
		(at 163.036328 105.997156)
		(size 0.5)
		(drill 0.2)
		(layers "F.Cu" "B.Cu")
		(net 5)
	)
	(via
		(at 216.336328 59.841183)
		(size 0.5)
		(drill 0.2)
		(layers "F.Cu" "B.Cu")
		(net 5)
	)
	(via
		(at 216.336328 109.094863)
		(size 0.5)
		(drill 0.2)
		(layers "F.Cu" "B.Cu")
		(net 5)
	)
	(via
		(at 205.486328 107.220008)
		(size 0.5)
		(drill 0.2)
		(layers "F.Cu" "B.Cu")
		(net 5)
	)
	(via
		(at 142.42275 135.197157)
		(size 0.5)
		(drill 0.2)
		(layers "F.Cu" "B.Cu")
		(net 5)
	)
	(via
		(at 147.0578 85.0512)
		(size 0.5)
		(drill 0.2)
		(layers "F.Cu" "B.Cu")
		(net 5)
	)
	(via
		(at 216.34 75.12698)
		(size 0.5)
		(drill 0.2)
		(layers "F.Cu" "B.Cu")
		(net 5)
	)
	(via
		(at 143.0325 91)
		(size 0.5)
		(drill 0.2)
		(layers "F.Cu" "B.Cu")
		(net 5)
	)
	(via
		(at 216.336328 52.078499)
		(size 0.5)
		(drill 0.2)
		(layers "F.Cu" "B.Cu")
		(net 5)
	)
	(via
		(at 125.8 91.025)
		(size 0.5)
		(drill 0.2)
		(layers "F.Cu" "B.Cu")
		(free yes)
		(net 5)
	)
	(via
		(at 124.9975 98.55)
		(size 0.5)
		(drill 0.2)
		(layers "F.Cu" "B.Cu")
		(free yes)
		(net 5)
	)
	(via
		(at 135.141398 135.197157)
		(size 0.5)
		(drill 0.2)
		(layers "F.Cu" "B.Cu")
		(net 5)
	)
	(via
		(at 113.7 119.9)
		(size 0.5)
		(drill 0.2)
		(layers "F.Cu" "B.Cu")
		(free yes)
		(net 5)
	)
	(via
		(at 181.259773 46.897157)
		(size 0.5)
		(drill 0.2)
		(layers "F.Cu" "B.Cu")
		(net 5)
	)
	(via
		(at 115.15836 46.897157)
		(size 0.5)
		(drill 0.2)
		(layers "F.Cu" "B.Cu")
		(net 5)
	)
	(via
		(at 115.3 119.9)
		(size 0.5)
		(drill 0.2)
		(layers "F.Cu" "B.Cu")
		(free yes)
		(net 5)
	)
	(via
		(at 107.936328 112.689293)
		(size 0.5)
		(drill 0.2)
		(layers "F.Cu" "B.Cu")
		(net 5)
	)
	(via
		(at 113.547806 90.425)
		(size 0.5)
		(drill 0.2)
		(layers "F.Cu" "B.Cu")
		(free yes)
		(net 5)
	)
	(via
		(at 178.82951 135.197157)
		(size 0.5)
		(drill 0.2)
		(layers "F.Cu" "B.Cu")
		(net 5)
	)
	(via
		(at 148.1 84.5)
		(size 0.5)
		(drill 0.2)
		(layers "F.Cu" "B.Cu")
		(net 5)
	)
	(via
		(at 126.05 86.675)
		(size 0.5)
		(drill 0.2)
		(layers "F.Cu" "B.Cu")
		(free yes)
		(net 5)
	)
	(via
		(at 216.34 92.853584)
		(size 0.5)
		(drill 0.2)
		(layers "F.Cu" "B.Cu")
		(net 5)
	)
	(via
		(at 184.05 114.035)
		(size 0.5)
		(drill 0.2)
		(layers "F.Cu" "B.Cu")
		(free yes)
		(net 5)
	)
	(via
		(at 124.5975 98.1)
		(size 0.5)
		(drill 0.2)
		(layers "F.Cu" "B.Cu")
		(free yes)
		(net 5)
	)
	(via
		(at 120.2 57.4)
		(size 0.5)
		(drill 0.2)
		(layers "F.Cu" "B.Cu")
		(free yes)
		(net 5)
	)
	(via
		(at 113.7 118.7)
		(size 0.5)
		(drill 0.2)
		(layers "F.Cu" "B.Cu")
		(free yes)
		(net 5)
	)
	(via
		(at 169.3935 119.541)
		(size 0.5)
		(drill 0.2)
		(layers "F.Cu" "B.Cu")
		(net 5)
	)
	(via
		(at 109.4 109.5)
		(size 0.5)
		(drill 0.2)
		(layers "F.Cu" "B.Cu")
		(free yes)
		(net 5)
	)
	(via
		(at 139.776328 115.797157)
		(size 0.5)
		(drill 0.2)
		(layers "F.Cu" "B.Cu")
		(net 5)
	)
	(via
		(at 120.578694 135.197157)
		(size 0.5)
		(drill 0.2)
		(layers "F.Cu" "B.Cu")
		(net 5)
	)
	(via
		(at 107.936328 91.912829)
		(size 0.5)
		(drill 0.2)
		(layers "F.Cu" "B.Cu")
		(net 5)
	)
	(via
		(at 109.036328 117.9)
		(size 0.5)
		(drill 0.2)
		(layers "F.Cu" "B.Cu")
		(net 5)
	)
	(via
		(at 184.65 113.435)
		(size 0.5)
		(drill 0.2)
		(layers "F.Cu" "B.Cu")
		(free yes)
		(net 5)
	)
	(via
		(at 124.2 76.2)
		(size 0.5)
		(drill 0.2)
		(layers "F.Cu" "B.Cu")
		(free yes)
		(net 5)
	)
	(via
		(at 195.212552 135.197157)
		(size 0.5)
		(drill 0.2)
		(layers "F.Cu" "B.Cu")
		(net 5)
	)
	(via
		(at 183.105906 46.897157)
		(size 0.5)
		(drill 0.2)
		(layers "F.Cu" "B.Cu")
		(net 5)
	)
	(via
		(at 201.586328 101.020008)
		(size 0.5)
		(drill 0.2)
		(layers "F.Cu" "B.Cu")
		(net 5)
	)
	(via
		(at 188 114.05)
		(size 0.5)
		(drill 0.2)
		(layers "F.Cu" "B.Cu")
		(free yes)
		(net 5)
	)
	(via
		(at 140.75 107.85)
		(size 0.5)
		(drill 0.2)
		(layers "F.Cu" "B.Cu")
		(net 5)
	)
	(via
		(at 188.45 112.8)
		(size 0.5)
		(drill 0.2)
		(layers "F.Cu" "B.Cu")
		(free yes)
		(net 5)
	)
	(via
		(at 133.46344 46.897157)
		(size 0.5)
		(drill 0.2)
		(layers "F.Cu" "B.Cu")
		(net 5)
	)
	(via
		(at 124.21937 135.197157)
		(size 0.5)
		(drill 0.2)
		(layers "F.Cu" "B.Cu")
		(net 5)
	)
	(via
		(at 143.8 101.7)
		(size 0.5)
		(drill 0.2)
		(layers "F.Cu" "B.Cu")
		(net 5)
	)
	(via
		(at 115.3 118.7)
		(size 0.5)
		(drill 0.2)
		(layers "F.Cu" "B.Cu")
		(free yes)
		(net 5)
	)
	(via
		(at 137.9 80.4)
		(size 0.5)
		(drill 0.2)
		(layers "F.Cu" "B.Cu")
		(net 5)
	)
	(via
		(at 121.4 58.2)
		(size 0.5)
		(drill 0.2)
		(layers "F.Cu" "B.Cu")
		(free yes)
		(net 5)
	)
	(via
		(at 168.93 125.891)
		(size 0.5)
		(drill 0.2)
		(layers "F.Cu" "B.Cu")
		(net 5)
	)
	(via
		(at 143 105.4)
		(size 0.5)
		(drill 0.2)
		(layers "F.Cu" "B.Cu")
		(net 5)
	)
	(via
		(at 144.446488 46.897157)
		(size 0.5)
		(drill 0.2)
		(layers "F.Cu" "B.Cu")
		(net 5)
	)
	(via
		(at 125.8 90.425)
		(size 0.5)
		(drill 0.2)
		(layers "F.Cu" "B.Cu")
		(free yes)
		(net 5)
	)
	(via
		(at 157.28632 87.670008)
		(size 0.5)
		(drill 0.2)
		(layers "F.Cu" "B.Cu")
		(net 5)
	)
	(via
		(at 137.536328 116.247157)
		(size 0.5)
		(drill 0.2)
		(layers "F.Cu" "B.Cu")
		(net 5)
	)
	(via
		(at 125.25 129.375)
		(size 0.5)
		(drill 0.2)
		(layers "F.Cu" "B.Cu")
		(net 5)
	)
	(via
		(at 205.259502 46.897157)
		(size 0.5)
		(drill 0.2)
		(layers "F.Cu" "B.Cu")
		(net 5)
	)
	(via
		(at 216.34 97.283396)
		(size 0.5)
		(drill 0.2)
		(layers "F.Cu" "B.Cu")
		(net 5)
	)
	(via
		(at 123.6 86.675)
		(size 0.5)
		(drill 0.2)
		(layers "F.Cu" "B.Cu")
		(free yes)
		(net 5)
	)
	(via
		(at 114.59 99.1)
		(size 0.5)
		(drill 0.2)
		(layers "F.Cu" "B.Cu")
		(free yes)
		(net 5)
	)
	(via
		(at 120.2 56.6)
		(size 0.5)
		(drill 0.2)
		(layers "F.Cu" "B.Cu")
		(free yes)
		(net 5)
	)
	(via
		(at 112.712806 87.075)
		(size 0.5)
		(drill 0.2)
		(layers "F.Cu" "B.Cu")
		(free yes)
		(net 5)
	)
	(via
		(at 114.5 119.9)
		(size 0.5)
		(drill 0.2)
		(layers "F.Cu" "B.Cu")
		(free yes)
		(net 5)
	)
	(via
		(at 156.985454 135.197157)
		(size 0.5)
		(drill 0.2)
		(layers "F.Cu" "B.Cu")
		(net 5)
	)
	(via
		(at 128.2 77)
		(size 0.5)
		(drill 0.2)
		(layers "F.Cu" "B.Cu")
		(free yes)
		(net 5)
	)
	(via
		(at 118.4 112.8)
		(size 0.5)
		(drill 0.2)
		(layers "F.Cu" "B.Cu")
		(free yes)
		(net 5)
	)
	(via
		(at 108.8 109.9)
		(size 0.5)
		(drill 0.2)
		(layers "F.Cu" "B.Cu")
		(free yes)
		(net 5)
	)
	(via
		(at 186.110862 135.197157)
		(size 0.5)
		(drill 0.2)
		(layers "F.Cu" "B.Cu")
		(net 5)
	)
	(via
		(at 123.25 128.875)
		(size 0.5)
		(drill 0.2)
		(layers "F.Cu" "B.Cu")
		(net 5)
	)
	(via
		(at 114.1 119.3)
		(size 0.5)
		(drill 0.2)
		(layers "F.Cu" "B.Cu")
		(free yes)
		(net 5)
	)
	(via
		(at 199.786328 102.620008)
		(size 0.5)
		(drill 0.2)
		(layers "F.Cu" "B.Cu")
		(net 5)
	)
	(via
		(at 125.8 72.4)
		(size 0.5)
		(drill 0.2)
		(layers "F.Cu" "B.Cu")
		(free yes)
		(net 5)
	)
	(via blind
		(at 180.036329 88.997157)
		(size 0.5)
		(drill 0.2)
		(layers "F.Cu" "In1.Cu")
		(net 5)
	)
	(via
		(at 151.52444 135.197157)
		(size 0.5)
		(drill 0.2)
		(layers "F.Cu" "B.Cu")
		(net 5)
	)
	(via
		(at 162.798443 46.897157)
		(size 0.5)
		(drill 0.2)
		(layers "F.Cu" "B.Cu")
		(net 5)
	)
	(via
		(at 113.562806 87.075)
		(size 0.5)
		(drill 0.2)
		(layers "F.Cu" "B.Cu")
		(free yes)
		(net 5)
	)
	(via
		(at 134.6 111.4)
		(size 0.5)
		(drill 0.2)
		(layers "F.Cu" "B.Cu")
		(net 5)
	)
	(via
		(at 188 111.55)
		(size 0.5)
		(drill 0.2)
		(layers "F.Cu" "B.Cu")
		(free yes)
		(net 5)
	)
	(via blind
		(at 172.036329 86.997157)
		(size 0.5)
		(drill 0.2)
		(layers "F.Cu" "In1.Cu")
		(net 5)
	)
	(via
		(at 128.2 73.2)
		(size 0.5)
		(drill 0.2)
		(layers "F.Cu" "B.Cu")
		(free yes)
		(net 5)
	)
	(via
		(at 197.87497 46.897157)
		(size 0.5)
		(drill 0.2)
		(layers "F.Cu" "B.Cu")
		(net 5)
	)
	(via
		(at 191.571876 135.197157)
		(size 0.5)
		(drill 0.2)
		(layers "F.Cu" "B.Cu")
		(net 5)
	)
	(via
		(at 113.29 98.55)
		(size 0.5)
		(drill 0.2)
		(layers "F.Cu" "B.Cu")
		(free yes)
		(net 5)
	)
	(via
		(at 107.936328 116.152037)
		(size 0.5)
		(drill 0.2)
		(layers "F.Cu" "B.Cu")
		(net 5)
	)
	(via
		(at 183.736328 97.897157)
		(size 0.5)
		(drill 0.2)
		(layers "F.Cu" "B.Cu")
		(net 5)
	)
	(via
		(at 132.4 52.2)
		(size 0.5)
		(drill 0.2)
		(layers "F.Cu" "B.Cu")
		(free yes)
		(net 5)
	)
	(via blind
		(at 180.191328 96.527157)
		(size 0.5)
		(drill 0.2)
		(layers "F.Cu" "In1.Cu")
		(net 5)
	)
	(via
		(at 162.036329 91.997158)
		(size 0.5)
		(drill 0.2)
		(layers "F.Cu" "B.Cu")
		(net 5)
	)
	(via
		(at 134.6 108.8)
		(size 0.5)
		(drill 0.2)
		(layers "F.Cu" "B.Cu")
		(net 5)
	)
	(via
		(at 149.938012 46.897157)
		(size 0.5)
		(drill 0.2)
		(layers "F.Cu" "B.Cu")
		(net 5)
	)
	(via
		(at 216.336328 103.188447)
		(size 0.5)
		(drill 0.2)
		(layers "F.Cu" "B.Cu")
		(net 5)
	)
	(via
		(at 107.936328 84.987341)
		(size 0.5)
		(drill 0.2)
		(layers "F.Cu" "B.Cu")
		(net 5)
	)
	(via
		(at 189.486328 103.224306)
		(size 0.5)
		(drill 0.2)
		(layers "F.Cu" "B.Cu")
		(net 5)
	)
	(via
		(at 107.936328 98.838317)
		(size 0.5)
		(drill 0.2)
		(layers "F.Cu" "B.Cu")
		(net 5)
	)
	(via
		(at 148.107504 46.897157)
		(size 0.5)
		(drill 0.2)
		(layers "F.Cu" "B.Cu")
		(net 5)
	)
	(via
		(at 166.490709 46.897157)
		(size 0.5)
		(drill 0.2)
		(layers "F.Cu" "B.Cu")
		(net 5)
	)
	(via
		(at 207.954918 135.197157)
		(size 0.5)
		(drill 0.2)
		(layers "F.Cu" "B.Cu")
		(net 5)
	)
	(via
		(at 216.336328 57.900512)
		(size 0.5)
		(drill 0.2)
		(layers "F.Cu" "B.Cu")
		(net 5)
	)
	(via
		(at 168.336842 46.897157)
		(size 0.5)
		(drill 0.2)
		(layers "F.Cu" "B.Cu")
		(net 5)
	)
	(via
		(at 112.4 109.9)
		(size 0.5)
		(drill 0.2)
		(layers "F.Cu" "B.Cu")
		(free yes)
		(net 5)
	)
	(via
		(at 210.797901 46.897157)
		(size 0.5)
		(drill 0.2)
		(layers "F.Cu" "B.Cu")
		(net 5)
	)
	(via
		(at 206.586328 107.220008)
		(size 0.5)
		(drill 0.2)
		(layers "F.Cu" "B.Cu")
		(net 5)
	)
	(via
		(at 154.15 65.2)
		(size 0.5)
		(drill 0.2)
		(layers "F.Cu" "B.Cu")
		(net 5)
	)
	(via
		(at 107.936328 107.495177)
		(size 0.5)
		(drill 0.2)
		(layers "F.Cu" "B.Cu")
		(net 5)
	)
	(via
		(at 128.2 72.4)
		(size 0.5)
		(drill 0.2)
		(layers "F.Cu" "B.Cu")
		(free yes)
		(net 5)
	)
	(via
		(at 107.936328 117.883409)
		(size 0.5)
		(drill 0.2)
		(layers "F.Cu" "B.Cu")
		(net 5)
	)
	(via
		(at 126.2475 98.1)
		(size 0.5)
		(drill 0.2)
		(layers "F.Cu" "B.Cu")
		(free yes)
		(net 5)
	)
	(via
		(at 111.24 98.1)
		(size 0.5)
		(drill 0.2)
		(layers "F.Cu" "B.Cu")
		(free yes)
		(net 5)
	)
	(via
		(at 125.65 54.05)
		(size 0.5)
		(drill 0.2)
		(layers "F.Cu" "B.Cu")
		(net 5)
	)
	(via
		(at 113 109.5)
		(size 0.5)
		(drill 0.2)
		(layers "F.Cu" "B.Cu")
		(free yes)
		(net 5)
	)
	(via
		(at 204.001328 95.925008)
		(size 0.5)
		(drill 0.2)
		(layers "F.Cu" "B.Cu")
		(net 5)
	)
	(via blind
		(at 176.036329 84.997157)
		(size 0.5)
		(drill 0.2)
		(layers "F.Cu" "In1.Cu")
		(net 5)
	)
	(via
		(at 157.641328 126.687157)
		(size 0.5)
		(drill 0.2)
		(layers "F.Cu" "B.Cu")
		(net 5)
	)
	(via
		(at 133.8 104.8)
		(size 0.5)
		(drill 0.2)
		(layers "F.Cu" "B.Cu")
		(net 5)
	)
	(via
		(at 114.1 118.1)
		(size 0.5)
		(drill 0.2)
		(layers "F.Cu" "B.Cu")
		(free yes)
		(net 5)
	)
	(via
		(at 124.2 77)
		(size 0.5)
		(drill 0.2)
		(layers "F.Cu" "B.Cu")
		(free yes)
		(net 5)
	)
	(via
		(at 200.486328 101.020008)
		(size 0.5)
		(drill 0.2)
		(layers "F.Cu" "B.Cu")
		(net 5)
	)
	(via
		(at 163 94)
		(size 0.5)
		(drill 0.2)
		(layers "F.Cu" "B.Cu")
		(net 5)
	)
	(via
		(at 201.690783 110.400079)
		(size 0.5)
		(drill 0.2)
		(layers "F.Cu" "B.Cu")
		(net 5)
	)
	(via
		(at 146.703 84.5156)
		(size 0.5)
		(drill 0.2)
		(layers "F.Cu" "B.Cu")
		(net 5)
	)
	(via
		(at 134.1 62.3)
		(size 0.5)
		(drill 0.2)
		(layers "F.Cu" "B.Cu")
		(free yes)
		(net 5)
	)
	(via
		(at 127.971916 46.897157)
		(size 0.5)
		(drill 0.2)
		(layers "F.Cu" "B.Cu")
		(net 5)
	)
	(via
		(at 128.2 76.2)
		(size 0.5)
		(drill 0.2)
		(layers "F.Cu" "B.Cu")
		(free yes)
		(net 5)
	)
	(via
		(at 169.184 131.606)
		(size 0.5)
		(drill 0.2)
		(layers "F.Cu" "B.Cu")
		(net 5)
	)
	(via
		(at 173.368496 135.197157)
		(size 0.5)
		(drill 0.2)
		(layers "F.Cu" "B.Cu")
		(net 5)
	)
	(via
		(at 123.9 61.5)
		(size 0.5)
		(drill 0.2)
		(layers "F.Cu" "B.Cu")
		(net 5)
	)
	(via
		(at 113.3 119.3)
		(size 0.5)
		(drill 0.2)
		(layers "F.Cu" "B.Cu")
		(free yes)
		(net 5)
	)
	(via
		(at 125.8 77)
		(size 0.5)
		(drill 0.2)
		(layers "F.Cu" "B.Cu")
		(free yes)
		(net 5)
	)
	(via
		(at 110 109.9)
		(size 0.5)
		(drill 0.2)
		(layers "F.Cu" "B.Cu")
		(free yes)
		(net 5)
	)
	(via
		(at 124 87.125)
		(size 0.5)
		(drill 0.2)
		(layers "F.Cu" "B.Cu")
		(free yes)
		(net 5)
	)
	(via
		(at 143.2 110.4)
		(size 0.5)
		(drill 0.2)
		(layers "F.Cu" "B.Cu")
		(net 5)
	)
	(via
		(at 143 83.6)
		(size 0.5)
		(drill 0.2)
		(layers "F.Cu" "B.Cu")
		(net 5)
	)
	(via
		(at 112.312806 86.625)
		(size 0.5)
		(drill 0.2)
		(layers "F.Cu" "B.Cu")
		(free yes)
		(net 5)
	)
	(via
		(at 137.2 52.6)
		(size 0.5)
		(drill 0.2)
		(layers "F.Cu" "B.Cu")
		(free yes)
		(net 5)
	)
	(via
		(at 216.336328 128.290715)
		(size 0.5)
		(drill 0.2)
		(layers "F.Cu" "B.Cu")
		(net 5)
	)
	(via
		(at 191.786328 99.820008)
		(size 0.5)
		(drill 0.2)
		(layers "F.Cu" "B.Cu")
		(net 5)
	)
	(via
		(at 134.8 65.7)
		(size 0.5)
		(drill 0.2)
		(layers "F.Cu" "B.Cu")
		(net 5)
	)
	(via
		(at 138.3 65.7)
		(size 0.5)
		(drill 0.2)
		(layers "F.Cu" "B.Cu")
		(net 5)
	)
	(via
		(at 111.2 109.9)
		(size 0.5)
		(drill 0.2)
		(layers "F.Cu" "B.Cu")
		(free yes)
		(net 5)
	)
	(via
		(at 137.286328 113.997157)
		(size 0.5)
		(drill 0.2)
		(layers "F.Cu" "B.Cu")
		(net 5)
	)
	(via
		(at 180.614 131.479)
		(size 0.5)
		(drill 0.2)
		(layers "F.Cu" "B.Cu")
		(net 5)
	)
	(via
		(at 164.266806 135.197157)
		(size 0.5)
		(drill 0.2)
		(layers "F.Cu" "B.Cu")
		(net 5)
	)
	(via
		(at 216.336328 112.048071)
		(size 0.5)
		(drill 0.2)
		(layers "F.Cu" "B.Cu")
		(net 5)
	)
	(via
		(at 154.621328 117.567157)
		(size 0.5)
		(drill 0.2)
		(layers "F.Cu" "B.Cu")
		(net 5)
	)
	(via
		(at 107.936328 110.957921)
		(size 0.5)
		(drill 0.2)
		(layers "F.Cu" "B.Cu")
		(free yes)
		(net 5)
	)
	(via
		(at 159.151328 126.687157)
		(size 0.5)
		(drill 0.2)
		(layers "F.Cu" "B.Cu")
		(net 5)
	)
	(via
		(at 172.359 112.81)
		(size 0.5)
		(drill 0.2)
		(layers "F.Cu" "B.Cu")
		(net 5)
	)
	(via
		(at 206.13458 135.197157)
		(size 0.5)
		(drill 0.2)
		(layers "F.Cu" "B.Cu")
		(net 5)
	)
	(via
		(at 175.188834 135.197157)
		(size 0.5)
		(drill 0.2)
		(layers "F.Cu" "B.Cu")
		(net 5)
	)
	(via
		(at 124.3109 46.897157)
		(size 0.5)
		(drill 0.2)
		(layers "F.Cu" "B.Cu")
		(net 5)
	)
	(via
		(at 136.8 80.4)
		(size 0.5)
		(drill 0.2)
		(layers "F.Cu" "B.Cu")
		(net 5)
	)
	(via
		(at 216.336328 119.431091)
		(size 0.5)
		(drill 0.2)
		(layers "F.Cu" "B.Cu")
		(net 5)
	)
	(via
		(at 184.05 113.435)
		(size 0.5)
		(drill 0.2)
		(layers "F.Cu" "B.Cu")
		(free yes)
		(net 5)
	)
	(via
		(at 202.493904 135.197157)
		(size 0.5)
		(drill 0.2)
		(layers "F.Cu" "B.Cu")
		(net 5)
	)
	(via
		(at 181.4585 115.731)
		(size 0.5)
		(drill 0.2)
		(layers "F.Cu" "B.Cu")
		(net 5)
	)
	(via
		(at 107.936328 69.404993)
		(size 0.5)
		(drill 0.2)
		(layers "F.Cu" "B.Cu")
		(net 5)
	)
	(via
		(at 107.936328 128.271641)
		(size 0.5)
		(drill 0.2)
		(layers "F.Cu" "B.Cu")
		(net 5)
	)
	(via blind
		(at 178.036329 84.997157)
		(size 0.5)
		(drill 0.2)
		(layers "F.Cu" "In1.Cu")
		(net 5)
	)
	(via
		(at 121.4 57.4)
		(size 0.5)
		(drill 0.2)
		(layers "F.Cu" "B.Cu")
		(free yes)
		(net 5)
	)
	(via
		(at 123.9 63.1)
		(size 0.5)
		(drill 0.2)
		(layers "F.Cu" "B.Cu")
		(net 5)
	)
	(via
		(at 180.649848 135.197157)
		(size 0.5)
		(drill 0.2)
		(layers "F.Cu" "B.Cu")
		(net 5)
	)
	(via
		(at 124.1975 98.55)
		(size 0.5)
		(drill 0.2)
		(layers "F.Cu" "B.Cu")
		(free yes)
		(net 5)
	)
	(via
		(at 122.6 58.2)
		(size 0.5)
		(drill 0.2)
		(layers "F.Cu" "B.Cu")
		(free yes)
		(net 5)
	)
	(via
		(at 127.4 77)
		(size 0.5)
		(drill 0.2)
		(layers "F.Cu" "B.Cu")
		(free yes)
		(net 5)
	)
	(via
		(at 107.936328 71.136365)
		(size 0.5)
		(drill 0.2)
		(layers "F.Cu" "B.Cu")
		(net 5)
	)
	(via
		(at 149.704102 135.197157)
		(size 0.5)
		(drill 0.2)
		(layers "F.Cu" "B.Cu")
		(net 5)
	)
	(via
		(at 147.769 83.9512)
		(size 0.5)
		(drill 0.2)
		(layers "F.Cu" "B.Cu")
		(net 5)
	)
	(via
		(at 156.15 84.175)
		(size 0.5)
		(drill 0.2)
		(layers "F.Cu" "B.Cu")
		(net 5)
	)
	(via
		(at 107.936328 114.420665)
		(size 0.5)
		(drill 0.2)
		(layers "F.Cu" "B.Cu")
		(net 5)
	)
	(via
		(at 111.512806 86.625)
		(size 0.5)
		(drill 0.2)
		(layers "F.Cu" "B.Cu")
		(free yes)
		(net 5)
	)
	(via blind
		(at 172.036329 84.997157)
		(size 0.5)
		(drill 0.2)
		(layers "F.Cu" "In1.Cu")
		(net 5)
	)
	(via
		(at 125 72.4)
		(size 0.5)
		(drill 0.2)
		(layers "F.Cu" "B.Cu")
		(free yes)
		(net 5)
	)
	(via
		(at 107.936328 86.718713)
		(size 0.5)
		(drill 0.2)
		(layers "F.Cu" "B.Cu")
		(net 5)
	)
	(via
		(at 146.063426 135.197157)
		(size 0.5)
		(drill 0.2)
		(layers "F.Cu" "B.Cu")
		(net 5)
	)
	(via
		(at 113.162806 86.625)
		(size 0.5)
		(drill 0.2)
		(layers "F.Cu" "B.Cu")
		(free yes)
		(net 5)
	)
	(via
		(at 136.6 52.2)
		(size 0.5)
		(drill 0.2)
		(layers "F.Cu" "B.Cu")
		(free yes)
		(net 5)
	)
	(via
		(at 193.786328 103.224306)
		(size 0.5)
		(drill 0.2)
		(layers "F.Cu" "B.Cu")
		(net 5)
	)
	(via
		(at 125.8475 98.55)
		(size 0.5)
		(drill 0.2)
		(layers "F.Cu" "B.Cu")
		(free yes)
		(net 5)
	)
	(via
		(at 146.703 85.6156)
		(size 0.5)
		(drill 0.2)
		(layers "F.Cu" "B.Cu")
		(net 5)
	)
	(via
		(at 107.936328 72.867737)
		(size 0.5)
		(drill 0.2)
		(layers "F.Cu" "B.Cu")
		(net 5)
	)
	(via
		(at 206.586328 102.720008)
		(size 0.5)
		(drill 0.2)
		(layers "F.Cu" "B.Cu")
		(net 5)
	)
	(via
		(at 169.311 120.938)
		(size 0.5)
		(drill 0.2)
		(layers "F.Cu" "B.Cu")
		(net 5)
	)
	(via
		(at 126.25 87.575)
		(size 0.5)
		(drill 0.2)
		(layers "F.Cu" "B.Cu")
		(free yes)
		(net 5)
	)
	(via
		(at 107.936328 104.032433)
		(size 0.5)
		(drill 0.2)
		(layers "F.Cu" "B.Cu")
		(net 5)
	)
	(via
		(at 136.036328 114.372157)
		(size 0.5)
		(drill 0.2)
		(layers "F.Cu" "B.Cu")
		(net 5)
	)
	(via
		(at 113.547806 91.025)
		(size 0.5)
		(drill 0.2)
		(layers "F.Cu" "B.Cu")
		(free yes)
		(net 5)
	)
	(via
		(at 125.2325 101.9)
		(size 0.5)
		(drill 0.2)
		(layers "F.Cu" "B.Cu")
		(free yes)
		(net 5)
	)
	(via
		(at 180.986328 111.320008)
		(size 0.5)
		(drill 0.2)
		(layers "F.Cu" "B.Cu")
		(net 5)
	)
	(via
		(at 107.936328 81.524597)
		(size 0.5)
		(drill 0.2)
		(layers "F.Cu" "B.Cu")
		(net 5)
	)
	(via
		(at 118.758356 135.197157)
		(size 0.5)
		(drill 0.2)
		(layers "F.Cu" "B.Cu")
		(net 5)
	)
	(via
		(at 131.500722 135.197157)
		(size 0.5)
		(drill 0.2)
		(layers "F.Cu" "B.Cu")
		(net 5)
	)
	(via
		(at 216.34 89.900376)
		(size 0.5)
		(drill 0.2)
		(layers "F.Cu" "B.Cu")
		(net 5)
	)
	(via
		(at 216.336328 116.477883)
		(size 0.5)
		(drill 0.2)
		(layers "F.Cu" "B.Cu")
		(net 5)
	)
	(via
		(at 122.399032 135.197157)
		(size 0.5)
		(drill 0.2)
		(layers "F.Cu" "B.Cu")
		(net 5)
	)
	(via
		(at 179.6 55.7)
		(size 0.5)
		(drill 0.2)
		(layers "F.Cu" "B.Cu")
		(net 5)
	)
	(via
		(at 117.4 73.2)
		(size 0.5)
		(drill 0.2)
		(layers "F.Cu" "B.Cu")
		(free yes)
		(net 5)
	)
	(via
		(at 110.662806 86.625)
		(size 0.5)
		(drill 0.2)
		(layers "F.Cu" "B.Cu")
		(free yes)
		(net 5)
	)
	(via
		(at 123.4 52)
		(size 0.5)
		(drill 0.2)
		(layers "F.Cu" "B.Cu")
		(net 5)
	)
	(via
		(at 137 97.5)
		(size 0.5)
		(drill 0.2)
		(layers "F.Cu" "B.Cu")
		(net 5)
	)
	(via
		(at 107.936328 67.673621)
		(size 0.5)
		(drill 0.2)
		(layers "F.Cu" "B.Cu")
		(net 5)
	)
	(via
		(at 107.936328 123.077525)
		(size 0.5)
		(drill 0.2)
		(layers "F.Cu" "B.Cu")
		(net 5)
	)
	(via
		(at 156.111328 117.567157)
		(size 0.5)
		(drill 0.2)
		(layers "F.Cu" "B.Cu")
		(net 5)
	)
	(via
		(at 127.4 76.2)
		(size 0.5)
		(drill 0.2)
		(layers "F.Cu" "B.Cu")
		(free yes)
		(net 5)
	)
	(via
		(at 107.936328 76.330481)
		(size 0.5)
		(drill 0.2)
		(layers "F.Cu" "B.Cu")
		(net 5)
	)
	(via
		(at 216.336328 61.781854)
		(size 0.5)
		(drill 0.2)
		(layers "F.Cu" "B.Cu")
		(net 5)
	)
	(via
		(at 127.25 68.3)
		(size 0.5)
		(drill 0.2)
		(layers "F.Cu" "B.Cu")
		(net 5)
	)
	(via
		(at 175.721374 46.897157)
		(size 0.5)
		(drill 0.2)
		(layers "F.Cu" "B.Cu")
		(net 5)
	)
	(via
		(at 203.413369 46.897157)
		(size 0.5)
		(drill 0.2)
		(layers "F.Cu" "B.Cu")
		(net 5)
	)
	(via
		(at 184.290524 135.197157)
		(size 0.5)
		(drill 0.2)
		(layers "F.Cu" "B.Cu")
		(net 5)
	)
	(via
		(at 107.936328 83.255969)
		(size 0.5)
		(drill 0.2)
		(layers "F.Cu" "B.Cu")
		(free yes)
		(net 5)
	)
	(via
		(at 109.036328 116.775)
		(size 0.5)
		(drill 0.2)
		(layers "F.Cu" "B.Cu")
		(net 5)
	)
	(via blind
		(at 180.036329 84.997157)
		(size 0.5)
		(drill 0.2)
		(layers "F.Cu" "In1.Cu")
		(net 5)
	)
	(via
		(at 143.0325 88.5)
		(size 0.5)
		(drill 0.2)
		(layers "F.Cu" "B.Cu")
		(net 5)
	)
	(via
		(at 216.336328 117.954487)
		(size 0.5)
		(drill 0.2)
		(layers "F.Cu" "B.Cu")
		(net 5)
	)
	(via
		(at 131.2 52.2)
		(size 0.5)
		(drill 0.2)
		(layers "F.Cu" "B.Cu")
		(free yes)
		(net 5)
	)
	(via
		(at 198.853228 135.197157)
		(size 0.5)
		(drill 0.2)
		(layers "F.Cu" "B.Cu")
		(net 5)
	)
	(via
		(at 118.2 72.4)
		(size 0.5)
		(drill 0.2)
		(layers "F.Cu" "B.Cu")
		(free yes)
		(net 5)
	)
	(via
		(at 216.336328 55.959841)
		(size 0.5)
		(drill 0.2)
		(layers "F.Cu" "B.Cu")
		(net 5)
	)
	(via
		(at 199.786328 103.620008)
		(size 0.5)
		(drill 0.2)
		(layers "F.Cu" "B.Cu")
		(net 5)
	)
	(via
		(at 125.8 73.2)
		(size 0.5)
		(drill 0.2)
		(layers "F.Cu" "B.Cu")
		(free yes)
		(net 5)
	)
	(via
		(at 113.74 98.1)
		(size 0.5)
		(drill 0.2)
		(layers "F.Cu" "B.Cu")
		(free yes)
		(net 5)
	)
	(via
		(at 201.086328 102.620008)
		(size 0.5)
		(drill 0.2)
		(layers "F.Cu" "B.Cu")
		(net 5)
	)
	(via
		(at 142.61598 46.897157)
		(size 0.5)
		(drill 0.2)
		(layers "F.Cu" "B.Cu")
		(net 5)
	)
	(via
		(at 216.34 72.173772)
		(size 0.5)
		(drill 0.2)
		(layers "F.Cu" "B.Cu")
		(net 5)
	)
	(via
		(at 130.6 51.8)
		(size 0.5)
		(drill 0.2)
		(layers "F.Cu" "B.Cu")
		(free yes)
		(net 5)
	)
	(via
		(at 137.124456 46.897157)
		(size 0.5)
		(drill 0.2)
		(layers "F.Cu" "B.Cu")
		(net 5)
	)
	(via
		(at 158.805792 135.197157)
		(size 0.5)
		(drill 0.2)
		(layers "F.Cu" "B.Cu")
		(net 5)
	)
	(via
		(at 190.886328 99.820008)
		(size 0.5)
		(drill 0.2)
		(layers "F.Cu" "B.Cu")
		(net 5)
	)
	(via
		(at 114.125 101.9)
		(size 0.5)
		(drill 0.2)
		(layers "F.Cu" "B.Cu")
		(free yes)
		(net 5)
	)
	(via
		(at 198.486328 101.020008)
		(size 0.5)
		(drill 0.2)
		(layers "F.Cu" "B.Cu")
		(net 5)
	)
	(via
		(at 199.3 85.5)
		(size 0.5)
		(drill 0.2)
		(layers "F.Cu" "B.Cu")
		(net 5)
	)
	(via
		(at 187.45 114.5)
		(size 0.5)
		(drill 0.2)
		(layers "F.Cu" "B.Cu")
		(free yes)
		(net 5)
	)
	(via
		(at 137.4 51.8)
		(size 0.5)
		(drill 0.2)
		(layers "F.Cu" "B.Cu")
		(free yes)
		(net 5)
	)
	(via
		(at 125.2 90.425)
		(size 0.5)
		(drill 0.2)
		(layers "F.Cu" "B.Cu")
		(free yes)
		(net 5)
	)
	(via
		(at 132.661328 117.122157)
		(size 0.5)
		(drill 0.2)
		(layers "F.Cu" "B.Cu")
		(net 5)
	)
	(via
		(at 172.029108 46.897157)
		(size 0.5)
		(drill 0.2)
		(layers "F.Cu" "B.Cu")
		(net 5)
	)
	(via
		(at 207.904527 75.638207)
		(size 0.5)
		(drill 0.2)
		(layers "F.Cu" "B.Cu")
		(net 5)
	)
	(via
		(at 137.286328 115.122157)
		(size 0.5)
		(drill 0.2)
		(layers "F.Cu" "B.Cu")
		(net 5)
	)
	(via
		(at 126.039708 135.197157)
		(size 0.5)
		(drill 0.2)
		(layers "F.Cu" "B.Cu")
		(net 5)
	)
	(via
		(at 113.297342 135.197157)
		(size 0.5)
		(drill 0.2)
		(layers "F.Cu" "B.Cu")
		(net 5)
	)
	(via
		(at 118.4 113.6)
		(size 0.5)
		(drill 0.2)
		(layers "F.Cu" "B.Cu")
		(free yes)
		(net 5)
	)
	(via
		(at 124.2 73.2)
		(size 0.5)
		(drill 0.2)
		(layers "F.Cu" "B.Cu")
		(free yes)
		(net 5)
	)
	(via
		(at 204.786328 109.320008)
		(size 0.5)
		(drill 0.2)
		(layers "F.Cu" "B.Cu")
		(net 5)
	)
	(via
		(at 171.536328 80.247157)
		(size 0.5)
		(drill 0.2)
		(layers "F.Cu" "B.Cu")
		(net 5)
	)
	(via
		(at 160.036328 88.997157)
		(size 0.5)
		(drill 0.2)
		(layers "F.Cu" "B.Cu")
		(net 5)
	)
	(via
		(at 133.8 103.8)
		(size 0.5)
		(drill 0.2)
		(layers "F.Cu" "B.Cu")
		(net 5)
	)
	(via
		(at 107.936328 95.375573)
		(size 0.5)
		(drill 0.2)
		(layers "F.Cu" "B.Cu")
		(net 5)
	)
	(via
		(at 114.54 98.1)
		(size 0.5)
		(drill 0.2)
		(layers "F.Cu" "B.Cu")
		(free yes)
		(net 5)
	)
	(via
		(at 111.062806 87.075)
		(size 0.5)
		(drill 0.2)
		(layers "F.Cu" "B.Cu")
		(free yes)
		(net 5)
	)
	(via
		(at 112.09 98.1)
		(size 0.5)
		(drill 0.2)
		(layers "F.Cu" "B.Cu")
		(free yes)
		(net 5)
	)
	(via blind
		(at 159.05 77.5)
		(size 0.5)
		(drill 0.2)
		(layers "F.Cu" "In1.Cu")
		(net 5)
	)
	(via
		(at 184.952039 46.897157)
		(size 0.5)
		(drill 0.2)
		(layers "F.Cu" "B.Cu")
		(net 5)
	)
	(via
		(at 159.106177 46.897157)
		(size 0.5)
		(drill 0.2)
		(layers "F.Cu" "B.Cu")
		(net 5)
	)
	(via
		(at 138.954964 46.897157)
		(size 0.5)
		(drill 0.2)
		(layers "F.Cu" "B.Cu")
		(net 5)
	)
	(via
		(at 126.2975 99.1)
		(size 0.5)
		(drill 0.2)
		(layers "F.Cu" "B.Cu")
		(free yes)
		(net 5)
	)
	(via
		(at 174.4 81.8)
		(size 0.5)
		(drill 0.2)
		(layers "F.Cu" "B.Cu")
		(net 5)
	)
	(via
		(at 135.881328 124.957157)
		(size 0.5)
		(drill 0.2)
		(layers "F.Cu" "B.Cu")
		(net 5)
	)
	(via
		(at 133 51.8)
		(size 0.5)
		(drill 0.2)
		(layers "F.Cu" "B.Cu")
		(free yes)
		(net 5)
	)
	(via
		(at 115.11768 135.197157)
		(size 0.5)
		(drill 0.2)
		(layers "F.Cu" "B.Cu")
		(net 5)
	)
	(via
		(at 112 120.7)
		(size 0.5)
		(drill 0.2)
		(layers "F.Cu" "B.Cu")
		(net 5)
	)
	(via
		(at 147.0578 83.9512)
		(size 0.5)
		(drill 0.2)
		(layers "F.Cu" "B.Cu")
		(net 5)
	)
	(via
		(at 125.2325 102.5)
		(size 0.5)
		(drill 0.2)
		(layers "F.Cu" "B.Cu")
		(free yes)
		(net 5)
	)
	(via
		(at 188 112.4)
		(size 0.5)
		(drill 0.2)
		(layers "F.Cu" "B.Cu")
		(free yes)
		(net 5)
	)
	(via
		(at 148.1 85.6)
		(size 0.5)
		(drill 0.2)
		(layers "F.Cu" "B.Cu")
		(net 5)
	)
	(via
		(at 151.661328 126.717157)
		(size 0.5)
		(drill 0.2)
		(layers "F.Cu" "B.Cu")
		(net 5)
	)
	(via
		(at 188.45 114.45)
		(size 0.5)
		(drill 0.2)
		(layers "F.Cu" "B.Cu")
		(free yes)
		(net 5)
	)
	(via
		(at 204.001328 97.540008)
		(size 0.5)
		(drill 0.2)
		(layers "F.Cu" "B.Cu")
		(net 5)
	)
	(via
		(at 139.7 61.6)
		(size 0.5)
		(drill 0.2)
		(layers "F.Cu" "B.Cu")
		(free yes)
		(net 5)
	)
	(segment
		(start 160.036328 87.997157)
		(end 160.036328 87.297157)
		(width 0.15)
		(layer "B.Cu")
		(net 5)
	)
	(segment
		(start 175.036328 94.797157)
		(end 175.036328 93.997157)
		(width 0.2)
		(layer "B.Cu")
		(net 5)
	)
	(segment
		(start 171.191328 95.622157)
		(end 171.191328 95.152155)
		(width 0.15)
		(layer "B.Cu")
		(net 5)
	)
	(segment
		(start 166.356328 98.372157)
		(end 166.411329 98.372157)
		(width 0.15)
		(layer "B.Cu")
		(net 5)
	)
	(segment
		(start 194.005626 103.005008)
		(end 193.786328 103.224306)
		(width 0.2)
		(layer "B.Cu")
		(net 5)
	)
	(segment
		(start 171.036329 88.997157)
		(end 170.536328 89.497157)
		(width 0.15)
		(layer "B.Cu")
		(net 5)
	)
	(segment
		(start 164.036329 101.997156)
		(end 164.857156 101.997156)
		(width 0.2)
		(layer "B.Cu")
		(net 5)
	)
	(segment
		(start 151.184758 98.786872)
		(end 150.247272 98.786872)
		(width 0.15)
		(layer "B.Cu")
		(net 5)
	)
	(segment
		(start 167.856329 94.817157)
		(end 168.036329 94.997157)
		(width 0.15)
		(layer "B.Cu")
		(net 5)
	)
	(segment
		(start 163.015 105.125)
		(end 163.015 105.975828)
		(width 0.2)
		(layer "B.Cu")
		(net 5)
	)
	(segment
		(start 174.985 103.94583)
		(end 175.036327 103.997157)
		(width 0.2)
		(layer "B.Cu")
		(net 5)
	)
	(segment
		(start 199.126328 97.930008)
		(end 199.516328 97.540008)
		(width 0.2)
		(layer "B.Cu")
		(net 5)
	)
	(segment
		(start 161.25 91.695)
		(end 160.554171 91.695)
		(width 0.2)
		(layer "B.Cu")
		(net 5)
	)
	(segment
		(start 159.015 103.125)
		(end 159.015 103.975827)
		(width 0.2)
		(layer "B.Cu")
		(net 5)
	)
	(segment
		(start 196.686328 98.195008)
		(end 196.701328 98.210008)
		(width 0.2)
		(layer "B.Cu")
		(net 5)
	)
	(segment
		(start 173.036328 87.997157)
		(end 173.036329 87.997156)
		(width 0.15)
		(layer "B.Cu")
		(net 5)
	)
	(segment
		(start 169.856329 97.177157)
		(end 170.036329 96.997157)
		(width 0.15)
		(layer "B.Cu")
		(net 5)
	)
	(segment
		(start 202.086328 109.720008)
		(end 201.686328 110.120008)
		(width 0.2)
		(layer "B.Cu")
		(net 5)
	)
	(segment
		(start 182.836328 97.897157)
		(end 183.736328 97.897157)
		(width 0.2)
		(layer "B.Cu")
		(net 5)
	)
	(segment
		(start 164.356329 98.317157)
		(end 165.036329 98.997157)
		(width 0.15)
		(layer "B.Cu")
		(net 5)
	)
	(segment
		(start 172.236329 99.197157)
		(end 172.036329 98.997157)
		(width 0.15)
		(layer "B.Cu")
		(net 5)
	)
	(segment
		(start 136.785 79.7)
		(end 136.785 78.74)
		(width 0.2)
		(layer "B.Cu")
		(net 5)
	)
	(segment
		(start 199.086328 110.020008)
		(end 199.186328 110.120008)
		(width 0.2)
		(layer "B.Cu")
		(net 5)
	)
	(segment
		(start 201.686328 110.120008)
		(end 201.686328 110.395624)
		(width 0.2)
		(layer "B.Cu")
		(net 5)
	)
	(segment
		(start 173.735 95.625)
		(end 173.735 95.305)
		(width 0.2)
		(layer "B.Cu")
		(net 5)
	)
	(segment
		(start 160.816328 87.597157)
		(end 160.436328 87.597157)
		(width 0.2)
		(layer "B.Cu")
		(net 5)
	)
	(segment
		(start 162.414173 95.375)
		(end 162.036329 94.997156)
		(width 0.2)
		(layer "B.Cu")
		(net 5)
	)
	(segment
		(start 208.306328 101.585008)
		(end 208.306328 100.750008)
		(width 0.2)
		(layer "B.Cu")
		(net 5)
	)
	(segment
		(start 160.711328 99.659958)
		(end 161.029728 99.978358)
		(width 0.15)
		(layer "B.Cu")
		(net 5)
	)
	(segment
		(start 173.036329 94.536329)
		(end 173.036329 94.997157)
		(width 0.2)
		(layer "B.Cu")
		(net 5)
	)
	(segment
		(start 166.036329 100.442156)
		(end 165.856328 100.622157)
		(width 0.15)
		(layer "B.Cu")
		(net 5)
	)
	(segment
		(start 168.716328 92.367157)
		(end 168.666328 92.367157)
		(width 0.15)
		(layer "B.Cu")
		(net 5)
	)
	(segment
		(start 168.897 125.858)
		(end 168.93 125.891)
		(width 0.2)
		(layer "B.Cu")
		(net 5)
	)
	(segment
		(start 168.216329 99.817157)
		(end 168.036329 99.997157)
		(width 0.15)
		(layer "B.Cu")
		(net 5)
	)
	(segment
		(start 177.146666 132.973218)
		(end 177.146666 131.517334)
		(width 0.1)
		(layer "B.Cu")
		(net 5)
	)
	(segment
		(start 180.547 132.849)
		(end 180.547 131.546)
		(width 0.1)
		(layer "B.Cu")
		(net 5)
	)
	(segment
		(start 197.486328 100.505008)
		(end 198.486328 100.505008)
		(width 0.2)
		(layer "B.Cu")
		(net 5)
	)
	(segment
		(start 171.831328 96.372157)
		(end 171.831328 96.792156)
		(width 0.15)
		(layer "B.Cu")
		(net 5)
	)
	(segment
		(start 160.051328 89.797157)
		(end 160.051328 89.012157)
		(width 0.2)
		(layer "B.Cu")
		(net 5)
	)
	(segment
		(start 169.411328 99.177157)
		(end 169.856329 99.177157)
		(width 0.15)
		(layer "B.Cu")
		(net 5)
	)
	(segment
		(start 167.736328 97.297157)
		(end 168.036329 96.997156)
		(width 0.15)
		(layer "B.Cu")
		(net 5)
	)
	(segment
		(start 168.25 87.305)
		(end 168.728485 87.305)
		(width 0.2)
		(layer "B.Cu")
		(net 5)
	)
	(segment
		(start 168.728485 87.305)
		(end 169.036328 86.997157)
		(width 0.2)
		(layer "B.Cu")
		(net 5)
	)
	(segment
		(start 170.695 100.338485)
		(end 171.036329 99.997156)
		(width 0.2)
		(layer "B.Cu")
		(net 5)
	)
	(segment
		(start 174.985 103.125)
		(end 174.985 103.94583)
		(width 0.2)
		(layer "B.Cu")
		(net 5)
	)
	(segment
		(start 137.9 79.685)
		(end 137.9 80.4)
		(width 0.2)
		(layer "B.Cu")
		(net 5)
	)
	(segment
		(start 204.186328 109.259306)
		(end 203.186328 109.259306)
		(width 0.2)
		(layer "B.Cu")
		(net 5)
	)
	(segment
		(start 171.356328 98.297157)
		(end 171.356328 98.317156)
		(width 0.15)
		(layer "B.Cu")
		(net 5)
	)
	(segment
		(start 200.486328 100.505008)
		(end 200.486328 101.020008)
		(width 0.2)
		(layer "B.Cu")
		(net 5)
	)
	(segment
		(start 174.5 91.460829)
		(end 174.036327 90.997156)
		(width 0.2)
		(layer "B.Cu")
		(net 5)
	)
	(segment
		(start 169.216328 95.697157)
		(end 169.216328 95.219984)
		(width 0.15)
		(layer "B.Cu")
		(net 5)
	)
	(segment
		(start 165.211328 96.822158)
		(end 165.036329 96.997157)
		(width 0.15)
		(layer "B.Cu")
		(net 5)
	)
	(segment
		(start 159.036327 93.372156)
		(end 159.036327 93.997157)
		(width 0.2)
		(layer "B.Cu")
		(net 5)
	)
	(segment
		(start 165.945 87.088486)
		(end 166.036329 86.997157)
		(width 0.2)
		(layer "B.Cu")
		(net 5)
	)
	(segment
		(start 167.836328 90.012157)
		(end 167.051329 90.012157)
		(width 0.15)
		(layer "B.Cu")
		(net 5)
	)
	(segment
		(start 172.736328 97.177157)
		(end 172.216329 97.177157)
		(width 0.15)
		(layer "B.Cu")
		(net 5)
	)
	(segment
		(start 167.985 96.945827)
		(end 168.036329 96.997156)
		(width 0.2)
		(layer "B.Cu")
		(net 5)
	)
	(segment
		(start 171.356328 98.317156)
		(end 172.036329 98.997157)
		(width 0.15)
		(layer "B.Cu")
		(net 5)
	)
	(segment
		(start 198.326328 97.930008)
		(end 198.771328 97.930008)
		(width 0.2)
		(layer "B.Cu")
		(net 5)
	)
	(segment
		(start 164.857156 101.997156)
		(end 164.875 102.015)
		(width 0.2)
		(layer "B.Cu")
		(net 5)
	)
	(segment
		(start 167.82 100.625)
		(end 167.82 100.213486)
		(width 0.2)
		(layer "B.Cu")
		(net 5)
	)
	(segment
		(start 137.9 71.285)
		(end 137.9 72)
		(width 0.2)
		(layer "B.Cu")
		(net 5)
	)
	(segment
		(start 173.7 81.8)
		(end 174.4 81.8)
		(width 0.5)
		(layer "B.Cu")
		(net 5)
	)
	(segment
		(start 174.015 99.018486)
		(end 174.036329 98.997157)
		(width 0.2)
		(layer "B.Cu")
		(net 5)
	)
	(segment
		(start 196.686328 97.245008)
		(end 196.686328 98.195008)
		(width 0.2)
		(layer "B.Cu")
		(net 5)
	)
	(segment
		(start 161.25 91.695)
		(end 161.734171 91.695)
		(width 0.2)
		(layer "B.Cu")
		(net 5)
	)
	(segment
		(start 167.736328 97.677157)
		(end 167.736328 97.297157)
		(width 0.15)
		(layer "B.Cu")
		(net 5)
	)
	(segment
		(start 164.336328 92.177157)
		(end 164.856329 92.177157)
		(width 0.15)
		(layer "B.Cu")
		(net 5)
	)
	(segment
		(start 136.785 70.34)
		(end 136.875 70.25)
		(width 0.2)
		(layer "B.Cu")
		(net 5)
	)
	(segment
		(start 171.735 94.125)
		(end 172.625 94.125)
		(width 0.2)
		(layer "B.Cu")
		(net 5)
	)
	(segment
		(start 167.5 87)
		(end 167.805 87.305)
		(width 0.2)
		(layer "B.Cu")
		(net 5)
	)
	(segment
		(start 170.536328 89.497157)
		(end 170.536328 90.347157)
		(width 0.15)
		(layer "B.Cu")
		(net 5)
	)
	(segment
		(start 197.686328 96.765008)
		(end 197.686328 97.290008)
		(width 0.2)
		(layer "B.Cu")
		(net 5)
	)
	(segment
		(start 197.686328 109.259306)
		(end 197.686328 109.820008)
		(width 0.2)
		(layer "B.Cu")
		(net 5)
	)
	(segment
		(start 168.666328 92.367157)
		(end 168.036329 92.997156)
		(width 0.15)
		(layer "B.Cu")
		(net 5)
	)
	(segment
		(start 169.347 122.189)
		(end 169.347 120.974)
		(width 0.2)
		(layer "B.Cu")
		(net 5)
	)
	(segment
		(start 136.785 71.3)
		(end 136.785 70.34)
		(width 0.2)
		(layer "B.Cu")
		(net 5)
	)
	(segment
		(start 171.191328 95.152155)
		(end 171.036329 94.997156)
		(width 0.15)
		(layer "B.Cu")
		(net 5)
	)
	(segment
		(start 162.805 97)
		(end 162.805 97.76583)
		(width 0.2)
		(layer "B.Cu")
		(net 5)
	)
	(segment
		(start 160.985 101.125)
		(end 160.985 101.945831)
		(width 0.2)
		(layer "B.Cu")
		(net 5)
	)
	(segment
		(start 160.68 98)
		(end 160.68 99.215829)
		(width 0.2)
		(layer "B.Cu")
		(net 5)
	)
	(segment
		(start 166.036329 99.997156)
		(end 166.036329 100.442156)
		(width 0.15)
		(layer "B.Cu")
		(net 5)
	)
	(segment
		(start 169.32 91.5)
		(end 169.32 90.865829)
		(width 0.15)
		(layer "B.Cu")
		(net 5)
	)
	(segment
		(start 170.265 93)
		(end 170.265 93.768486)
		(width 0.2)
		(layer "B.Cu")
		(net 5)
	)
	(segment
		(start 169.197 132.849)
		(end 169.197 131.619)
		(width 0.2)
		(layer "B.Cu")
		(net 5)
	)
	(segment
		(start 177.85 65.8)
		(end 177.85 65.15)
		(width 0.5)
		(layer "B.Cu")
		(net 5)
	)
	(segment
		(start 173.015 105.125)
		(end 173.015 105.975828)
		(width 0.2)
		(layer "B.Cu")
		(net 5)
	)
	(segment
		(start 167.5 86.195)
		(end 167.5 87)
		(width 0.2)
		(layer "B.Cu")
		(net 5)
	)
	(segment
		(start 160.051328 89.012157)
		(end 160.036328 88.997157)
		(width 0.2)
		(layer "B.Cu")
		(net 5)
	)
	(segment
		(start 208.306328 100.750008)
		(end 208.311328 100.745008)
		(width 0.2)
		(layer "B.Cu")
		(net 5)
	)
	(segment
		(start 198.771328 97.930008)
		(end 199.126328 97.930008)
		(width 0.2)
		(layer "B.Cu")
		(net 5)
	)
	(segment
		(start 159.6414 99.1362)
		(end 160.655 99.1362)
		(width 0.15)
		(layer "B.Cu")
		(net 5)
	)
	(segment
		(start 173.015 105.975828)
		(end 173.036329 105.997157)
		(width 0.2)
		(layer "B.Cu")
		(net 5)
	)
	(segment
		(start 194.786328 103.005008)
		(end 194.005626 103.005008)
		(width 0.2)
		(layer "B.Cu")
		(net 5)
	)
	(segment
		(start 170.695 100.75)
		(end 170.695 100.338485)
		(width 0.2)
		(layer "B.Cu")
		(net 5)
	)
	(segment
		(start 201.586328 100.505008)
		(end 201.586328 101.020008)
		(width 0.2)
		(layer "B.Cu")
		(net 5)
	)
	(segment
		(start 168.897 124.589)
		(end 168.897 125.858)
		(width 0.2)
		(layer "B.Cu")
		(net 5)
	)
	(segment
		(start 150.9014 97.2082)
		(end 150.518 97.2082)
		(width 0.15)
		(layer "B.Cu")
		(net 5)
	)
	(segment
		(start 164.14 94)
		(end 163 94)
		(width 0.2)
		(layer "B.Cu")
		(net 5)
	)
	(segment
		(start 177.146666 131.517334)
		(end 177.185 131.479)
		(width 0.1)
		(layer "B.Cu")
		(net 5)
	)
	(segment
		(start 164.336328 98.317157)
		(end 164.356329 98.317157)
		(width 0.15)
		(layer "B.Cu")
		(net 5)
	)
	(segment
		(start 164.856329 92.177157)
		(end 165.036329 91.997157)
		(width 0.15)
		(layer "B.Cu")
		(net 5)
	)
	(segment
		(start 201.086328 109.520008)
		(end 201.686328 110.120008)
		(width 0.2)
		(layer "B.Cu")
		(net 5)
	)
	(segment
		(start 199.086328 109.274306)
		(end 199.086328 110.020008)
		(width 0.2)
		(layer "B.Cu")
		(net 5)
	)
	(segment
		(start 136.785 80.385)
		(end 136.8 80.4)
		(width 0.2)
		(layer "B.Cu")
		(net 5)
	)
	(segment
		(start 180.747 126.52)
		(end 180.741 126.526)
		(width 0.1)
		(layer "B.Cu")
		(net 5)
	)
	(segment
		(start 122.215 68.95)
		(end 121.75 68.485)
		(width 0.15)
		(layer "B.Cu")
		(net 5)
	)
	(segment
		(start 179.036327 105.997157)
		(end 179.036327 106.974306)
		(width 0.2)
		(layer "B.Cu")
		(net 5)
	)
	(segment
		(start 172.736328 92.177157)
		(end 173.426328 92.177157)
		(width 0.15)
		(layer "B.Cu")
		(net 5)
	)
	(segment
		(start 198.861328 101.660008)
		(end 198.861328 101.395008)
		(width 0.2)
		(layer "B.Cu")
		(net 5)
	)
	(segment
		(start 173.427157 94.997157)
		(end 173.036329 94.997157)
		(width 0.2)
		(layer "B.Cu")
		(net 5)
	)
	(segment
		(start 136.785 79.7)
		(end 136.785 80.385)
		(width 0.2)
		(layer "B.Cu")
		(net 5)
	)
	(segment
		(start 121.75 67.6)
		(end 120.95 67.6)
		(width 0.15)
		(layer "B.Cu")
		(net 5)
	)
	(segment
		(start 168.661328 99.817157)
		(end 168.216329 99.817157)
		(width 0.15)
		(layer "B.Cu")
		(net 5)
	)
	(segment
		(start 179.661328 102.947157)
		(end 180.486329 102.947157)
		(width 0.15)
		(layer "B.Cu")
		(net 5)
	)
	(segment
		(start 169.336328 94.337157)
		(end 169.336328 94.654328)
		(width 0.15)
		(layer "B.Cu")
		(net 5)
	)
	(segment
		(start 169.836327 106.197157)
		(end 170.036327 105.997157)
		(width 0.2)
		(layer "B.Cu")
		(net 5)
	)
	(segment
		(start 166.015 104.975828)
		(end 166.036328 104.997156)
		(width 0.2)
		(layer "B.Cu")
		(net 5)
	)
	(segment
		(start 157.236328 87.097157)
		(end 157.236328 87.620016)
		(width 0.2)
		(layer "B.Cu")
		(net 5)
	)
	(segment
		(start 197.686328 96.765008)
		(end 197.166328 96.765008)
		(width 0.2)
		(layer "B.Cu")
		(net 5)
	)
	(segment
		(start 174.015 99.875)
		(end 174.015 99.018486)
		(width 0.2)
		(layer "B.Cu")
		(net 5)
	)
	(segment
		(start 136.785 78.74)
		(end 136.875 78.65)
		(width 0.2)
		(layer "B.Cu")
		(net 5)
	)
	(segment
		(start 169.197 131.619)
		(end 169.184 131.606)
		(width 0.2)
		(layer "B.Cu")
		(net 5)
	)
	(segment
		(start 176.2 97.875)
		(end 176.914173 97.875)
		(width 0.2)
		(layer "B.Cu")
		(net 5)
	)
	(segment
		(start 167.051329 90.012157)
		(end 167.036329 89.997157)
		(width 0.15)
		(layer "B.Cu")
		(net 5)
	)
	(segment
		(start 153.0072 94.742)
		(end 152.23243 94.742)
		(width 0.15)
		(layer "B.Cu")
		(net 5)
	)
	(segment
		(start 164.511329 90.522157)
		(end 164.036329 90.997157)
		(width 0.15)
		(layer "B.Cu")
		(net 5)
	)
	(segment
		(start 170.985 102.75)
		(end 170.985 102.048484)
		(width 0.2)
		(layer "B.Cu")
		(net 5)
	)
	(segment
		(start 160.036328 87.297157)
		(end 159.986328 87.247157)
		(width 0.15)
		(layer "B.Cu")
		(net 5)
	)
	(segment
		(start 166.216328 94.817157)
		(end 166.036329 94.997156)
		(width 0.15)
		(layer "B.Cu")
		(net 5)
	)
	(segment
		(start 165.856328 95.177157)
		(end 166.036329 94.997156)
		(width 0.15)
		(layer "B.Cu")
		(net 5)
	)
	(segment
		(start 172.216329 97.177157)
		(end 172.036329 96.997157)
		(width 0.15)
		(layer "B.Cu")
		(net 5)
	)
	(segment
		(start 179.7 121)
		(end 179.7 119.5445)
		(width 0.15)
		(layer "B.Cu")
		(net 5)
	)
	(segment
		(start 172.216329 92.177157)
		(end 172.036329 91.997157)
		(width 0.15)
		(layer "B.Cu")
		(net 5)
	)
	(segment
		(start 197.686328 97.290008)
		(end 198.326328 97.930008)
		(width 0.2)
		(layer "B.Cu")
		(net 5)
	)
	(segment
		(start 136.785 71.3)
		(end 136.785 71.985)
		(width 0.2)
		(layer "B.Cu")
		(net 5)
	)
	(segment
		(start 170.265 93.768486)
		(end 170.036329 93.997157)
		(width 0.2)
		(layer "B.Cu")
		(net 5)
	)
	(segment
		(start 166.32 89.875)
		(end 166.914172 89.875)
		(width 0.2)
		(layer "B.Cu")
		(net 5)
	)
	(segment
		(start 180.747 125.239)
		(end 180.747 126.52)
		(width 0.1)
		(layer "B.Cu")
		(net 5)
	)
	(segment
		(start 169.856329 99.177157)
		(end 170.036329 98.997157)
		(width 0.15)
		(layer "B.Cu")
		(net 5)
	)
	(segment
		(start 199.101328 109.259306)
		(end 199.086328 109.274306)
		(width 0.2)
		(layer "B.Cu")
		(net 5)
	)
	(segment
		(start 164.716328 91.297157)
		(end 164.716328 91.677157)
		(width 0.15)
		(layer "B.Cu")
		(net 5)
	)
	(segment
		(start 164.716328 91.677157)
		(end 165.036329 91.997157)
		(width 0.15)
		(layer "B.Cu")
		(net 5)
	)
	(segment
		(start 174.5 91.515)
		(end 174.5 91.460829)
		(width 0.2)
		(layer "B.Cu")
		(net 5)
	)
	(segment
		(start 163.536328 89.997157)
		(end 163.536328 90.497157)
		(width 0.15)
		(layer "B.Cu")
		(net 5)
	)
	(segment
		(start 201.086328 109.259306)
		(end 201.086328 109.520008)
		(width 0.2)
		(layer "B.Cu")
		(net 5)
	)
	(segment
		(start 160.711328 99.247157)
		(end 160.711328 99.659958)
		(width 0.15)
		(layer "B.Cu")
		(net 5)
	)
	(segment
		(start 166.914172 89.875)
		(end 167.036329 89.997157)
		(width 0.2)
		(layer "B.Cu")
		(net 5)
	)
	(segment
		(start 167.805 87.305)
		(end 168.25 87.305)
		(width 0.2)
		(layer "B.Cu")
		(net 5)
	)
	(segment
		(start 198.861328 101.395008)
		(end 198.486328 101.020008)
		(width 0.2)
		(layer "B.Cu")
		(net 5)
	)
	(segment
		(start 193.001328 97.210008)
		(end 193.001328 98.475008)
		(width 0.2)
		(layer "B.Cu")
		(net 5)
	)
	(segment
		(start 160.985 101.945831)
		(end 161.036328 101.997159)
		(width 0.2)
		(layer "B.Cu")
		(net 5)
	)
	(segment
		(start 169.411328 97.177157)
		(end 169.856329 97.177157)
		(width 0.15)
		(layer "B.Cu")
		(net 5)
	)
	(segment
		(start 161.509181 94.470008)
		(end 162.036329 94.997156)
		(width 0.15)
		(layer "B.Cu")
		(net 5)
	)
	(segment
		(start 136.785 79.7)
		(end 137.885 79.7)
		(width 0.2)
		(layer "B.Cu")
		(net 5)
	)
	(segment
		(start 165.945 87.625)
		(end 165.945 87.088486)
		(width 0.2)
		(layer "B.Cu")
		(net 5)
	)
	(segment
		(start 167.82 100.213486)
		(end 168.036329 99.997157)
		(width 0.2)
		(layer "B.Cu")
		(net 5)
	)
	(segment
		(start 163.536328 90.497157)
		(end 163.036328 90.997157)
		(width 0.15)
		(layer "B.Cu")
		(net 5)
	)
	(segment
		(start 175.515 91.5)
		(end 174.515 91.5)
		(width 0.2)
		(layer "B.Cu")
		(net 5)
	)
	(segment
		(start 193.001328 98.475008)
		(end 192.556328 98.920008)
		(width 0.2)
		(layer "B.Cu")
		(net 5)
	)
	(segment
		(start 166.661328 94.817157)
		(end 166.216328 94.817157)
		(width 0.15)
		(layer "B.Cu")
		(net 5)
	)
	(segment
		(start 177.015 99.975829)
		(end 177.036328 99.997157)
		(width 0.2)
		(layer "B.Cu")
		(net 5)
	)
	(segment
		(start 169.216328 95.219984)
		(end 168.9935 94.997156)
		(width 0.15)
		(layer "B.Cu")
		(net 5)
	)
	(segment
		(start 204.186328 109.259306)
		(end 204.725626 109.259306)
		(width 0.2)
		(layer "B.Cu")
		(net 5)
	)
	(segment
		(start 213.086328 120.474306)
		(end 213.086328 119.620008)
		(width 0.2)
		(layer "B.Cu")
		(net 5)
	)
	(segment
		(start 172.736328 99.197157)
		(end 172.236329 99.197157)
		(width 0.15)
		(layer "B.Cu")
		(net 5)
	)
	(segment
		(start 160.554171 91.695)
		(end 160.356328 91.497157)
		(width 0.2)
		(layer "B.Cu")
		(net 5)
	)
	(segment
		(start 174.515 91.5)
		(end 174.5 91.515)
		(width 0.2)
		(layer "B.Cu")
		(net 5)
	)
	(segment
		(start 169.336328 94.654328)
		(end 168.9935 94.997156)
		(width 0.15)
		(layer "B.Cu")
		(net 5)
	)
	(segment
		(start 201.686328 110.395624)
		(end 201.690783 110.400079)
		(width 0.2)
		(layer "B.Cu")
		(net 5)
	)
	(segment
		(start 166.411329 98.372157)
		(end 167.036329 98.997157)
		(width 0.15)
		(layer "B.Cu")
		(net 5)
	)
	(segment
		(start 198.486328 100.505008)
		(end 198.486328 101.020008)
		(width 0.2)
		(layer "B.Cu")
		(net 5)
	)
	(segment
		(start 152.23243 94.742)
		(end 152.200758 94.773672)
		(width 0.15)
		(layer "B.Cu")
		(net 5)
	)
	(segment
		(start 165.211328 96.372157)
		(end 165.211328 96.822158)
		(width 0.15)
		(layer "B.Cu")
		(net 5)
	)
	(segment
		(start 167.411328 94.817157)
		(end 167.856329 94.817157)
		(width 0.15)
		(layer "B.Cu")
		(net 5)
	)
	(segment
		(start 208.306328 106.965008)
		(end 208.306328 107.800008)
		(width 0.2)
		(layer "B.Cu")
		(net 5)
	)
	(segment
		(start 170.536328 90.347157)
		(end 169.336328 91.547157)
		(width 0.15)
		(layer "B.Cu")
		(net 5)
	)
	(segment
		(start 159.853477 89.180008)
		(end 160.036328 88.997157)
		(width 0.15)
		(layer "B.Cu")
		(net 5)
	)
	(segment
		(start 199.516328 97.540008)
		(end 204.001328 97.540008)
		(width 0.2)
		(layer "B.Cu")
		(net 5)
	)
	(segment
		(start 202.086328 109.259306)
		(end 202.086328 109.720008)
		(width 0.2)
		(layer "B.Cu")
		(net 5)
	)
	(segment
		(start 162.375 93.82)
		(end 162.82 93.82)
		(width 0.2)
		(layer "B.Cu")
		(net 5)
	)
	(segment
		(start 162.82 93.82)
		(end 163 94)
		(width 0.2)
		(layer "B.Cu")
		(net 5)
	)
	(segment
		(start 177.036328 101.512157)
		(end 177.036328 99.997157)
		(width 0.15)
		(layer "B.Cu")
		(net 5)
	)
	(segment
		(start 167.985 102.94583)
		(end 168.036328 102.997158)
		(width 0.2)
		(layer "B.Cu")
		(net 5)
	)
	(segment
		(start 177.015 99.125)
		(end 177.015 99.975829)
		(width 0.2)
		(layer "B.Cu")
		(net 5)
	)
	(segment
		(start 192.556328 98.920008)
		(end 191.786328 98.920008)
		(width 0.2)
		(layer "B.Cu")
		(net 5)
	)
	(segment
		(start 162.675 95.375)
		(end 162.414173 95.375)
		(width 0.2)
		(layer "B.Cu")
		(net 5)
	)
	(segment
		(start 204.725626 109.259306)
		(end 204.786328 109.320008)
		(width 0.2)
		(layer "B.Cu")
		(net 5)
	)
	(segment
		(start 169.347 120.974)
		(end 169.311 120.938)
		(width 0.2)
		(layer "B.Cu")
		(net 5)
	)
	(segment
		(start 137.885 79.7)
		(end 137.9 79.685)
		(width 0.2)
		(layer "B.Cu")
		(net 5)
	)
	(segment
		(start 161.734171 91.695)
		(end 162.036329 91.997158)
		(width 0.2)
		(layer "B.Cu")
		(net 5)
	)
	(segment
		(start 154.15 65.8)
		(end 154.15 65.2)
		(width 0.5)
		(layer "B.Cu")
		(net 5)
	)
	(segment
		(start 199.486328 100.505008)
		(end 199.486328 101.020008)
		(width 0.2)
		(layer "B.Cu")
		(net 5)
	)
	(segment
		(start 164.716328 90.522157)
		(end 164.511329 90.522157)
		(width 0.15)
		(layer "B.Cu")
		(net 5)
	)
	(segment
		(start 169.036328 106.197157)
		(end 169.836327 106.197157)
		(width 0.2)
		(layer "B.Cu")
		(net 5)
	)
	(segment
		(start 201.586328 100.505008)
		(end 202.686328 100.505008)
		(width 0.2)
		(layer "B.Cu")
		(net 5)
	)
	(segment
		(start 182.936328 86.597157)
		(end 183.536328 86.597157)
		(width 0.2)
		(layer "B.Cu")
		(net 5)
	)
	(segment
		(start 150.186242 97.539958)
		(end 150.186242 97.758328)
		(width 0.15)
		(layer "B.Cu")
		(net 5)
	)
	(segment
		(start 176.39 94.75)
		(end 175.083485 94.75)
		(width 0.2)
		(layer "B.Cu")
		(net 5)
	)
	(segment
		(start 197.166328 96.765008)
		(end 196.686328 97.245008)
		(width 0.2)
		(layer "B.Cu")
		(net 5)
	)
	(segment
		(start 170.985 102.048484)
		(end 171.036327 101.997157)
		(width 0.2)
		(layer "B.Cu")
		(net 5)
	)
	(segment
		(start 173.735 95.305)
		(end 173.427157 94.997157)
		(width 0.2)
		(layer "B.Cu")
		(net 5)
	)
	(segment
		(start 199.836328 95.925008)
		(end 204.001328 95.925008)
		(width 0.2)
		(layer "B.Cu")
		(net 5)
	)
	(segment
		(start 209.111328 69.920008)
		(end 207.861328 69.920008)
		(width 0.2)
		(layer "B.Cu")
		(net 5)
	)
	(segment
		(start 209.111328 69.920008)
		(end 209.886328 69.920008)
		(width 0.2)
		(layer "B.Cu")
		(net 5)
	)
	(segment
		(start 169.32 90.865829)
		(end 169.036328 90.582157)
		(width 0.15)
		(layer "B.Cu")
		(net 5)
	)
	(segment
		(start 159.015 103.975827)
		(end 159.036328 103.997155)
		(width 0.2)
		(layer "B.Cu")
		(net 5)
	)
	(segment
		(start 172.736328 92.177157)
		(end 172.216329 92.177157)
		(width 0.15)
		(layer "B.Cu")
		(net 5)
	)
	(segment
		(start 163.015 105.975828)
		(end 163.036328 105.997156)
		(width 0.2)
		(layer "B.Cu")
		(net 5)
	)
	(segment
		(start 156.9 84.175)
		(end 156.15 84.175)
		(width 0.4)
		(layer "B.Cu")
		(net 5)
	)
	(segment
		(start 162.805 97.76583)
		(end 163.036328 97.997158)
		(width 0.2)
		(layer "B.Cu")
		(net 5)
	)
	(segment
		(start 180.486329 102.947157)
		(end 180.536329 102.997157)
		(width 0.15)
		(layer "B.Cu")
		(net 5)
	)
	(segment
		(start 136.785 71.985)
		(end 136.8 72)
		(width 0.2)
		(layer "B.Cu")
		(net 5)
	)
	(segment
		(start 177.015 98.018485)
		(end 177.036329 97.997156)
		(width 0.2)
		(layer "B.Cu")
		(net 5)
	)
	(segment
		(start 172.625 94.125)
		(end 173.036329 94.536329)
		(width 0.2)
		(layer "B.Cu")
		(net 5)
	)
	(segment
		(start 158.661328 92.997157)
		(end 159.036327 93.372156)
		(width 0.2)
		(layer "B.Cu")
		(net 5)
	)
	(segment
		(start 165.856328 95.622157)
		(end 165.856328 95.177157)
		(width 0.15)
		(layer "B.Cu")
		(net 5)
	)
	(segment
		(start 159.116328 89.180008)
		(end 159.853477 89.180008)
		(width 0.15)
		(layer "B.Cu")
		(net 5)
	)
	(segment
		(start 173.426328 92.177157)
		(end 173.536328 92.067157)
		(width 0.15)
		(layer "B.Cu")
		(net 5)
	)
	(segment
		(start 150.518 97.2082)
		(end 150.186242 97.539958)
		(width 0.15)
		(layer "B.Cu")
		(net 5)
	)
	(segment
		(start 173.985 101.048484)
		(end 174.036327 100.997157)
		(width 0.2)
		(layer "B.Cu")
		(net 5)
	)
	(segment
		(start 166.015 104.125)
		(end 166.015 104.975828)
		(width 0.2)
		(layer "B.Cu")
		(net 5)
	)
	(segment
		(start 161.326328 94.470008)
		(end 161.509181 94.470008)
		(width 0.15)
		(layer "B.Cu")
		(net 5)
	)
	(segment
		(start 176.914173 97.875)
		(end 177.036329 97.997156)
		(width 0.2)
		(layer "B.Cu")
		(net 5)
	)
	(segment
		(start 180.547 131.546)
		(end 180.614 131.479)
		(width 0.1)
		(layer "B.Cu")
		(net 5)
	)
	(segment
		(start 167.985 95.875)
		(end 167.985 96.945827)
		(width 0.2)
		(layer "B.Cu")
		(net 5)
	)
	(segment
		(start 173.985 101.75)
		(end 173.985 101.048484)
		(width 0.2)
		(layer "B.Cu")
		(net 5)
	)
	(segment
		(start 157.236328 87.620016)
		(end 157.28632 87.670008)
		(width 0.2)
		(layer "B.Cu")
		(net 5)
	)
	(segment
		(start 121.75 68.485)
		(end 121.75 67.6)
		(width 0.15)
		(layer "B.Cu")
		(net 5)
	)
	(segment
		(start 177.015 99.125)
		(end 177.015 98.018485)
		(width 0.2)
		(layer "B.Cu")
		(net 5)
	)
	(segment
		(start 171.831328 96.792156)
		(end 172.036329 96.997157)
		(width 0.15)
		(layer "B.Cu")
		(net 5)
	)
	(segment
		(start 200.086328 109.259306)
		(end 199.101328 109.259306)
		(width 0.2)
		(layer "B.Cu")
		(net 5)
	)
	(segment
		(start 175.083485 94.75)
		(end 175.036328 94.797157)
		(width 0.2)
		(layer "B.Cu")
		(net 5)
	)
	(segment
		(start 160.68 99.215829)
		(end 160.711328 99.247157)
		(width 0.2)
		(layer "B.Cu")
		(net 5)
	)
	(segment
		(start 173.036328 88.947157)
		(end 173.036328 87.997157)
		(width 0.15)
		(layer "B.Cu")
		(net 5)
	)
	(segment
		(start 167.985 102.125)
		(end 167.985 102.94583)
		(width 0.2)
		(layer "B.Cu")
		(net 5)
	)
	(segment
		(start 160.436328 87.597157)
		(end 160.036328 87.997157)
		(width 0.2)
		(layer "B.Cu")
		(net 5)
	)
	(segment
		(start 136.421328 125.737157)
		(end 136.421328 124.827157)
		(width 0.13)
		(layer "F.Cu")
		(net 6)
	)
	(segment
		(start 136.152953 123.597047)
		(end 136.152953 124.136664)
		(width 0.15)
		(layer "F.Cu")
		(net 6)
	)
	(segment
		(start 136.421328 124.405039)
		(end 136.421328 124.827157)
		(width 0.15)
		(layer "F.Cu")
		(net 6)
	)
	(segment
		(start 136.231328 125.927157)
		(end 136.421328 125.737157)
		(width 0.13)
		(layer "F.Cu")
		(net 6)
	)
	(segment
		(start 136.152953 123.745375)
		(end 136.152953 123.309181)
		(width 0.1)
		(layer "F.Cu")
		(net 6)
	)
	(segment
		(start 140.9 118.562134)
		(end 140.900001 111.887499)
		(width 0.1)
		(layer "F.Cu")
		(net 6)
	)
	(segment
		(start 136.231328 126.867157)
		(end 136.231328 126.292157)
		(width 0.13)
		(layer "F.Cu")
		(net 6)
	)
	(segment
		(start 136.257 129.329)
		(end 136.081328 129.153328)
		(width 0.13)
		(layer "F.Cu")
		(net 6)
	)
	(segment
		(start 136.081328 127.017157)
		(end 136.231328 126.867157)
		(width 0.13)
		(layer "F.Cu")
		(net 6)
	)
	(segment
		(start 136.231328 126.292157)
		(end 136.231328 125.927157)
		(width 0.13)
		(layer "F.Cu")
		(net 6)
	)
	(segment
		(start 136.152953 124.136664)
		(end 136.421328 124.405039)
		(width 0.15)
		(layer "F.Cu")
		(net 6)
	)
	(segment
		(start 136.152953 123.309181)
		(end 140.9 118.562134)
		(width 0.1)
		(layer "F.Cu")
		(net 6)
	)
	(segment
		(start 140.900001 111.887499)
		(end 141 111.7875)
		(width 0.1)
		(layer "F.Cu")
		(net 6)
	)
	(segment
		(start 136.081328 129.153328)
		(end 136.081328 127.017157)
		(width 0.13)
		(layer "F.Cu")
		(net 6)
	)
	(segment
		(start 135.531328 125.867157)
		(end 135.341328 125.677157)
		(width 0.13)
		(layer "F.Cu")
		(net 7)
	)
	(segment
		(start 135.341328 124.837157)
		(end 135.341328 125.677157)
		(width 0.13)
		(layer "F.Cu")
		(net 7)
	)
	(segment
		(start 135.761328 129.174672)
		(end 135.761328 127.007157)
		(width 0.13)
		(layer "F.Cu")
		(net 7)
	)
	(segment
		(start 135.531328 126.777157)
		(end 135.531328 126.292157)
		(width 0.13)
		(layer "F.Cu")
		(net 7)
	)
	(segment
		(start 135.852953 123.184913)
		(end 140.6 118.437866)
		(width 0.1)
		(layer "F.Cu")
		(net 7)
	)
	(segment
		(start 135.607 129.329)
		(end 135.761328 129.174672)
		(width 0.13)
		(layer "F.Cu")
		(net 7)
	)
	(segment
		(start 135.341328 124.533672)
		(end 135.852953 124.022047)
		(width 0.15)
		(layer "F.Cu")
		(net 7)
	)
	(segment
		(start 140.6 118.437866)
		(end 140.599999 111.887499)
		(width 0.1)
		(layer "F.Cu")
		(net 7)
	)
	(segment
		(start 135.852953 124.022047)
		(end 135.852953 123.621107)
		(width 0.15)
		(layer "F.Cu")
		(net 7)
	)
	(segment
		(start 135.341328 124.837157)
		(end 135.341328 124.533672)
		(width 0.15)
		(layer "F.Cu")
		(net 7)
	)
	(segment
		(start 140.599999 111.887499)
		(end 140.5 111.7875)
		(width 0.1)
		(layer "F.Cu")
		(net 7)
	)
	(segment
		(start 135.761328 127.007157)
		(end 135.531328 126.777157)
		(width 0.13)
		(layer "F.Cu")
		(net 7)
	)
	(segment
		(start 135.852953 123.621107)
		(end 135.852953 123.184913)
		(width 0.1)
		(layer "F.Cu")
		(net 7)
	)
	(segment
		(start 135.531328 126.292157)
		(end 135.531328 125.867157)
		(width 0.13)
		(layer "F.Cu")
		(net 7)
	)
	(segment
		(start 148.536328 113.137157)
		(end 149.146328 113.137157)
		(width 0.1)
		(layer "F.Cu")
		(net 8)
	)
	(segment
		(start 170.536329 91.497157)
		(end 171.036329 90.997156)
		(width 0.15)
		(layer "F.Cu")
		(net 8)
	)
	(via
		(at 149.161328 113.122157)
		(size 0.5)
		(drill 0.2)
		(layers "F.Cu" "B.Cu")
		(net 8)
	)
	(via
		(at 171.036329 90.997156)
		(size 0.5)
		(drill 0.2)
		(layers "F.Cu" "B.Cu")
		(net 8)
	)
	(via
		(at 206.036328 73.420008)
		(size 0.5)
		(drill 0.2)
		(layers "F.Cu" "B.Cu")
		(net 8)
	)
	(segment
		(start 209.111328 71.420008)
		(end 211.784179 71.420008)
		(width 0.2)
		(layer "B.Cu")
		(net 8)
	)
	(segment
		(start 209.111328 71.420008)
		(end 207.861328 71.420008)
		(width 0.2)
		(layer "B.Cu")
		(net 8)
	)
	(segment
		(start 206.286328 71.420008)
		(end 207.861328 71.420008)
		(width 0.2)
		(layer "B.Cu")
		(net 8)
	)
	(segment
		(start 205.986328 71.720008)
		(end 205.986328 73.370008)
		(width 0.2)
		(layer "B.Cu")
		(net 8)
	)
	(segment
		(start 211.784179 71.420008)
		(end 212.161328 71.797157)
		(width 0.2)
		(layer "B.Cu")
		(net 8)
	)
	(segment
		(start 205.986328 73.370008)
		(end 206.036328 73.420008)
		(width 0.2)
		(layer "B.Cu")
		(net 8)
	)
	(segment
		(start 206.286328 71.420008)
		(end 205.986328 71.720008)
		(width 0.2)
		(layer "B.Cu")
		(net 8)
	)
	(segment
		(start 206.686328 73.420008)
		(end 206.036328 73.420008)
		(width 0.1)
		(layer "In2.Cu")
		(net 8)
	)
	(segment
		(start 171.513173 91.474)
		(end 174.309485 91.474)
		(width 0.1)
		(layer "In2.Cu")
		(net 8)
	)
	(segment
		(start 207.036329 73.770009)
		(end 206.686328 73.420008)
		(width 0.1)
		(layer "In2.Cu")
		(net 8)
	)
	(segment
		(start 175.325485 90.458)
		(end 183.408 90.458)
		(width 0.1)
		(layer "In2.Cu")
		(net 8)
	)
	(segment
		(start 171.036329 90.997156)
		(end 171.513173 91.474)
		(width 0.1)
		(layer "In2.Cu")
		(net 8)
	)
	(segment
		(start 205.386328 77.720008)
		(end 207.036329 76.070007)
		(width 0.1)
		(layer "In2.Cu")
		(net 8)
	)
	(segment
		(start 174.309485 91.474)
		(end 175.325485 90.458)
		(width 0.1)
		(layer "In2.Cu")
		(net 8)
	)
	(segment
		(start 207.036329 76.070007)
		(end 207.036329 73.770009)
		(width 0.1)
		(layer "In2.Cu")
		(net 8)
	)
	(segment
		(start 196.145992 77.720008)
		(end 205.386328 77.720008)
		(width 0.1)
		(layer "In2.Cu")
		(net 8)
	)
	(segment
		(start 183.408 90.458)
		(end 196.145992 77.720008)
		(width 0.1)
		(layer "In2.Cu")
		(net 8)
	)
	(segment
		(start 164.743464 89.397157)
		(end 163.743462 90.397159)
		(width 0.1)
		(layer "In5.Cu")
		(net 8)
	)
	(segment
		(start 149.161328 113.122157)
		(end 153.4414 108.842085)
		(width 0.1)
		(layer "In5.Cu")
		(net 8)
	)
	(segment
		(start 167.436328 89.397157)
		(end 164.743464 89.397157)
		(width 0.1)
		(layer "In5.Cu")
		(net 8)
	)
	(segment
		(start 169.670327 90.297157)
		(end 168.336328 90.297157)
		(width 0.1)
		(layer "In5.Cu")
		(net 8)
	)
	(segment
		(start 158.330923 90.397159)
		(end 156.486327 92.241755)
		(width 0.1)
		(layer "In5.Cu")
		(net 8)
	)
	(segment
		(start 168.336328 90.297157)
		(end 167.436328 89.397157)
		(width 0.1)
		(layer "In5.Cu")
		(net 8)
	)
	(segment
		(start 170.370326 90.997156)
		(end 169.670327 90.297157)
		(width 0.1)
		(layer "In5.Cu")
		(net 8)
	)
	(segment
		(start 171.036329 90.997156)
		(end 170.370326 90.997156)
		(width 0.1)
		(layer "In5.Cu")
		(net 8)
	)
	(segment
		(start 163.743462 90.397159)
		(end 158.330923 90.397159)
		(width 0.1)
		(layer "In5.Cu")
		(net 8)
	)
	(segment
		(start 153.4414 95.277789)
		(end 153.4414 108.842085)
		(width 0.1)
		(layer "In5.Cu")
		(net 8)
	)
	(segment
		(start 156.486327 92.241755)
		(end 153.4414 95.277789)
		(width 0.1)
		(layer "In5.Cu")
		(net 8)
	)
	(segment
		(start 169.536329 90.497157)
		(end 170.036329 89.997157)
		(width 0.15)
		(layer "F.Cu")
		(net 9)
	)
	(segment
		(start 148.541328 109.832157)
		(end 150.74632 109.832157)
		(width 0.15)
		(layer "F.Cu")
		(net 9)
	)
	(segment
		(start 150.74632 109.832157)
		(end 150.786328 109.872165)
		(width 0.15)
		(layer "F.Cu")
		(net 9)
	)
	(via
		(at 170.036329 89.997157)
		(size 0.5)
		(drill 0.2)
		(layers "F.Cu" "B.Cu")
		(net 9)
	)
	(via
		(at 206.586328 74.54)
		(size 0.5)
		(drill 0.2)
		(layers "F.Cu" "B.Cu")
		(net 9)
	)
	(via
		(at 216.34 78.080188)
		(size 0.5)
		(drill 0.2)
		(layers "F.Cu" "B.Cu")
		(net 9)
	)
	(via
		(at 150.786328 109.872165)
		(size 0.5)
		(drill 0.2)
		(layers "F.Cu" "B.Cu")
		(net 9)
	)
	(via
		(at 216.34 73.650376)
		(size 0.5)
		(drill 0.2)
		(layers "F.Cu" "B.Cu")
		(net 9)
	)
	(segment
		(start 206.586328 72.320008)
		(end 206.986328 71.920008)
		(width 0.2)
		(layer "B.Cu")
		(net 9)
	)
	(segment
		(start 210.284179 71.920008)
		(end 212.161328 73.797157)
		(width 0.2)
		(layer "B.Cu")
		(net 9)
	)
	(segment
		(start 206.986328 71.920008)
		(end 210.284179 71.920008)
		(width 0.2)
		(layer "B.Cu")
		(net 9)
	)
	(segment
		(start 206.586328 74.54)
		(end 206.586328 72.320008)
		(width 0.2)
		(layer "B.Cu")
		(net 9)
	)
	(segment
		(start 173.742951 89.950001)
		(end 173.245794 90.447158)
		(width 0.1)
		(layer "In2.Cu")
		(net 9)
	)
	(segment
		(start 195.933981 77.170019)
		(end 183.154 89.95)
		(width 0.1)
		(layer "In2.Cu")
		(net 9)
	)
	(segment
		(start 206.586328 74.54)
		(end 206.586328 75.020008)
		(width 0.1)
		(layer "In2.Cu")
		(net 9)
	)
	(segment
		(start 183.154 89.95)
		(end 173.742951 89.950001)
		(width 0.1)
		(layer "In2.Cu")
		(net 9)
	)
	(segment
		(start 170.48633 90.447158)
		(end 170.036329 89.997157)
		(width 0.1)
		(layer "In2.Cu")
		(net 9)
	)
	(segment
		(start 173.245794 90.447158)
		(end 170.48633 90.447158)
		(width 0.1)
		(layer "In2.Cu")
		(net 9)
	)
	(segment
		(start 204.436317 77.170019)
		(end 195.933981 77.170019)
		(width 0.1)
		(layer "In2.Cu")
		(net 9)
	)
	(segment
		(start 206.586328 75.020008)
		(end 204.436317 77.170019)
		(width 0.1)
		(layer "In2.Cu")
		(net 9)
	)
	(segment
		(start 150.786328 109.872165)
		(end 153.1874 107.471093)
		(width 0.1)
		(layer "In5.Cu")
		(net 9)
	)
	(segment
		(start 153.1874 95.178221)
		(end 153.1874 107.471093)
		(width 0.1)
		(layer "In5.Cu")
		(net 9)
	)
	(segment
		(start 164.689896 89.097157)
		(end 163.639905 90.147148)
		(width 0.1)
		(layer "In5.Cu")
		(net 9)
	)
	(segment
		(start 170.036329 89.997157)
		(end 168.436326 89.997157)
		(width 0.1)
		(layer "In5.Cu")
		(net 9)
	)
	(segment
		(start 163.639905 90.147148)
		(end 158.218473 90.147148)
		(width 0.1)
		(layer "In5.Cu")
		(net 9)
	)
	(segment
		(start 168.436326 89.997157)
		(end 167.536326 89.097157)
		(width 0.1)
		(layer "In5.Cu")
		(net 9)
	)
	(segment
		(start 167.536326 89.097157)
		(end 164.689896 89.097157)
		(width 0.1)
		(layer "In5.Cu")
		(net 9)
	)
	(segment
		(start 158.218473 90.147148)
		(end 153.1874 95.178221)
		(width 0.1)
		(layer "In5.Cu")
		(net 9)
	)
	(segment
		(start 170.536329 90.497156)
		(end 171.036329 89.997156)
		(width 0.15)
		(layer "F.Cu")
		(net 10)
	)
	(segment
		(start 149.521328 111.982157)
		(end 149.536328 111.997157)
		(width 0.15)
		(layer "F.Cu")
		(net 10)
	)
	(segment
		(start 148.541328 111.982157)
		(end 149.521328 111.982157)
		(width 0.15)
		(layer "F.Cu")
		(net 10)
	)
	(via
		(at 171.036329 89.997156)
		(size 0.5)
		(drill 0.2)
		(layers "F.Cu" "B.Cu")
		(net 10)
	)
	(via
		(at 205.586324 68.320008)
		(size 0.5)
		(drill 0.2)
		(layers "F.Cu" "B.Cu")
		(net 10)
	)
	(via
		(at 149.536328 111.997157)
		(size 0.5)
		(drill 0.2)
		(layers "F.Cu" "B.Cu")
		(net 10)
	)
	(segment
		(start 207.136326 68.920008)
		(end 206.536326 68.320008)
		(width 0.2)
		(layer "B.Cu")
		(net 10)
	)
	(segment
		(start 207.861328 68.920008)
		(end 209.111328 68.920008)
		(width 0.2)
		(layer "B.Cu")
		(net 10)
	)
	(segment
		(start 207.861328 68.920008)
		(end 207.136326 68.920008)
		(width 0.2)
		(layer "B.Cu")
		(net 10)
	)
	(segment
		(start 206.536326 68.320008)
		(end 205.586324 68.320008)
		(width 0.2)
		(layer "B.Cu")
		(net 10)
	)
	(segment
		(start 209.111328 68.920008)
		(end 211.038477 68.920008)
		(width 0.2)
		(layer "B.Cu")
		(net 10)
	)
	(segment
		(start 211.038477 68.920008)
		(end 212.161328 67.797157)
		(width 0.2)
		(layer "B.Cu")
		(net 10)
	)
	(segment
		(start 172.729244 89.061)
		(end 182.9 89.061)
		(width 0.1)
		(layer "In2.Cu")
		(net 10)
	)
	(segment
		(start 205.586324 69.420012)
		(end 205.586324 68.320008)
		(width 0.1)
		(layer "In2.Cu")
		(net 10)
	)
	(segment
		(start 196.040992 75.920008)
		(end 204.586328 75.920008)
		(width 0.1)
		(layer "In2.Cu")
		(net 10)
	)
	(segment
		(start 205.286328 75.220008)
		(end 205.286328 69.720008)
		(width 0.1)
		(layer "In2.Cu")
		(net 10)
	)
	(segment
		(start 182.9 89.061)
		(end 196.040992 75.920008)
		(width 0.1)
		(layer "In2.Cu")
		(net 10)
	)
	(segment
		(start 171.486329 89.547156)
		(end 172.243088 89.547156)
		(width 0.1)
		(layer "In2.Cu")
		(net 10)
	)
	(segment
		(start 172.243088 89.547156)
		(end 172.729244 89.061)
		(width 0.1)
		(layer "In2.Cu")
		(net 10)
	)
	(segment
		(start 204.586328 75.920008)
		(end 205.286328 75.220008)
		(width 0.1)
		(layer "In2.Cu")
		(net 10)
	)
	(segment
		(start 171.036329 89.997156)
		(end 171.486329 89.547156)
		(width 0.1)
		(layer "In2.Cu")
		(net 10)
	)
	(segment
		(start 205.286328 69.720008)
		(end 205.586324 69.420012)
		(width 0.1)
		(layer "In2.Cu")
		(net 10)
	)
	(segment
		(start 149.536328 111.997157)
		(end 150.161328 111.372157)
		(width 0.1)
		(layer "In5.Cu")
		(net 10)
	)
	(segment
		(start 152.9334 106.850085)
		(end 150.161328 109.622157)
		(width 0.1)
		(layer "In5.Cu")
		(net 10)
	)
	(segment
		(start 152.9334 95.078653)
		(end 152.9334 106.850085)
		(width 0.1)
		(layer "In5.Cu")
		(net 10)
	)
	(segment
		(start 164.586339 88.847146)
		(end 163.536647 89.896838)
		(width 0.1)
		(layer "In5.Cu")
		(net 10)
	)
	(segment
		(start 171.036329 89.997156)
		(end 170.682776 89.997156)
		(width 0.1)
		(layer "In5.Cu")
		(net 10)
	)
	(segment
		(start 167.639883 88.847146)
		(end 164.586339 88.847146)
		(width 0.1)
		(layer "In5.Cu")
		(net 10)
	)
	(segment
		(start 150.161328 109.622157)
		(end 150.161328 111.372157)
		(width 0.1)
		(layer "In5.Cu")
		(net 10)
	)
	(segment
		(start 168.289894 89.497157)
		(end 167.639883 88.847146)
		(width 0.1)
		(layer "In5.Cu")
		(net 10)
	)
	(segment
		(start 158.115215 89.896838)
		(end 152.9334 95.078653)
		(width 0.1)
		(layer "In5.Cu")
		(net 10)
	)
	(segment
		(start 170.682776 89.997156)
		(end 170.182777 89.497157)
		(width 0.1)
		(layer "In5.Cu")
		(net 10)
	)
	(segment
		(start 170.182777 89.497157)
		(end 168.289894 89.497157)
		(width 0.1)
		(layer "In5.Cu")
		(net 10)
	)
	(segment
		(start 163.536647 89.896838)
		(end 158.115215 89.896838)
		(width 0.1)
		(layer "In5.Cu")
		(net 10)
	)
	(segment
		(start 171.536329 90.497156)
		(end 172.036329 89.997157)
		(width 0.15)
		(layer "F.Cu")
		(net 11)
	)
	(segment
		(start 149.626328 110.907157)
		(end 149.661328 110.872157)
		(width 0.1)
		(layer "F.Cu")
		(net 11)
	)
	(segment
		(start 148.541328 110.907157)
		(end 149.626328 110.907157)
		(width 0.1)
		(layer "F.Cu")
		(net 11)
	)
	(via
		(at 172.036329 89.997157)
		(size 0.5)
		(drill 0.2)
		(layers "F.Cu" "B.Cu")
		(net 11)
	)
	(via
		(at 206.186328 68.820008)
		(size 0.5)
		(drill 0.2)
		(layers "F.Cu" "B.Cu")
		(net 11)
	)
	(via
		(at 149.661328 110.872157)
		(size 0.5)
		(drill 0.2)
		(layers "F.Cu" "B.Cu")
		(net 11)
	)
	(segment
		(start 210.386328 69.420008)
		(end 210.763477 69.797157)
		(width 0.2)
		(layer "B.Cu")
		(net 11)
	)
	(segment
		(start 206.836318 69.420008)
		(end 206.236318 68.820008)
		(width 0.2)
		(layer "B.Cu")
		(net 11)
	)
	(segment
		(start 209.111328 69.420008)
		(end 210.386328 69.420008)
		(width 0.2)
		(layer "B.Cu")
		(net 11)
	)
	(segment
		(start 207.886328 69.420008)
		(end 207.861328 69.420008)
		(width 0.2)
		(layer "B.Cu")
		(net 11)
	)
	(segment
		(start 206.236318 68.820008)
		(end 206.186328 68.820008)
		(width 0.2)
		(layer "B.Cu")
		(net 11)
	)
	(segment
		(start 207.861328 69.420008)
		(end 206.836318 69.420008)
		(width 0.2)
		(layer "B.Cu")
		(net 11)
	)
	(segment
		(start 209.111328 69.420008)
		(end 207.886328 69.420008)
		(width 0.2)
		(layer "B.Cu")
		(net 11)
	)
	(segment
		(start 210.763477 69.797157)
		(end 212.161328 69.797157)
		(width 0.2)
		(layer "B.Cu")
		(net 11)
	)
	(segment
		(start 182.892021 89.449979)
		(end 196.121992 76.220008)
		(width 0.1)
		(layer "In2.Cu")
		(net 11)
	)
	(segment
		(start 206.186328 69.520008)
		(end 206.186328 68.820008)
		(width 0.1)
		(layer "In2.Cu")
		(net 11)
	)
	(segment
		(start 196.121992 76.220008)
		(end 204.886328 76.220008)
		(width 0.1)
		(layer "In2.Cu")
		(net 11)
	)
	(segment
		(start 204.886328 76.220008)
		(end 205.586328 75.520008)
		(width 0.1)
		(layer "In2.Cu")
		(net 11)
	)
	(segment
		(start 172.036329 89.997157)
		(end 172.389882 89.997157)
		(width 0.1)
		(layer "In2.Cu")
		(net 11)
	)
	(segment
		(start 172.389882 89.997157)
		(end 172.937059 89.44998)
		(width 0.1)
		(layer "In2.Cu")
		(net 11)
	)
	(segment
		(start 205.586328 70.120008)
		(end 206.186328 69.520008)
		(width 0.1)
		(layer "In2.Cu")
		(net 11)
	)
	(segment
		(start 172.937059 89.44998)
		(end 182.892021 89.449979)
		(width 0.1)
		(layer "In2.Cu")
		(net 11)
	)
	(segment
		(start 205.586328 75.520008)
		(end 205.586328 70.120008)
		(width 0.1)
		(layer "In2.Cu")
		(net 11)
	)
	(segment
		(start 170.589897 89.447158)
		(end 169.639874 88.497135)
		(width 0.1)
		(layer "In5.Cu")
		(net 11)
	)
	(segment
		(start 152.6794 94.979085)
		(end 152.6794 106.729085)
		(width 0.1)
		(layer "In5.Cu")
		(net 11)
	)
	(segment
		(start 169.639874 88.497135)
		(end 159.146239 88.497135)
		(width 0.1)
		(layer "In5.Cu")
		(net 11)
	)
	(segment
		(start 149.661328 109.747157)
		(end 149.661328 110.872157)
		(width 0.1)
		(layer "In5.Cu")
		(net 11)
	)
	(segment
		(start 152.6794 106.729085)
		(end 149.661328 109.747157)
		(width 0.1)
		(layer "In5.Cu")
		(net 11)
	)
	(segment
		(start 171.48633 89.447158)
		(end 170.589897 89.447158)
		(width 0.1)
		(layer "In5.Cu")
		(net 11)
	)
	(segment
		(start 159.146239 88.497135)
		(end 155.736294 91.90708)
		(width 0.1)
		(layer "In5.Cu")
		(net 11)
	)
	(segment
		(start 155.736294 91.90708)
		(end 152.6794 94.979085)
		(width 0.1)
		(layer "In5.Cu")
		(net 11)
	)
	(segment
		(start 172.036329 89.997157)
		(end 171.48633 89.447158)
		(width 0.1)
		(layer "In5.Cu")
		(net 11)
	)
	(segment
		(start 203.863477 103.797157)
		(end 204.586328 103.797157)
		(width 0.2)
		(layer "F.Cu")
		(net 12)
	)
	(via
		(at 204.586328 103.797157)
		(size 0.5)
		(drill 0.2)
		(layers "F.Cu" "B.Cu")
		(net 12)
	)
	(segment
		(start 204.586328 103.797157)
		(end 207.009179 103.797157)
		(width 0.2)
		(layer "B.Cu")
		(net 12)
	)
	(segment
		(start 207.286328 103.520008)
		(end 208.301328 103.520008)
		(width 0.2)
		(layer "B.Cu")
		(net 12)
	)
	(segment
		(start 208.301328 103.520008)
		(end 208.301328 102.560008)
		(width 0.2)
		(layer "B.Cu")
		(net 12)
	)
	(segment
		(start 207.009179 103.797157)
		(end 207.286328 103.520008)
		(width 0.2)
		(layer "B.Cu")
		(net 12)
	)
	(segment
		(start 208.301328 102.560008)
		(end 208.306328 102.555008)
		(width 0.2)
		(layer "B.Cu")
		(net 12)
	)
	(segment
		(start 204.586328 103.797157)
		(end 204.286327 104.097158)
		(width 0.2)
		(layer "In2.Cu")
		(net 12)
	)
	(segment
		(start 191.546555 125.880235)
		(end 193.086328 127.420008)
		(width 0.2)
		(layer "In2.Cu")
		(net 12)
	)
	(segment
		(start 195.739179 127.420008)
		(end 197.346328 129.027157)
		(width 0.2)
		(layer "In2.Cu")
		(net 12)
	)
	(segment
		(start 204.286327 106.820007)
		(end 205.386328 107.920008)
		(width 0.2)
		(layer "In2.Cu")
		(net 12)
	)
	(segment
		(start 191.546555 116.059781)
		(end 191.546555 125.880235)
		(width 0.2)
		(layer "In2.Cu")
		(net 12)
	)
	(segment
		(start 203.186328 114.020008)
		(end 193.586328 114.020008)
		(width 0.2)
		(layer "In2.Cu")
		(net 12)
	)
	(segment
		(start 193.086328 127.420008)
		(end 195.739179 127.420008)
		(width 0.2)
		(layer "In2.Cu")
		(net 12)
	)
	(segment
		(start 193.586328 114.020008)
		(end 191.546555 116.059781)
		(width 0.2)
		(layer "In2.Cu")
		(net 12)
	)
	(segment
		(start 204.286327 104.097158)
		(end 204.286327 106.820007)
		(width 0.2)
		(layer "In2.Cu")
		(net 12)
	)
	(segment
		(start 205.386328 111.820008)
		(end 203.186328 114.020008)
		(width 0.2)
		(layer "In2.Cu")
		(net 12)
	)
	(segment
		(start 205.386328 107.920008)
		(end 205.386328 111.820008)
		(width 0.2)
		(layer "In2.Cu")
		(net 12)
	)
	(segment
		(start 203.863477 104.797157)
		(end 204.563477 104.797157)
		(width 0.2)
		(layer "F.Cu")
		(net 13)
	)
	(segment
		(start 204.563477 104.797157)
		(end 204.586328 104.820008)
		(width 0.2)
		(layer "F.Cu")
		(net 13)
	)
	(via
		(at 204.786328 104.820008)
		(size 0.5)
		(drill 0.2)
		(layers "F.Cu" "B.Cu")
		(net 13)
	)
	(segment
		(start 207.386328 105.020008)
		(end 208.301328 105.020008)
		(width 0.2)
		(layer "B.Cu")
		(net 13)
	)
	(segment
		(start 207.186328 104.820008)
		(end 207.386328 105.020008)
		(width 0.2)
		(layer "B.Cu")
		(net 13)
	)
	(segment
		(start 208.306328 105.995008)
		(end 208.306328 105.025008)
		(width 0.2)
		(layer "B.Cu")
		(net 13)
	)
	(segment
		(start 208.306328 105.025008)
		(end 208.301328 105.020008)
		(width 0.2)
		(layer "B.Cu")
		(net 13)
	)
	(segment
		(start 204.586328 104.820008)
		(end 207.186328 104.820008)
		(width 0.2)
		(layer "B.Cu")
		(net 13)
	)
	(segment
		(start 211.186328 125.907157)
		(end 211.186328 115.320008)
		(width 0.2)
		(layer "In2.Cu")
		(net 13)
	)
	(segment
		(start 208.066328 129.027157)
		(end 211.186328 125.907157)
		(width 0.2)
		(layer "In2.Cu")
		(net 13)
	)
	(segment
		(start 208.086328 104.820008)
		(end 204.786328 104.820008)
		(width 0.2)
		(layer "In2.Cu")
		(net 13)
	)
	(segment
		(start 209.986328 114.120008)
		(end 209.986328 106.720008)
		(width 0.2)
		(layer "In2.Cu")
		(net 13)
	)
	(segment
		(start 209.986328 106.720008)
		(end 208.086328 104.820008)
		(width 0.2)
		(layer "In2.Cu")
		(net 13)
	)
	(segment
		(start 211.186328 115.320008)
		(end 209.986328 114.120008)
		(width 0.2)
		(layer "In2.Cu")
		(net 13)
	)
	(segment
		(start 171.536329 89.497157)
		(end 172.036329 88.997157)
		(width 0.15)
		(layer "F.Cu")
		(net 14)
	)
	(via blind
		(at 172.036329 88.997157)
		(size 0.5)
		(drill 0.2)
		(layers "F.Cu" "In2.Cu")
		(net 14)
	)
	(via
		(at 192.425 78.52)
		(size 0.5)
		(drill 0.2)
		(layers "F.Cu" "B.Cu")
		(net 14)
	)
	(segment
		(start 209.986328 80.620008)
		(end 209.986328 85.720008)
		(width 0.15)
		(layer "B.Cu")
		(net 14)
	)
	(segment
		(start 209.986328 85.720008)
		(end 211.346328 87.080008)
		(width 0.15)
		(layer "B.Cu")
		(net 14)
	)
	(segment
		(start 207.50532 78.139)
		(end 209.986328 80.620008)
		(width 0.15)
		(layer "B.Cu")
		(net 14)
	)
	(segment
		(start 192.806 78.139)
		(end 207.50532 78.139)
		(width 0.15)
		(layer "B.Cu")
		(net 14)
	)
	(segment
		(start 192.806 78.139)
		(end 192.425 78.52)
		(width 0.15)
		(layer "B.Cu")
		(net 14)
	)
	(segment
		(start 211.346328 87.080008)
		(end 213.186328 87.080008)
		(width 0.15)
		(layer "B.Cu")
		(net 14)
	)
	(segment
		(start 172.036329 88.997157)
		(end 172.439519 88.997157)
		(width 0.1)
		(layer "In2.Cu")
		(net 14)
	)
	(segment
		(start 182.773 88.807)
		(end 192.425 79.155)
		(width 0.1)
		(layer "In2.Cu")
		(net 14)
	)
	(segment
		(start 172.629676 88.807)
		(end 182.773 88.807)
		(width 0.1)
		(layer "In2.Cu")
		(net 14)
	)
	(segment
		(start 192.425 79.155)
		(end 192.425 78.52)
		(width 0.1)
		(layer "In2.Cu")
		(net 14)
	)
	(segment
		(start 172.439519 88.997157)
		(end 172.629676 88.807)
		(width 0.1)
		(layer "In2.Cu")
		(net 14)
	)
	(segment
		(start 172.536329 102.497156)
		(end 173.036329 102.997157)
		(width 0.15)
		(layer "F.Cu")
		(net 15)
	)
	(segment
		(start 180.6735 119.541)
		(end 181.522 119.541)
		(width 0.1)
		(layer "F.Cu")
		(net 15)
	)
	(via blind
		(at 173.036329 102.997157)
		(size 0.5)
		(drill 0.2)
		(layers "F.Cu" "In2.Cu")
		(net 15)
	)
	(via
		(at 181.522 119.541)
		(size 0.5)
		(drill 0.2)
		(layers "F.Cu" "B.Cu")
		(net 15)
	)
	(segment
		(start 174.786318 110.497147)
		(end 174.786318 115.971886)
		(width 0.1)
		(layer "In2.Cu")
		(net 15)
	)
	(segment
		(start 173.036329 102.997157)
		(end 173.510486 102.523)
		(width 0.1)
		(layer "In2.Cu")
		(net 15)
	)
	(segment
		(start 181.522 119.541)
		(end 178.355432 119.541)
		(width 0.1)
		(layer "In2.Cu")
		(net 15)
	)
	(segment
		(start 174.563587 110.274416)
		(end 174.786318 110.497147)
		(width 0.1)
		(layer "In2.Cu")
		(net 15)
	)
	(segment
		(start 173.510486 102.523)
		(end 174.228174 102.523)
		(width 0.1)
		(layer "In2.Cu")
		(net 15)
	)
	(segment
		(start 174.228174 102.523)
		(end 174.563587 102.858413)
		(width 0.1)
		(layer "In2.Cu")
		(net 15)
	)
	(segment
		(start 174.786318 115.971886)
		(end 178.355432 119.541)
		(width 0.1)
		(layer "In2.Cu")
		(net 15)
	)
	(segment
		(start 174.563587 102.858413)
		(end 174.563587 110.274416)
		(width 0.1)
		(layer "In2.Cu")
		(net 15)
	)
	(segment
		(start 172.536329 103.497157)
		(end 173.036329 103.997157)
		(width 0.15)
		(layer "F.Cu")
		(net 16)
	)
	(segment
		(start 168.337 117.001)
		(end 167.4885 117.001)
		(width 0.1)
		(layer "F.Cu")
		(net 16)
	)
	(via blind
		(at 173.036329 103.997157)
		(size 0.5)
		(drill 0.2)
		(layers "F.Cu" "In2.Cu")
		(net 16)
	)
	(via
		(at 167.4885 117.001)
		(size 0.5)
		(drill 0.2)
		(layers "F.Cu" "B.Cu")
		(net 16)
	)
	(segment
		(start 174.01 110.470829)
		(end 174.01 115.985)
		(width 0.1)
		(layer "In2.Cu")
		(net 16)
	)
	(segment
		(start 172.994 117.001)
		(end 167.4885 117.001)
		(width 0.1)
		(layer "In2.Cu")
		(net 16)
	)
	(segment
		(start 173.036329 103.997157)
		(end 172.536328 104.497158)
		(width 0.1)
		(layer "In2.Cu")
		(net 16)
	)
	(segment
		(start 172.536328 104.497158)
		(end 172.536328 108.997157)
		(width 0.1)
		(layer "In2.Cu")
		(net 16)
	)
	(segment
		(start 174.01 115.985)
		(end 172.994 117.001)
		(width 0.1)
		(layer "In2.Cu")
		(net 16)
	)
	(segment
		(start 172.536328 108.997157)
		(end 174.01 110.470829)
		(width 0.1)
		(layer "In2.Cu")
		(net 16)
	)
	(segment
		(start 173.536329 102.497156)
		(end 174.036329 102.997157)
		(width 0.15)
		(layer "F.Cu")
		(net 17)
	)
	(segment
		(start 168.337 118.9925)
		(end 168.3775 119.033)
		(width 0.1)
		(layer "F.Cu")
		(net 17)
	)
	(segment
		(start 168.337 118.271)
		(end 168.337 118.9925)
		(width 0.1)
		(layer "F.Cu")
		(net 17)
	)
	(via blind
		(at 174.036329 102.997157)
		(size 0.5)
		(drill 0.2)
		(layers "F.Cu" "In2.Cu")
		(net 17)
	)
	(via
		(at 168.3775 119.033)
		(size 0.5)
		(drill 0.2)
		(layers "F.Cu" "B.Cu")
		(net 17)
	)
	(segment
		(start 168.337 118.9925)
		(end 168.3775 119.033)
		(width 0.1)
		(layer "B.Cu")
		(net 17)
	)
	(segment
		(start 168.337 118.271)
		(end 168.337 118.9925)
		(width 0.1)
		(layer "B.Cu")
		(net 17)
	)
	(segment
		(start 173.629 119.033)
		(end 174.518 118.144)
		(width 0.1)
		(layer "In2.Cu")
		(net 17)
	)
	(segment
		(start 173.586326 104.297159)
		(end 173.586328 104.297157)
		(width 0.1)
		(layer "In2.Cu")
		(net 17)
	)
	(segment
		(start 173.586328 104.297157)
		(end 173.586328 103.447158)
		(width 0.1)
		(layer "In2.Cu")
		(net 17)
	)
	(segment
		(start 174.518 110.603829)
		(end 173.586326 109.672155)
		(width 0.1)
		(layer "In2.Cu")
		(net 17)
	)
	(segment
		(start 174.518 118.144)
		(end 174.518 110.603829)
		(width 0.1)
		(layer "In2.Cu")
		(net 17)
	)
	(segment
		(start 173.586328 103.447158)
		(end 174.036329 102.997157)
		(width 0.1)
		(layer "In2.Cu")
		(net 17)
	)
	(segment
		(start 168.3775 119.033)
		(end 173.629 119.033)
		(width 0.1)
		(layer "In2.Cu")
		(net 17)
	)
	(segment
		(start 173.586326 109.672155)
		(end 173.586326 104.297159)
		(width 0.1)
		(layer "In2.Cu")
		(net 17)
	)
	(segment
		(start 174.536328 103.497156)
		(end 175.036327 102.997156)
		(width 0.15)
		(layer "F.Cu")
		(net 18)
	)
	(segment
		(start 180.6735 117.001)
		(end 181.458504 117.001)
		(width 0.1)
		(layer "F.Cu")
		(net 18)
	)
	(via blind
		(at 175.036327 102.997156)
		(size 0.5)
		(drill 0.2)
		(layers "F.Cu" "In2.Cu")
		(net 18)
	)
	(via
		(at 181.458504 117.001)
		(size 0.5)
		(drill 0.2)
		(layers "F.Cu" "B.Cu")
		(net 18)
	)
	(segment
		(start 181.458504 117.001)
		(end 180.6735 117.001)
		(width 0.1)
		(layer "B.Cu")
		(net 18)
	)
	(segment
		(start 175.536328 104.872157)
		(end 175.536328 103.497157)
		(width 0.1)
		(layer "In2.Cu")
		(net 18)
	)
	(segment
		(start 181.458504 117.001)
		(end 176.169 117.001)
		(width 0.1)
		(layer "In2.Cu")
		(net 18)
	)
	(segment
		(start 175.536328 103.497157)
		(end 175.036327 102.997156)
		(width 0.1)
		(layer "In2.Cu")
		(net 18)
	)
	(segment
		(start 176.169 117.001)
		(end 175.036329 115.868329)
		(width 0.1)
		(layer "In2.Cu")
		(net 18)
	)
	(segment
		(start 175.036329 115.868329)
		(end 175.036329 105.372156)
		(width 0.1)
		(layer "In2.Cu")
		(net 18)
	)
	(segment
		(start 175.036329 105.372156)
		(end 175.536328 104.872157)
		(width 0.1)
		(layer "In2.Cu")
		(net 18)
	)
	(segment
		(start 172.53633 91.497157)
		(end 173.036329 90.997157)
		(width 0.15)
		(layer "F.Cu")
		(net 19)
	)
	(segment
		(start 206.386328 78.835008)
		(end 205.286328 78.835008)
		(width 0.1)
		(layer "F.Cu")
		(net 19)
	)
	(segment
		(start 205.286328 77.120008)
		(end 205.286328 78.835008)
		(width 0.1)
		(layer "F.Cu")
		(net 19)
	)
	(via blind
		(at 173.036329 90.997157)
		(size 0.5)
		(drill 0.2)
		(layers "F.Cu" "In2.Cu")
		(net 19)
	)
	(via
		(at 205.286328 77.120008)
		(size 0.5)
		(drill 0.2)
		(layers "F.Cu" "B.Cu")
		(net 19)
	)
	(segment
		(start 196.014993 77.470007)
		(end 204.936329 77.470007)
		(width 0.1)
		(layer "In2.Cu")
		(net 19)
	)
	(segment
		(start 173.036329 90.997157)
		(end 173.389882 90.997157)
		(width 0.1)
		(layer "In2.Cu")
		(net 19)
	)
	(segment
		(start 204.936329 77.470007)
		(end 205.286328 77.120008)
		(width 0.1)
		(layer "In2.Cu")
		(net 19)
	)
	(segment
		(start 173.389882 90.997157)
		(end 174.183039 90.204)
		(width 0.1)
		(layer "In2.Cu")
		(net 19)
	)
	(segment
		(start 174.183039 90.204)
		(end 183.281 90.204)
		(width 0.1)
		(layer "In2.Cu")
		(net 19)
	)
	(segment
		(start 183.281 90.204)
		(end 196.014993 77.470007)
		(width 0.1)
		(layer "In2.Cu")
		(net 19)
	)
	(segment
		(start 172.536329 90.497157)
		(end 173.036329 89.997157)
		(width 0.15)
		(layer "F.Cu")
		(net 20)
	)
	(segment
		(start 204.086328 76.720019)
		(end 204.086328 78.735008)
		(width 0.1)
		(layer "F.Cu")
		(net 20)
	)
	(segment
		(start 203.866328 78.835008)
		(end 203.086328 78.835008)
		(width 0.1)
		(layer "F.Cu")
		(net 20)
	)
	(segment
		(start 204.186328 78.835008)
		(end 203.866328 78.835008)
		(width 0.1)
		(layer "F.Cu")
		(net 20)
	)
	(segment
		(start 204.086328 78.735008)
		(end 204.186328 78.835008)
		(width 0.1)
		(layer "F.Cu")
		(net 20)
	)
	(via blind
		(at 173.036329 89.997157)
		(size 0.5)
		(drill 0.2)
		(layers "F.Cu" "In2.Cu")
		(net 20)
	)
	(via
		(at 204.086328 76.720019)
		(size 0.5)
		(drill 0.2)
		(layers "F.Cu" "B.Cu")
		(net 20)
	)
	(segment
		(start 173.036329 89.997157)
		(end 173.333496 89.69999)
		(width 0.1)
		(layer "In2.Cu")
		(net 20)
	)
	(segment
		(start 196.05 76.673)
		(end 204.039309 76.673)
		(width 0.1)
		(layer "In2.Cu")
		(net 20)
	)
	(segment
		(start 204.039309 76.673)
		(end 204.086328 76.720019)
		(width 0.1)
		(layer "In2.Cu")
		(net 20)
	)
	(segment
		(start 183.02301 89.69999)
		(end 196.05 76.673)
		(width 0.1)
		(layer "In2.Cu")
		(net 20)
	)
	(segment
		(start 173.333496 89.69999)
		(end 183.02301 89.69999)
		(width 0.1)
		(layer "In2.Cu")
		(net 20)
	)
	(segment
		(start 166.536329 90.497156)
		(end 166.036329 89.997156)
		(width 0.15)
		(layer "F.Cu")
		(net 21)
	)
	(segment
		(start 197.921336 83.8)
		(end 197.486328 84.235008)
		(width 0.1)
		(layer "F.Cu")
		(net 21)
	)
	(segment
		(start 196.701328 84.235008)
		(end 196.686328 84.220008)
		(width 0.1)
		(layer "F.Cu")
		(net 21)
	)
	(segment
		(start 197.486328 84.235008)
		(end 196.701328 84.235008)
		(width 0.1)
		(layer "F.Cu")
		(net 21)
	)
	(segment
		(start 198.736328 83.8)
		(end 197.921336 83.8)
		(width 0.1)
		(layer "F.Cu")
		(net 21)
	)
	(via blind
		(at 166.036329 89.997156)
		(size 0.5)
		(drill 0.2)
		(layers "F.Cu" "In2.Cu")
		(net 21)
	)
	(via
		(at 196.686328 84.220008)
		(size 0.5)
		(drill 0.2)
		(layers "F.Cu" "B.Cu")
		(net 21)
	)
	(segment
		(start 171.939885 94.247146)
		(end 173.347112 94.247146)
		(width 0.1)
		(layer "In2.Cu")
		(net 21)
	)
	(segment
		(start 184.047736 95.497157)
		(end 189.124885 90.420008)
		(width 0.1)
		(layer "In2.Cu")
		(net 21)
	)
	(segment
		(start 195.286328 84.720008)
		(end 195.786328 84.220008)
		(width 0.1)
		(layer "In2.Cu")
		(net 21)
	)
	(segment
		(start 191.186328 90.420008)
		(end 195.286328 86.320008)
		(width 0.1)
		(layer "In2.Cu")
		(net 21)
	)
	(segment
		(start 166.036329 89.997156)
		(end 166.586329 90.547156)
		(width 0.1)
		(layer "In2.Cu")
		(net 21)
	)
	(segment
		(start 195.786328 84.220008)
		(end 196.686328 84.220008)
		(width 0.1)
		(layer "In2.Cu")
		(net 21)
	)
	(segment
		(start 189.124885 90.420008)
		(end 191.186328 90.420008)
		(width 0.1)
		(layer "In2.Cu")
		(net 21)
	)
	(segment
		(start 174.597123 95.497157)
		(end 184.047736 95.497157)
		(width 0.1)
		(layer "In2.Cu")
		(net 21)
	)
	(segment
		(start 195.286328 86.320008)
		(end 195.286328 84.720008)
		(width 0.1)
		(layer "In2.Cu")
		(net 21)
	)
	(segment
		(start 173.347112 94.247146)
		(end 174.597123 95.497157)
		(width 0.1)
		(layer "In2.Cu")
		(net 21)
	)
	(segment
		(start 166.586329 90.547156)
		(end 168.239895 90.547156)
		(width 0.1)
		(layer "In2.Cu")
		(net 21)
	)
	(segment
		(start 168.239895 90.547156)
		(end 171.939885 94.247146)
		(width 0.1)
		(layer "In2.Cu")
		(net 21)
	)
	(segment
		(start 198.859179 96.347157)
		(end 199.686328 97.174306)
		(width 0.1)
		(layer "F.Cu")
		(net 22)
	)
	(segment
		(start 192.53203 96.691977)
		(end 192.554282 96.689469)
		(width 0.1)
		(layer "F.Cu")
		(net 22)
	)
	(segment
		(start 191.93203 96.056635)
		(end 191.954282 96.059143)
		(width 0.1)
		(layer "F.Cu")
		(net 22)
	)
	(segment
		(start 192.688641 96.066539)
		(end 192.709777 96.059143)
		(width 0.1)
		(layer "F.Cu")
		(net 22)
	)
	(segment
		(start 193.43203 96.374306)
		(end 193.434537 96.352053)
		(width 0.1)
		(layer "F.Cu")
		(net 22)
	)
	(segment
		(start 191.975418 96.066539)
		(end 191.994378 96.078452)
		(width 0.1)
		(layer "F.Cu")
		(net 22)
	)
	(segment
		(start 192.453846 96.654325)
		(end 192.469681 96.67016)
		(width 0.1)
		(layer "F.Cu")
		(net 22)
	)
	(segment
		(start 192.222126 96.635365)
		(end 192.229522 96.614229)
		(width 0.1)
		(layer "F.Cu")
		(net 22)
	)
	(segment
		(start 193.434537 96.352053)
		(end 193.441933 96.330917)
		(width 0.1)
		(layer "F.Cu")
		(net 22)
	)
	(segment
		(start 193.488641 96.284209)
		(end 193.509777 96.276813)
		(width 0.1)
		(layer "F.Cu")
		(net 22)
	)
	(segment
		(start 192.03203 96.156635)
		(end 192.03203 96.591977)
		(width 0.1)
		(layer "F.Cu")
		(net 22)
	)
	(segment
		(start 192.869681 96.67016)
		(end 192.888641 96.682073)
		(width 0.1)
		(layer "F.Cu")
		(net 22)
	)
	(segment
		(start 199.686328 97.174306)
		(end 199.686328 99.620008)
		(width 0.1)
		(layer "F.Cu")
		(net 22)
	)
	(segment
		(start 192.241933 96.113247)
		(end 192.253846 96.094287)
		(width 0.1)
		(layer "F.Cu")
		(net 22)
	)
	(segment
		(start 192.269681 96.078452)
		(end 192.288641 96.066539)
		(width 0.1)
		(layer "F.Cu")
		(net 22)
	)
	(segment
		(start 192.010213 96.094287)
		(end 192.022126 96.113247)
		(width 0.1)
		(layer "F.Cu")
		(net 22)
	)
	(segment
		(start 191.822126 96.635365)
		(end 191.829522 96.614229)
		(width 0.1)
		(layer "F.Cu")
		(net 22)
	)
	(segment
		(start 193.422126 96.635365)
		(end 193.429522 96.614229)
		(width 0.1)
		(layer "F.Cu")
		(net 22)
	)
	(segment
		(start 193.53203 96.274306)
		(end 198.786328 96.274306)
		(width 0.1)
		(layer "F.Cu")
		(net 22)
	)
	(segment
		(start 191.834537 96.134383)
		(end 191.841933 96.113247)
		(width 0.1)
		(layer "F.Cu")
		(net 22)
	)
	(segment
		(start 192.669681 96.078452)
		(end 192.688641 96.066539)
		(width 0.1)
		(layer "F.Cu")
		(net 22)
	)
	(segment
		(start 193.234537 96.614229)
		(end 193.241933 96.635365)
		(width 0.1)
		(layer "F.Cu")
		(net 22)
	)
	(segment
		(start 193.288641 96.682073)
		(end 193.309777 96.689469)
		(width 0.1)
		(layer "F.Cu")
		(net 22)
	)
	(segment
		(start 192.041933 96.635365)
		(end 192.053846 96.654325)
		(width 0.1)
		(layer "F.Cu")
		(net 22)
	)
	(segment
		(start 198.786328 96.274306)
		(end 198.859179 96.347157)
		(width 0.1)
		(layer "F.Cu")
		(net 22)
	)
	(segment
		(start 192.394378 96.078452)
		(end 192.410213 96.094287)
		(width 0.1)
		(layer "F.Cu")
		(net 22)
	)
	(segment
		(start 192.175418 96.682073)
		(end 192.194378 96.67016)
		(width 0.1)
		(layer "F.Cu")
		(net 22)
	)
	(segment
		(start 192.109777 96.689469)
		(end 192.13203 96.691977)
		(width 0.1)
		(layer "F.Cu")
		(net 22)
	)
	(segment
		(start 191.810213 96.654325)
		(end 191.822126 96.635365)
		(width 0.1)
		(layer "F.Cu")
		(net 22)
	)
	(segment
		(start 192.053846 96.654325)
		(end 192.069681 96.67016)
		(width 0.1)
		(layer "F.Cu")
		(net 22)
	)
	(segment
		(start 192.975418 96.682073)
		(end 192.994378 96.67016)
		(width 0.1)
		(layer "F.Cu")
		(net 22)
	)
	(segment
		(start 192.469681 96.67016)
		(end 192.488641 96.682073)
		(width 0.1)
		(layer "F.Cu")
		(net 22)
	)
	(segment
		(start 192.994378 96.67016)
		(end 193.010213 96.654325)
		(width 0.1)
		(layer "F.Cu")
		(net 22)
	)
	(segment
		(start 192.83203 96.156635)
		(end 192.83203 96.591977)
		(width 0.1)
		(layer "F.Cu")
		(net 22)
	)
	(segment
		(start 193.022126 96.635365)
		(end 193.029522 96.614229)
		(width 0.1)
		(layer "F.Cu")
		(net 22)
	)
	(segment
		(start 192.834537 96.614229)
		(end 192.841933 96.635365)
		(width 0.1)
		(layer "F.Cu")
		(net 22)
	)
	(segment
		(start 191.829522 96.614229)
		(end 191.83203 96.591977)
		(width 0.1)
		(layer "F.Cu")
		(net 22)
	)
	(segment
		(start 188.886328 96.274306)
		(end 191.53203 96.274306)
		(width 0.1)
		(layer "F.Cu")
		(net 22)
	)
	(segment
		(start 193.253846 96.654325)
		(end 193.269681 96.67016)
		(width 0.1)
		(layer "F.Cu")
		(net 22)
	)
	(segment
		(start 191.688641 96.682073)
		(end 191.709777 96.689469)
		(width 0.1)
		(layer "F.Cu")
		(net 22)
	)
	(segment
		(start 192.23203 96.156635)
		(end 192.234537 96.134383)
		(width 0.1)
		(layer "F.Cu")
		(net 22)
	)
	(segment
		(start 193.229522 96.134383)
		(end 193.23203 96.156635)
		(width 0.1)
		(layer "F.Cu")
		(net 22)
	)
	(segment
		(start 192.554282 96.689469)
		(end 192.575418 96.682073)
		(width 0.1)
		(layer "F.Cu")
		(net 22)
	)
	(segment
		(start 191.841933 96.113247)
		(end 191.853846 96.094287)
		(width 0.1)
		(layer "F.Cu")
		(net 22)
	)
	(segment
		(start 192.03203 96.591977)
		(end 192.034537 96.614229)
		(width 0.1)
		(layer "F.Cu")
		(net 22)
	)
	(segment
		(start 192.709777 96.059143)
		(end 192.73203 96.056635)
		(width 0.1)
		(layer "F.Cu")
		(net 22)
	)
	(segment
		(start 192.422126 96.113247)
		(end 192.429522 96.134383)
		(width 0.1)
		(layer "F.Cu")
		(net 22)
	)
	(segment
		(start 191.994378 96.078452)
		(end 192.010213 96.094287)
		(width 0.1)
		(layer "F.Cu")
		(net 22)
	)
	(segment
		(start 191.888641 96.066539)
		(end 191.909777 96.059143)
		(width 0.1)
		(layer "F.Cu")
		(net 22)
	)
	(segment
		(start 193.109777 96.059143)
		(end 193.13203 96.056635)
		(width 0.1)
		(layer "F.Cu")
		(net 22)
	)
	(segment
		(start 193.410213 96.654325)
		(end 193.422126 96.635365)
		(width 0.1)
		(layer "F.Cu")
		(net 22)
	)
	(segment
		(start 191.909777 96.059143)
		(end 191.93203 96.056635)
		(width 0.1)
		(layer "F.Cu")
		(net 22)
	)
	(segment
		(start 192.575418 96.682073)
		(end 192.594378 96.67016)
		(width 0.1)
		(layer "F.Cu")
		(net 22)
	)
	(segment
		(start 193.23203 96.591977)
		(end 193.234537 96.614229)
		(width 0.1)
		(layer "F.Cu")
		(net 22)
	)
	(segment
		(start 193.053846 96.094287)
		(end 193.069681 96.078452)
		(width 0.1)
		(layer "F.Cu")
		(net 22)
	)
	(segment
		(start 193.269681 96.67016)
		(end 193.288641 96.682073)
		(width 0.1)
		(layer "F.Cu")
		(net 22)
	)
	(segment
		(start 192.888641 96.682073)
		(end 192.909777 96.689469)
		(width 0.1)
		(layer "F.Cu")
		(net 22)
	)
	(segment
		(start 191.73203 96.691977)
		(end 191.754282 96.689469)
		(width 0.1)
		(layer "F.Cu")
		(net 22)
	)
	(segment
		(start 192.23203 96.591977)
		(end 192.23203 96.156635)
		(width 0.1)
		(layer "F.Cu")
		(net 22)
	)
	(segment
		(start 191.775418 96.682073)
		(end 191.794378 96.67016)
		(width 0.1)
		(layer "F.Cu")
		(net 22)
	)
	(segment
		(start 192.034537 96.614229)
		(end 192.041933 96.635365)
		(width 0.1)
		(layer "F.Cu")
		(net 22)
	)
	(segment
		(start 191.53203 96.274306)
		(end 191.554282 96.276813)
		(width 0.1)
		(layer "F.Cu")
		(net 22)
	)
	(segment
		(start 192.309777 96.059143)
		(end 192.33203 96.056635)
		(width 0.1)
		(layer "F.Cu")
		(net 22)
	)
	(segment
		(start 193.069681 96.078452)
		(end 193.088641 96.066539)
		(width 0.1)
		(layer "F.Cu")
		(net 22)
	)
	(segment
		(start 193.010213 96.654325)
		(end 193.022126 96.635365)
		(width 0.1)
		(layer "F.Cu")
		(net 22)
	)
	(segment
		(start 192.775418 96.066539)
		(end 192.794378 96.078452)
		(width 0.1)
		(layer "F.Cu")
		(net 22)
	)
	(segment
		(start 193.23203 96.156635)
		(end 193.23203 96.591977)
		(width 0.1)
		(layer "F.Cu")
		(net 22)
	)
	(segment
		(start 193.175418 96.066539)
		(end 193.194378 96.078452)
		(width 0.1)
		(layer "F.Cu")
		(net 22)
	)
	(segment
		(start 191.641933 96.635365)
		(end 191.653846 96.654325)
		(width 0.1)
		(layer "F.Cu")
		(net 22)
	)
	(segment
		(start 192.022126 96.113247)
		(end 192.029522 96.134383)
		(width 0.1)
		(layer "F.Cu")
		(net 22)
	)
	(segment
		(start 192.429522 96.134383)
		(end 192.43203 96.156635)
		(width 0.1)
		(layer "F.Cu")
		(net 22)
	)
	(segment
		(start 192.594378 96.67016)
		(end 192.610213 96.654325)
		(width 0.1)
		(layer "F.Cu")
		(net 22)
	)
	(segment
		(start 192.194378 96.67016)
		(end 192.210213 96.654325)
		(width 0.1)
		(layer "F.Cu")
		(net 22)
	)
	(segment
		(start 193.33203 96.691977)
		(end 193.354282 96.689469)
		(width 0.1)
		(layer "F.Cu")
		(net 22)
	)
	(segment
		(start 191.63203 96.591977)
		(end 191.634537 96.614229)
		(width 0.1)
		(layer "F.Cu")
		(net 22)
	)
	(segment
		(start 193.13203 96.056635)
		(end 193.154282 96.059143)
		(width 0.1)
		(layer "F.Cu")
		(net 22)
	)
	(segment
		(start 193.210213 96.094287)
		(end 193.222126 96.113247)
		(width 0.1)
		(layer "F.Cu")
		(net 22)
	)
	(segment
		(start 191.83203 96.156635)
		(end 191.834537 96.134383)
		(width 0.1)
		(layer "F.Cu")
		(net 22)
	)
	(segment
		(start 192.794378 96.078452)
		(end 192.810213 96.094287)
		(width 0.1)
		(layer "F.Cu")
		(net 22)
	)
	(segment
		(start 192.43203 96.156635)
		(end 192.43203 96.591977)
		(width 0.1)
		(layer "F.Cu")
		(net 22)
	)
	(segment
		(start 192.954282 96.689469)
		(end 192.975418 96.682073)
		(width 0.1)
		(layer "F.Cu")
		(net 22)
	)
	(segment
		(start 192.253846 96.094287)
		(end 192.269681 96.078452)
		(width 0.1)
		(layer "F.Cu")
		(net 22)
	)
	(segment
		(start 191.869681 96.078452)
		(end 191.888641 96.066539)
		(width 0.1)
		(layer "F.Cu")
		(net 22)
	)
	(segment
		(start 191.554282 96.276813)
		(end 191.575418 96.284209)
		(width 0.1)
		(layer "F.Cu")
		(net 22)
	)
	(segment
		(start 192.229522 96.614229)
		(end 192.23203 96.591977)
		(width 0.1)
		(layer "F.Cu")
		(net 22)
	)
	(segment
		(start 193.509777 96.276813)
		(end 193.53203 96.274306)
		(width 0.1)
		(layer "F.Cu")
		(net 22)
	)
	(segment
		(start 192.410213 96.094287)
		(end 192.422126 96.113247)
		(width 0.1)
		(layer "F.Cu")
		(net 22)
	)
	(segment
		(start 192.354282 96.059143)
		(end 192.375418 96.066539)
		(width 0.1)
		(layer "F.Cu")
		(net 22)
	)
	(segment
		(start 192.154282 96.689469)
		(end 192.175418 96.682073)
		(width 0.1)
		(layer "F.Cu")
		(net 22)
	)
	(segment
		(start 193.194378 96.078452)
		(end 193.210213 96.094287)
		(width 0.1)
		(layer "F.Cu")
		(net 22)
	)
	(segment
		(start 193.453846 96.311957)
		(end 193.469681 96.296122)
		(width 0.1)
		(layer "F.Cu")
		(net 22)
	)
	(segment
		(start 193.03203 96.156635)
		(end 193.034537 96.134383)
		(width 0.1)
		(layer "F.Cu")
		(net 22)
	)
	(segment
		(start 192.822126 96.113247)
		(end 192.829522 96.134383)
		(width 0.1)
		(layer "F.Cu")
		(net 22)
	)
	(segment
		(start 191.575418 96.284209)
		(end 191.594378 96.296122)
		(width 0.1)
		(layer "F.Cu")
		(net 22)
	)
	(segment
		(start 192.909777 96.689469)
		(end 192.93203 96.691977)
		(width 0.1)
		(layer "F.Cu")
		(net 22)
	)
	(segment
		(start 192.441933 96.635365)
		(end 192.453846 96.654325)
		(width 0.1)
		(layer "F.Cu")
		(net 22)
	)
	(segment
		(start 192.622126 96.635365)
		(end 192.629522 96.614229)
		(width 0.1)
		(layer "F.Cu")
		(net 22)
	)
	(segment
		(start 192.13203 96.691977)
		(end 192.154282 96.689469)
		(width 0.1)
		(layer "F.Cu")
		(net 22)
	)
	(segment
		(start 191.853846 96.094287)
		(end 191.869681 96.078452)
		(width 0.1)
		(layer "F.Cu")
		(net 22)
	)
	(segment
		(start 192.488641 96.682073)
		(end 192.509777 96.689469)
		(width 0.1)
		(layer "F.Cu")
		(net 22)
	)
	(segment
		(start 193.394378 96.67016)
		(end 193.410213 96.654325)
		(width 0.1)
		(layer "F.Cu")
		(net 22)
	)
	(segment
		(start 193.309777 96.689469)
		(end 193.33203 96.691977)
		(width 0.1)
		(layer "F.Cu")
		(net 22)
	)
	(segment
		(start 191.709777 96.689469)
		(end 191.73203 96.691977)
		(width 0.1)
		(layer "F.Cu")
		(net 22)
	)
	(segment
		(start 193.088641 96.066539)
		(end 193.109777 96.059143)
		(width 0.1)
		(layer "F.Cu")
		(net 22)
	)
	(segment
		(start 193.43203 96.591977)
		(end 193.43203 96.374306)
		(width 0.1)
		(layer "F.Cu")
		(net 22)
	)
	(segment
		(start 193.354282 96.689469)
		(end 193.375418 96.682073)
		(width 0.1)
		(layer "F.Cu")
		(net 22)
	)
	(segment
		(start 191.754282 96.689469)
		(end 191.775418 96.682073)
		(width 0.1)
		(layer "F.Cu")
		(net 22)
	)
	(segment
		(start 192.434537 96.614229)
		(end 192.441933 96.635365)
		(width 0.1)
		(layer "F.Cu")
		(net 22)
	)
	(segment
		(start 192.641933 96.113247)
		(end 192.653846 96.094287)
		(width 0.1)
		(layer "F.Cu")
		(net 22)
	)
	(segment
		(start 192.234537 96.134383)
		(end 192.241933 96.113247)
		(width 0.1)
		(layer "F.Cu")
		(net 22)
	)
	(segment
		(start 192.83203 96.591977)
		(end 192.834537 96.614229)
		(width 0.1)
		(layer "F.Cu")
		(net 22)
	)
	(segment
		(start 191.63203 96.374306)
		(end 191.63203 96.591977)
		(width 0.1)
		(layer "F.Cu")
		(net 22)
	)
	(segment
		(start 193.429522 96.614229)
		(end 193.43203 96.591977)
		(width 0.1)
		(layer "F.Cu")
		(net 22)
	)
	(segment
		(start 193.041933 96.113247)
		(end 193.053846 96.094287)
		(width 0.1)
		(layer "F.Cu")
		(net 22)
	)
	(segment
		(start 192.829522 96.134383)
		(end 192.83203 96.156635)
		(width 0.1)
		(layer "F.Cu")
		(net 22)
	)
	(segment
		(start 191.634537 96.614229)
		(end 191.641933 96.635365)
		(width 0.1)
		(layer "F.Cu")
		(net 22)
	)
	(segment
		(start 191.622126 96.330917)
		(end 191.629522 96.352053)
		(width 0.1)
		(layer "F.Cu")
		(net 22)
	)
	(segment
		(start 192.375418 96.066539)
		(end 192.394378 96.078452)
		(width 0.1)
		(layer "F.Cu")
		(net 22)
	)
	(segment
		(start 185.163477 99.997157)
		(end 188.886328 96.274306)
		(width 0.1)
		(layer "F.Cu")
		(net 22)
	)
	(segment
		(start 193.03203 96.591977)
		(end 193.03203 96.156635)
		(width 0.1)
		(layer "F.Cu")
		(net 22)
	)
	(segment
		(start 192.73203 96.056635)
		(end 192.754282 96.059143)
		(width 0.1)
		(layer "F.Cu")
		(net 22)
	)
	(segment
		(start 178.536328 100.497157)
		(end 179.036328 99.997157)
		(width 0.1)
		(layer "F.Cu")
		(net 22)
	)
	(segment
		(start 191.794378 96.67016)
		(end 191.810213 96.654325)
		(width 0.1)
		(layer "F.Cu")
		(net 22)
	)
	(segment
		(start 193.222126 96.113247)
		(end 193.229522 96.134383)
		(width 0.1)
		(layer "F.Cu")
		(net 22)
	)
	(segment
		(start 192.069681 96.67016)
		(end 192.088641 96.682073)
		(width 0.1)
		(layer "F.Cu")
		(net 22)
	)
	(segment
		(start 192.93203 96.691977)
		(end 192.954282 96.689469)
		(width 0.1)
		(layer "F.Cu")
		(net 22)
	)
	(segment
		(start 192.509777 96.689469)
		(end 192.53203 96.691977)
		(width 0.1)
		(layer "F.Cu")
		(net 22)
	)
	(segment
		(start 192.754282 96.059143)
		(end 192.775418 96.066539)
		(width 0.1)
		(layer "F.Cu")
		(net 22)
	)
	(segment
		(start 191.653846 96.654325)
		(end 191.669681 96.67016)
		(width 0.1)
		(layer "F.Cu")
		(net 22)
	)
	(segment
		(start 192.288641 96.066539)
		(end 192.309777 96.059143)
		(width 0.1)
		(layer "F.Cu")
		(net 22)
	)
	(segment
		(start 191.629522 96.352053)
		(end 191.63203 96.374306)
		(width 0.1)
		(layer "F.Cu")
		(net 22)
	)
	(segment
		(start 191.669681 96.67016)
		(end 191.688641 96.682073)
		(width 0.1)
		(layer "F.Cu")
		(net 22)
	)
	(segment
		(start 179.036328 99.997157)
		(end 185.163477 99.997157)
		(width 0.1)
		(layer "F.Cu")
		(net 22)
	)
	(segment
		(start 192.653846 96.094287)
		(end 192.669681 96.078452)
		(width 0.1)
		(layer "F.Cu")
		(net 22)
	)
	(segment
		(start 192.634537 96.134383)
		(end 192.641933 96.113247)
		(width 0.1)
		(layer "F.Cu")
		(net 22)
	)
	(segment
		(start 192.810213 96.094287)
		(end 192.822126 96.113247)
		(width 0.1)
		(layer "F.Cu")
		(net 22)
	)
	(segment
		(start 192.210213 96.654325)
		(end 192.222126 96.635365)
		(width 0.1)
		(layer "F.Cu")
		(net 22)
	)
	(segment
		(start 191.83203 96.591977)
		(end 191.83203 96.156635)
		(width 0.1)
		(layer "F.Cu")
		(net 22)
	)
	(segment
		(start 192.841933 96.635365)
		(end 192.853846 96.654325)
		(width 0.1)
		(layer "F.Cu")
		(net 22)
	)
	(segment
		(start 193.034537 96.134383)
		(end 193.041933 96.113247)
		(width 0.1)
		(layer "F.Cu")
		(net 22)
	)
	(segment
		(start 193.029522 96.614229)
		(end 193.03203 96.591977)
		(width 0.1)
		(layer "F.Cu")
		(net 22)
	)
	(segment
		(start 192.43203 96.591977)
		(end 192.434537 96.614229)
		(width 0.1)
		(layer "F.Cu")
		(net 22)
	)
	(segment
		(start 193.375418 96.682073)
		(end 193.394378 96.67016)
		(width 0.1)
		(layer "F.Cu")
		(net 22)
	)
	(segment
		(start 192.33203 96.056635)
		(end 192.354282 96.059143)
		(width 0.1)
		(layer "F.Cu")
		(net 22)
	)
	(segment
		(start 191.954282 96.059143)
		(end 191.975418 96.066539)
		(width 0.1)
		(layer "F.Cu")
		(net 22)
	)
	(segment
		(start 192.853846 96.654325)
		(end 192.869681 96.67016)
		(width 0.1)
		(layer "F.Cu")
		(net 22)
	)
	(segment
		(start 193.241933 96.635365)
		(end 193.253846 96.654325)
		(width 0.1)
		(layer "F.Cu")
		(net 22)
	)
	(segment
		(start 193.469681 96.296122)
		(end 193.488641 96.284209)
		(width 0.1)
		(layer "F.Cu")
		(net 22)
	)
	(segment
		(start 193.441933 96.330917)
		(end 193.453846 96.311957)
		(width 0.1)
		(layer "F.Cu")
		(net 22)
	)
	(segment
		(start 191.594378 96.296122)
		(end 191.610213 96.311957)
		(width 0.1)
		(layer "F.Cu")
		(net 22)
	)
	(segment
		(start 193.154282 96.059143)
		(end 193.175418 96.066539)
		(width 0.1)
		(layer "F.Cu")
		(net 22)
	)
	(segment
		(start 191.610213 96.311957)
		(end 191.622126 96.330917)
		(width 0.1)
		(layer "F.Cu")
		(net 22)
	)
	(segment
		(start 192.63203 96.156635)
		(end 192.634537 96.134383)
		(width 0.1)
		(layer "F.Cu")
		(net 22)
	)
	(segment
		(start 192.088641 96.682073)
		(end 192.109777 96.689469)
		(width 0.1)
		(layer "F.Cu")
		(net 22)
	)
	(segment
		(start 192.610213 96.654325)
		(end 192.622126 96.635365)
		(width 0.1)
		(layer "F.Cu")
		(net 22)
	)
	(segment
		(start 192.629522 96.614229)
		(end 192.63203 96.591977)
		(width 0.1)
		(layer "F.Cu")
		(net 22)
	)
	(segment
		(start 192.63203 96.591977)
		(end 192.63203 96.156635)
		(width 0.1)
		(layer "F.Cu")
		(net 22)
	)
	(segment
		(start 192.029522 96.134383)
		(end 192.03203 96.156635)
		(width 0.1)
		(layer "F.Cu")
		(net 22)
	)
	(via
		(at 198.859179 96.347157)
		(size 0.5)
		(drill 0.2)
		(layers "F.Cu" "B.Cu")
		(net 22)
	)
	(segment
		(start 198.771328 96.435008)
		(end 198.859179 96.347157)
		(width 0.2)
		(layer "B.Cu")
		(net 22)
	)
	(segment
		(start 198.786328 95.605008)
		(end 198.786328 96.274306)
		(width 0.2)
		(layer "B.Cu")
		(net 22)
	)
	(segment
		(start 198.771328 96.960008)
		(end 198.771328 96.435008)
		(width 0.2)
		(layer "B.Cu")
		(net 22)
	)
	(segment
		(start 190.543133 95.447586)
		(end 190.550529 95.42645)
		(width 0.1)
		(layer "F.Cu")
		(net 23)
	)
	(segment
		(start 190.718809 95.40749)
		(end 190.730722 95.42645)
		(width 0.1)
		(layer "F.Cu")
		(net 23)
	)
	(segment
		(start 190.518809 95.941122)
		(end 190.530722 95.922162)
		(width 0.1)
		(layer "F.Cu")
		(net 23)
	)
	(segment
		(start 190.578277 95.391655)
		(end 190.597237 95.379742)
		(width 0.1)
		(layer "F.Cu")
		(net 23)
	)
	(segment
		(start 190.743133 95.901026)
		(end 190.750529 95.922162)
		(width 0.1)
		(layer "F.Cu")
		(net 23)
	)
	(segment
		(start 191.294924 95.720008)
		(end 199.13203 95.720008)
		(width 0.1)
		(layer "F.Cu")
		(net 23)
	)
	(segment
		(start 189.840626 95.774306)
		(end 189.862878 95.776813)
		(width 0.1)
		(layer "F.Cu")
		(net 23)
	)
	(segment
		(start 179.536328 99.497157)
		(end 184.663477 99.497157)
		(width 0.1)
		(layer "F.Cu")
		(net 23)
	)
	(segment
		(start 190.840626 95.978774)
		(end 190.862878 95.976266)
		(width 0.1)
		(layer "F.Cu")
		(net 23)
	)
	(segment
		(start 191.062878 95.372346)
		(end 191.084014 95.379742)
		(width 0.1)
		(layer "F.Cu")
		(net 23)
	)
	(segment
		(start 191.118809 95.40749)
		(end 191.130722 95.42645)
		(width 0.1)
		(layer "F.Cu")
		(net 23)
	)
	(segment
		(start 190.340626 95.469838)
		(end 190.340626 95.878774)
		(width 0.1)
		(layer "F.Cu")
		(net 23)
	)
	(segment
		(start 190.318809 95.40749)
		(end 190.330722 95.42645)
		(width 0.1)
		(layer "F.Cu")
		(net 23)
	)
	(segment
		(start 190.338118 95.447586)
		(end 190.340626 95.469838)
		(width 0.1)
		(layer "F.Cu")
		(net 23)
	)
	(segment
		(start 190.197237 95.379742)
		(end 190.218373 95.372346)
		(width 0.1)
		(layer "F.Cu")
		(net 23)
	)
	(segment
		(start 189.997237 95.96887)
		(end 190.018373 95.976266)
		(width 0.1)
		(layer "F.Cu")
		(net 23)
	)
	(segment
		(start 190.818373 95.976266)
		(end 190.840626 95.978774)
		(width 0.1)
		(layer "F.Cu")
		(net 23)
	)
	(segment
		(start 190.340626 95.878774)
		(end 190.343133 95.901026)
		(width 0.1)
		(layer "F.Cu")
		(net 23)
	)
	(segment
		(start 190.978277 95.391655)
		(end 190.997237 95.379742)
		(width 0.1)
		(layer "F.Cu")
		(net 23)
	)
	(segment
		(start 199.13203 95.720008)
		(end 200.186328 96.774306)
		(width 0.1)
		(layer "F.Cu")
		(net 23)
	)
	(segment
		(start 191.178277 95.75249)
		(end 191.197237 95.764403)
		(width 0.1)
		(layer "F.Cu")
		(net 23)
	)
	(segment
		(start 190.240626 95.369838)
		(end 190.262878 95.372346)
		(width 0.1)
		(layer "F.Cu")
		(net 23)
	)
	(segment
		(start 190.118809 95.941122)
		(end 190.130722 95.922162)
		(width 0.1)
		(layer "F.Cu")
		(net 23)
	)
	(segment
		(start 191.018373 95.372346)
		(end 191.040626 95.369838)
		(width 0.1)
		(layer "F.Cu")
		(net 23)
	)
	(segment
		(start 190.178277 95.391655)
		(end 190.197237 95.379742)
		(width 0.1)
		(layer "F.Cu")
		(net 23)
	)
	(segment
		(start 190.730722 95.42645)
		(end 190.738118 95.447586)
		(width 0.1)
		(layer "F.Cu")
		(net 23)
	)
	(segment
		(start 190.350529 95.922162)
		(end 190.362442 95.941122)
		(width 0.1)
		(layer "F.Cu")
		(net 23)
	)
	(segment
		(start 190.930722 95.922162)
		(end 190.938118 95.901026)
		(width 0.1)
		(layer "F.Cu")
		(net 23)
	)
	(segment
		(start 191.040626 95.369838)
		(end 191.062878 95.372346)
		(width 0.1)
		(layer "F.Cu")
		(net 23)
	)
	(segment
		(start 189.943133 95.901026)
		(end 189.950529 95.922162)
		(width 0.1)
		(layer "F.Cu")
		(net 23)
	)
	(segment
		(start 190.962442 95.40749)
		(end 190.978277 95.391655)
		(width 0.1)
		(layer "F.Cu")
		(net 23)
	)
	(segment
		(start 190.884014 95.96887)
		(end 190.902974 95.956957)
		(width 0.1)
		(layer "F.Cu")
		(net 23)
	)
	(segment
		(start 190.378277 95.956957)
		(end 190.397237 95.96887)
		(width 0.1)
		(layer "F.Cu")
		(net 23)
	)
	(segment
		(start 190.938118 95.901026)
		(end 190.940626 95.878774)
		(width 0.1)
		(layer "F.Cu")
		(net 23)
	)
	(segment
		(start 190.918809 95.941122)
		(end 190.930722 95.922162)
		(width 0.1)
		(layer "F.Cu")
		(net 23)
	)
	(segment
		(start 190.138118 95.901026)
		(end 190.140626 95.878774)
		(width 0.1)
		(layer "F.Cu")
		(net 23)
	)
	(segment
		(start 190.997237 95.379742)
		(end 191.018373 95.372346)
		(width 0.1)
		(layer "F.Cu")
		(net 23)
	)
	(segment
		(start 190.440626 95.978774)
		(end 190.462878 95.976266)
		(width 0.1)
		(layer "F.Cu")
		(net 23)
	)
	(segment
		(start 190.130722 95.922162)
		(end 190.138118 95.901026)
		(width 0.1)
		(layer "F.Cu")
		(net 23)
	)
	(segment
		(start 190.862878 95.976266)
		(end 190.884014 95.96887)
		(width 0.1)
		(layer "F.Cu")
		(net 23)
	)
	(segment
		(start 190.684014 95.379742)
		(end 190.702974 95.391655)
		(width 0.1)
		(layer "F.Cu")
		(net 23)
	)
	(segment
		(start 190.084014 95.96887)
		(end 190.102974 95.956957)
		(width 0.1)
		(layer "F.Cu")
		(net 23)
	)
	(segment
		(start 190.740626 95.878774)
		(end 190.743133 95.901026)
		(width 0.1)
		(layer "F.Cu")
		(net 23)
	)
	(segment
		(start 190.950529 95.42645)
		(end 190.962442 95.40749)
		(width 0.1)
		(layer "F.Cu")
		(net 23)
	)
	(segment
		(start 190.540626 95.878774)
		(end 190.540626 95.469838)
		(width 0.1)
		(layer "F.Cu")
		(net 23)
	)
	(segment
		(start 190.797237 95.96887)
		(end 190.818373 95.976266)
		(width 0.1)
		(layer "F.Cu")
		(net 23)
	)
	(segment
		(start 190.218373 95.372346)
		(end 190.240626 95.369838)
		(width 0.1)
		(layer "F.Cu")
		(net 23)
	)
	(segment
		(start 190.150529 95.42645)
		(end 190.162442 95.40749)
		(width 0.1)
		(layer "F.Cu")
		(net 23)
	)
	(segment
		(start 190.143133 95.447586)
		(end 190.150529 95.42645)
		(width 0.1)
		(layer "F.Cu")
		(net 23)
	)
	(segment
		(start 190.943133 95.447586)
		(end 190.950529 95.42645)
		(width 0.1)
		(layer "F.Cu")
		(net 23)
	)
	(segment
		(start 184.663477 99.497157)
		(end 188.386328 95.774306)
		(width 0.1)
		(layer "F.Cu")
		(net 23)
	)
	(segment
		(start 189.884014 95.784209)
		(end 189.902974 95.796122)
		(width 0.1)
		(layer "F.Cu")
		(net 23)
	)
	(segment
		(start 191.102974 95.391655)
		(end 191.118809 95.40749)
		(width 0.1)
		(layer "F.Cu")
		(net 23)
	)
	(segment
		(start 190.262878 95.372346)
		(end 190.284014 95.379742)
		(width 0.1)
		(layer "F.Cu")
		(net 23)
	)
	(segment
		(start 190.140626 95.878774)
		(end 190.140626 95.469838)
		(width 0.1)
		(layer "F.Cu")
		(net 23)
	)
	(segment
		(start 191.140626 95.674306)
		(end 191.143133 95.696559)
		(width 0.1)
		(layer "F.Cu")
		(net 23)
	)
	(segment
		(start 189.940626 95.874306)
		(end 189.940626 95.878774)
		(width 0.1)
		(layer "F.Cu")
		(net 23)
	)
	(segment
		(start 190.140626 95.469838)
		(end 190.143133 95.447586)
		(width 0.1)
		(layer "F.Cu")
		(net 23)
	)
	(segment
		(start 191.143133 95.696559)
		(end 191.150529 95.717695)
		(width 0.1)
		(layer "F.Cu")
		(net 23)
	)
	(segment
		(start 189.930722 95.830917)
		(end 189.938118 95.852053)
		(width 0.1)
		(layer "F.Cu")
		(net 23)
	)
	(segment
		(start 190.750529 95.922162)
		(end 190.762442 95.941122)
		(width 0.1)
		(layer "F.Cu")
		(net 23)
	)
	(segment
		(start 190.018373 95.976266)
		(end 190.040626 95.978774)
		(width 0.1)
		(layer "F.Cu")
		(net 23)
	)
	(segment
		(start 190.418373 95.976266)
		(end 190.440626 95.978774)
		(width 0.1)
		(layer "F.Cu")
		(net 23)
	)
	(segment
		(start 190.062878 95.976266)
		(end 190.084014 95.96887)
		(width 0.1)
		(layer "F.Cu")
		(net 23)
	)
	(segment
		(start 190.540626 95.469838)
		(end 190.543133 95.447586)
		(width 0.1)
		(layer "F.Cu")
		(net 23)
	)
	(segment
		(start 190.362442 95.941122)
		(end 190.378277 95.956957)
		(width 0.1)
		(layer "F.Cu")
		(net 23)
	)
	(segment
		(start 190.778277 95.956957)
		(end 190.797237 95.96887)
		(width 0.1)
		(layer "F.Cu")
		(net 23)
	)
	(segment
		(start 191.140626 95.469838)
		(end 191.140626 95.674306)
		(width 0.1)
		(layer "F.Cu")
		(net 23)
	)
	(segment
		(start 190.102974 95.956957)
		(end 190.118809 95.941122)
		(width 0.1)
		(layer "F.Cu")
		(net 23)
	)
	(segment
		(start 190.740626 95.469838)
		(end 190.740626 95.878774)
		(width 0.1)
		(layer "F.Cu")
		(net 23)
	)
	(segment
		(start 190.302974 95.391655)
		(end 190.318809 95.40749)
		(width 0.1)
		(layer "F.Cu")
		(net 23)
	)
	(segment
		(start 190.940626 95.469838)
		(end 190.943133 95.447586)
		(width 0.1)
		(layer "F.Cu")
		(net 23)
	)
	(segment
		(start 190.702974 95.391655)
		(end 190.718809 95.40749)
		(width 0.1)
		(layer "F.Cu")
		(net 23)
	)
	(segment
		(start 190.550529 95.42645)
		(end 190.562442 95.40749)
		(width 0.1)
		(layer "F.Cu")
		(net 23)
	)
	(segment
		(start 191.162442 95.736655)
		(end 191.178277 95.75249)
		(width 0.1)
		(layer "F.Cu")
		(net 23)
	)
	(segment
		(start 189.902974 95.796122)
		(end 189.918809 95.811957)
		(width 0.1)
		(layer "F.Cu")
		(net 23)
	)
	(segment
		(start 190.284014 95.379742)
		(end 190.302974 95.391655)
		(width 0.1)
		(layer "F.Cu")
		(net 23)
	)
	(segment
		(start 189.918809 95.811957)
		(end 189.930722 95.830917)
		(width 0.1)
		(layer "F.Cu")
		(net 23)
	)
	(segment
		(start 190.502974 95.956957)
		(end 190.518809 95.941122)
		(width 0.1)
		(layer "F.Cu")
		(net 23)
	)
	(segment
		(start 191.218373 95.771799)
		(end 191.240626 95.774306)
		(width 0.1)
		(layer "F.Cu")
		(net 23)
	)
	(segment
		(start 188.386328 95.774306)
		(end 189.840626 95.774306)
		(width 0.1)
		(layer "F.Cu")
		(net 23)
	)
	(segment
		(start 190.162442 95.40749)
		(end 190.178277 95.391655)
		(width 0.1)
		(layer "F.Cu")
		(net 23)
	)
	(segment
		(start 190.762442 95.941122)
		(end 190.778277 95.956957)
		(width 0.1)
		(layer "F.Cu")
		(net 23)
	)
	(segment
		(start 191.084014 95.379742)
		(end 191.102974 95.391655)
		(width 0.1)
		(layer "F.Cu")
		(net 23)
	)
	(segment
		(start 200.186328 96.774306)
		(end 200.186328 99.620008)
		(width 0.1)
		(layer "F.Cu")
		(net 23)
	)
	(segment
		(start 189.940626 95.878774)
		(end 189.943133 95.901026)
		(width 0.1)
		(layer "F.Cu")
		(net 23)
	)
	(segment
		(start 190.597237 95.379742)
		(end 190.618373 95.372346)
		(width 0.1)
		(layer "F.Cu")
		(net 23)
	)
	(segment
		(start 191.197237 95.764403)
		(end 191.218373 95.771799)
		(width 0.1)
		(layer "F.Cu")
		(net 23)
	)
	(segment
		(start 189.938118 95.852053)
		(end 189.940626 95.874306)
		(width 0.1)
		(layer "F.Cu")
		(net 23)
	)
	(segment
		(start 190.940626 95.878774)
		(end 190.940626 95.469838)
		(width 0.1)
		(layer "F.Cu")
		(net 23)
	)
	(segment
		(start 191.150529 95.717695)
		(end 191.162442 95.736655)
		(width 0.1)
		(layer "F.Cu")
		(net 23)
	)
	(segment
		(start 191.240626 95.774306)
		(end 191.294924 95.720008)
		(width 0.1)
		(layer "F.Cu")
		(net 23)
	)
	(segment
		(start 191.130722 95.42645)
		(end 191.138118 95.447586)
		(width 0.1)
		(layer "F.Cu")
		(net 23)
	)
	(segment
		(start 190.530722 95.922162)
		(end 190.538118 95.901026)
		(width 0.1)
		(layer "F.Cu")
		(net 23)
	)
	(segment
		(start 189.950529 95.922162)
		(end 189.962442 95.941122)
		(width 0.1)
		(layer "F.Cu")
		(net 23)
	)
	(segment
		(start 190.462878 95.976266)
		(end 190.484014 95.96887)
		(width 0.1)
		(layer "F.Cu")
		(net 23)
	)
	(segment
		(start 190.640626 95.369838)
		(end 190.662878 95.372346)
		(width 0.1)
		(layer "F.Cu")
		(net 23)
	)
	(segment
		(start 189.862878 95.776813)
		(end 189.884014 95.784209)
		(width 0.1)
		(layer "F.Cu")
		(net 23)
	)
	(segment
		(start 189.962442 95.941122)
		(end 189.978277 95.956957)
		(width 0.1)
		(layer "F.Cu")
		(net 23)
	)
	(segment
		(start 190.738118 95.447586)
		(end 190.740626 95.469838)
		(width 0.1)
		(layer "F.Cu")
		(net 23)
	)
	(segment
		(start 190.562442 95.40749)
		(end 190.578277 95.391655)
		(width 0.1)
		(layer "F.Cu")
		(net 23)
	)
	(segment
		(start 190.484014 95.96887)
		(end 190.502974 95.956957)
		(width 0.1)
		(layer "F.Cu")
		(net 23)
	)
	(segment
		(start 190.662878 95.372346)
		(end 190.684014 95.379742)
		(width 0.1)
		(layer "F.Cu")
		(net 23)
	)
	(segment
		(start 190.618373 95.372346)
		(end 190.640626 95.369838)
		(width 0.1)
		(layer "F.Cu")
		(net 23)
	)
	(segment
		(start 190.040626 95.978774)
		(end 190.062878 95.976266)
		(width 0.1)
		(layer "F.Cu")
		(net 23)
	)
	(segment
		(start 190.343133 95.901026)
		(end 190.350529 95.922162)
		(width 0.1)
		(layer "F.Cu")
		(net 23)
	)
	(segment
		(start 190.538118 95.901026)
		(end 190.540626 95.878774)
		(width 0.1)
		(layer "F.Cu")
		(net 23)
	)
	(segment
		(start 190.902974 95.956957)
		(end 190.918809 95.941122)
		(width 0.1)
		(layer "F.Cu")
		(net 23)
	)
	(segment
		(start 190.330722 95.42645)
		(end 190.338118 95.447586)
		(width 0.1)
		(layer "F.Cu")
		(net 23)
	)
	(segment
		(start 189.978277 95.956957)
		(end 189.997237 95.96887)
		(width 0.1)
		(layer "F.Cu")
		(net 23)
	)
	(segment
		(start 190.397237 95.96887)
		(end 190.418373 95.976266)
		(width 0.1)
		(layer "F.Cu")
		(net 23)
	)
	(segment
		(start 191.138118 95.447586)
		(end 191.140626 95.469838)
		(width 0.1)
		(layer "F.Cu")
		(net 23)
	)
	(via
		(at 196.686328 95.720008)
		(size 0.5)
		(drill 0.2)
		(layers "F.Cu" "B.Cu")
		(net 23)
	)
	(segment
		(start 196.686328 95.005008)
		(end 196.686328 95.720008)
		(width 0.2)
		(layer "B.Cu")
		(net 23)
	)
	(segment
		(start 196.686328 96.275008)
		(end 196.686328 95.720008)
		(width 0.2)
		(layer "B.Cu")
		(net 23)
	)
	(segment
		(start 175.536329 100.497156)
		(end 176.036329 100.997156)
		(width 0.15)
		(layer "F.Cu")
		(net 24)
	)
	(segment
		(start 197.009179 102.797157)
		(end 195.709179 102.797157)
		(width 0.1)
		(layer "F.Cu")
		(net 24)
	)
	(segment
		(start 195.709179 102.797157)
		(end 195.686328 102.774306)
		(width 0.1)
		(layer "F.Cu")
		(net 24)
	)
	(via blind
		(at 176.036329 100.997156)
		(size 0.5)
		(drill 0.2)
		(layers "F.Cu" "In2.Cu")
		(net 24)
	)
	(via
		(at 195.686328 102.774306)
		(size 0.5)
		(drill 0.2)
		(layers "F.Cu" "B.Cu")
		(net 24)
	)
	(segment
		(start 196.401328 103.320008)
		(end 196.23203 103.320008)
		(width 0.2)
		(layer "B.Cu")
		(net 24)
	)
	(segment
		(start 196.23203 103.320008)
		(end 195.686328 102.774306)
		(width 0.2)
		(layer "B.Cu")
		(net 24)
	)
	(segment
		(start 185.713477 102.774306)
		(end 183.936328 100.997157)
		(width 0.1)
		(layer "In2.Cu")
		(net 24)
	)
	(segment
		(start 183.936328 100.997157)
		(end 176.03633 100.997157)
		(width 0.1)
		(layer "In2.Cu")
		(net 24)
	)
	(segment
		(start 176.03633 100.997157)
		(end 176.036329 100.997156)
		(width 0.1)
		(layer "In2.Cu")
		(net 24)
	)
	(segment
		(start 195.686328 102.774306)
		(end 185.713477 102.774306)
		(width 0.1)
		(layer "In2.Cu")
		(net 24)
	)
	(segment
		(start 177.536329 98.497156)
		(end 178.036329 98.997156)
		(width 0.15)
		(layer "F.Cu")
		(net 25)
	)
	(segment
		(start 195.409179 100.297157)
		(end 195.386328 100.274306)
		(width 0.1)
		(layer "F.Cu")
		(net 25)
	)
	(segment
		(start 197.009179 100.297157)
		(end 195.409179 100.297157)
		(width 0.1)
		(layer "F.Cu")
		(net 25)
	)
	(via blind
		(at 178.036329 98.997156)
		(size 0.5)
		(drill 0.2)
		(layers "F.Cu" "In2.Cu")
		(net 25)
	)
	(via
		(at 195.386328 100.274306)
		(size 0.5)
		(drill 0.2)
		(layers "F.Cu" "B.Cu")
		(net 25)
	)
	(segment
		(start 195.386328 100.020008)
		(end 195.386328 100.274306)
		(width 0.2)
		(layer "B.Cu")
		(net 25)
	)
	(segment
		(start 195.401328 100.005008)
		(end 195.386328 100.020008)
		(width 0.2)
		(layer "B.Cu")
		(net 25)
	)
	(segment
		(start 195.401328 99.520008)
		(end 195.401328 100.005008)
		(width 0.2)
		(layer "B.Cu")
		(net 25)
	)
	(segment
		(start 186.813477 98.974306)
		(end 178.059179 98.974306)
		(width 0.1)
		(layer "In2.Cu")
		(net 25)
	)
	(segment
		(start 178.059179 98.974306)
		(end 178.036329 98.997156)
		(width 0.1)
		(layer "In2.Cu")
		(net 25)
	)
	(segment
		(start 195.386328 100.274306)
		(end 188.113477 100.274306)
		(width 0.1)
		(layer "In2.Cu")
		(net 25)
	)
	(segment
		(start 188.113477 100.274306)
		(end 186.813477 98.974306)
		(width 0.1)
		(layer "In2.Cu")
		(net 25)
	)
	(segment
		(start 177.536329 96.497158)
		(end 177.036329 96.997158)
		(width 0.15)
		(layer "F.Cu")
		(net 26)
	)
	(segment
		(start 197.686328 102.274306)
		(end 197.886328 102.274306)
		(width 0.1)
		(layer "F.Cu")
		(net 26)
	)
	(segment
		(start 197.663477 102.297157)
		(end 197.686328 102.274306)
		(width 0.1)
		(layer "F.Cu")
		(net 26)
	)
	(segment
		(start 197.009179 102.297157)
		(end 197.663477 102.297157)
		(width 0.1)
		(layer "F.Cu")
		(net 26)
	)
	(via blind
		(at 177.036329 96.997158)
		(size 0.5)
		(drill 0.2)
		(layers "F.Cu" "In2.Cu")
		(net 26)
	)
	(via
		(at 197.886328 102.274306)
		(size 0.5)
		(drill 0.2)
		(layers "F.Cu" "B.Cu")
		(net 26)
	)
	(segment
		(start 197.886328 102.274306)
		(end 197.886328 101.665008)
		(width 0.2)
		(layer "B.Cu")
		(net 26)
	)
	(segment
		(start 198.386328 102.910008)
		(end 198.386328 102.774306)
		(width 0.2)
		(layer "B.Cu")
		(net 26)
	)
	(segment
		(start 198.386328 102.774306)
		(end 197.886328 102.274306)
		(width 0.2)
		(layer "B.Cu")
		(net 26)
	)
	(segment
		(start 197.886328 101.665008)
		(end 197.891328 101.660008)
		(width 0.2)
		(layer "B.Cu")
		(net 26)
	)
	(segment
		(start 176.386328 97.647159)
		(end 177.036329 96.997158)
		(width 0.1)
		(layer "In2.Cu")
		(net 26)
	)
	(segment
		(start 186.049902 101.474306)
		(end 185.249902 100.674306)
		(width 0.1)
		(layer "In2.Cu")
		(net 26)
	)
	(segment
		(start 176.940626 100.674306)
		(end 176.386328 100.120008)
		(width 0.1)
		(layer "In2.Cu")
		(net 26)
	)
	(segment
		(start 185.249902 100.674306)
		(end 176.940626 100.674306)
		(width 0.1)
		(layer "In2.Cu")
		(net 26)
	)
	(segment
		(start 197.886328 102.274306)
		(end 197.086328 101.474306)
		(width 0.1)
		(layer "In2.Cu")
		(net 26)
	)
	(segment
		(start 176.386328 100.120008)
		(end 176.386328 97.647159)
		(width 0.1)
		(layer "In2.Cu")
		(net 26)
	)
	(segment
		(start 197.086328 101.474306)
		(end 186.049902 101.474306)
		(width 0.1)
		(layer "In2.Cu")
		(net 26)
	)
	(segment
		(start 178.536327 104.497156)
		(end 179.036327 103.997156)
		(width 0.15)
		(layer "F.Cu")
		(net 27)
	)
	(segment
		(start 205.363477 102.297157)
		(end 205.386328 102.274306)
		(width 0.15)
		(layer "F.Cu")
		(net 27)
	)
	(segment
		(start 203.863477 102.297157)
		(end 205.363477 102.297157)
		(width 0.15)
		(layer "F.Cu")
		(net 27)
	)
	(via blind
		(at 179.036327 103.997156)
		(size 0.5)
		(drill 0.2)
		(layers "F.Cu" "In2.Cu")
		(net 27)
	)
	(via
		(at 205.386328 102.274306)
		(size 0.5)
		(drill 0.2)
		(layers "F.Cu" "B.Cu")
		(net 27)
	)
	(segment
		(start 197.475418 105.58421)
		(end 197.454282 105.576814)
		(width 0.1)
		(layer "In2.Cu")
		(net 27)
	)
	(segment
		(start 201.286328 105.574306)
		(end 198.43203 105.574306)
		(width 0.1)
		(layer "In2.Cu")
		(net 27)
	)
	(segment
		(start 197.969681 105.999813)
		(end 197.953846 105.983978)
		(width 0.1)
		(layer "In2.Cu")
		(net 27)
	)
	(segment
		(start 197.553846 105.983978)
		(end 197.541933 105.965018)
		(width 0.1)
		(layer "In2.Cu")
		(net 27)
	)
	(segment
		(start 197.53203 105.674306)
		(end 197.529522 105.652054)
		(width 0.1)
		(layer "In2.Cu")
		(net 27)
	)
	(segment
		(start 203.486328 102.274306)
		(end 202.986328 102.774306)
		(width 0.1)
		(layer "In2.Cu")
		(net 27)
	)
	(segment
		(start 197.53203 105.921629)
		(end 197.53203 105.674306)
		(width 0.1)
		(layer "In2.Cu")
		(net 27)
	)
	(segment
		(start 197.675418 106.011726)
		(end 197.654282 106.019122)
		(width 0.1)
		(layer "In2.Cu")
		(net 27)
	)
	(segment
		(start 198.122126 105.965018)
		(end 198.110213 105.983978)
		(width 0.1)
		(layer "In2.Cu")
		(net 27)
	)
	(segment
		(start 197.73203 105.326983)
		(end 197.73203 105.921629)
		(width 0.1)
		(layer "In2.Cu")
		(net 27)
	)
	(segment
		(start 198.341933 105.517694)
		(end 198.334537 105.496558)
		(width 0.1)
		(layer "In2.Cu")
		(net 27)
	)
	(segment
		(start 197.854282 105.22949)
		(end 197.83203 105.226983)
		(width 0.1)
		(layer "In2.Cu")
		(net 27)
	)
	(segment
		(start 197.609777 106.019122)
		(end 197.588641 106.011726)
		(width 0.1)
		(layer "In2.Cu")
		(net 27)
	)
	(segment
		(start 197.93203 105.921629)
		(end 197.93203 105.326983)
		(width 0.1)
		(layer "In2.Cu")
		(net 27)
	)
	(segment
		(start 180.436327 103.997156)
		(end 179.036327 103.997156)
		(width 0.1)
		(layer "In2.Cu")
		(net 27)
	)
	(segment
		(start 197.93203 105.326983)
		(end 197.929522 105.30473)
		(width 0.1)
		(layer "In2.Cu")
		(net 27)
	)
	(segment
		(start 197.729522 105.943882)
		(end 197.722126 105.965018)
		(width 0.1)
		(layer "In2.Cu")
		(net 27)
	)
	(segment
		(start 198.129522 105.943882)
		(end 198.122126 105.965018)
		(width 0.1)
		(layer "In2.Cu")
		(net 27)
	)
	(segment
		(start 198.054282 106.019122)
		(end 198.03203 106.021629)
		(width 0.1)
		(layer "In2.Cu")
		(net 27)
	)
	(segment
		(start 197.569681 105.999813)
		(end 197.553846 105.983978)
		(width 0.1)
		(layer "In2.Cu")
		(net 27)
	)
	(segment
		(start 198.009777 106.019122)
		(end 197.988641 106.011726)
		(width 0.1)
		(layer "In2.Cu")
		(net 27)
	)
	(segment
		(start 197.454282 105.576814)
		(end 197.43203 105.574306)
		(width 0.1)
		(layer "In2.Cu")
		(net 27)
	)
	(segment
		(start 198.153846 105.264634)
		(end 198.141933 105.283594)
		(width 0.1)
		(layer "In2.Cu")
		(net 27)
	)
	(segment
		(start 197.541933 105.965018)
		(end 197.534537 105.943882)
		(width 0.1)
		(layer "In2.Cu")
		(net 27)
	)
	(segment
		(start 198.294378 105.248799)
		(end 198.275418 105.236886)
		(width 0.1)
		(layer "In2.Cu")
		(net 27)
	)
	(segment
		(start 198.369681 105.552489)
		(end 198.353846 105.536654)
		(width 0.1)
		(layer "In2.Cu")
		(net 27)
	)
	(segment
		(start 198.188641 105.236886)
		(end 198.169681 105.248799)
		(width 0.1)
		(layer "In2.Cu")
		(net 27)
	)
	(segment
		(start 197.769681 105.248799)
		(end 197.753846 105.264634)
		(width 0.1)
		(layer "In2.Cu")
		(net 27)
	)
	(segment
		(start 198.353846 105.536654)
		(end 198.341933 105.517694)
		(width 0.1)
		(layer "In2.Cu")
		(net 27)
	)
	(segment
		(start 197.63203 106.021629)
		(end 197.609777 106.019122)
		(width 0.1)
		(layer "In2.Cu")
		(net 27)
	)
	(segment
		(start 197.741933 105.283594)
		(end 197.734537 105.30473)
		(width 0.1)
		(layer "In2.Cu")
		(net 27)
	)
	(segment
		(start 198.254282 105.22949)
		(end 198.23203 105.226983)
		(width 0.1)
		(layer "In2.Cu")
		(net 27)
	)
	(segment
		(start 197.929522 105.30473)
		(end 197.922126 105.283594)
		(width 0.1)
		(layer "In2.Cu")
		(net 27)
	)
	(segment
		(start 198.13203 105.921629)
		(end 198.129522 105.943882)
		(width 0.1)
		(layer "In2.Cu")
		(net 27)
	)
	(segment
		(start 198.33203 105.474306)
		(end 198.33203 105.326983)
		(width 0.1)
		(layer "In2.Cu")
		(net 27)
	)
	(segment
		(start 197.934537 105.943882)
		(end 197.93203 105.921629)
		(width 0.1)
		(layer "In2.Cu")
		(net 27)
	)
	(segment
		(start 197.694378 105.999813)
		(end 197.675418 106.011726)
		(width 0.1)
		(layer "In2.Cu")
		(net 27)
	)
	(segment
		(start 197.988641 106.011726)
		(end 197.969681 105.999813)
		(width 0.1)
		(layer "In2.Cu")
		(net 27)
	)
	(segment
		(start 197.875418 105.236886)
		(end 197.854282 105.22949)
		(width 0.1)
		(layer "In2.Cu")
		(net 27)
	)
	(segment
		(start 198.03203 106.021629)
		(end 198.009777 106.019122)
		(width 0.1)
		(layer "In2.Cu")
		(net 27)
	)
	(segment
		(start 197.534537 105.943882)
		(end 197.53203 105.921629)
		(width 0.1)
		(layer "In2.Cu")
		(net 27)
	)
	(segment
		(start 198.275418 105.236886)
		(end 198.254282 105.22949)
		(width 0.1)
		(layer "In2.Cu")
		(net 27)
	)
	(segment
		(start 198.33203 105.326983)
		(end 198.329522 105.30473)
		(width 0.1)
		(layer "In2.Cu")
		(net 27)
	)
	(segment
		(start 197.510213 105.611958)
		(end 197.494378 105.596123)
		(width 0.1)
		(layer "In2.Cu")
		(net 27)
	)
	(segment
		(start 197.809777 105.22949)
		(end 197.788641 105.236886)
		(width 0.1)
		(layer "In2.Cu")
		(net 27)
	)
	(segment
		(start 197.910213 105.264634)
		(end 197.894378 105.248799)
		(width 0.1)
		(layer "In2.Cu")
		(net 27)
	)
	(segment
		(start 197.654282 106.019122)
		(end 197.63203 106.021629)
		(width 0.1)
		(layer "In2.Cu")
		(net 27)
	)
	(segment
		(start 197.494378 105.596123)
		(end 197.475418 105.58421)
		(width 0.1)
		(layer "In2.Cu")
		(net 27)
	)
	(segment
		(start 198.169681 105.248799)
		(end 198.153846 105.264634)
		(width 0.1)
		(layer "In2.Cu")
		(net 27)
	)
	(segment
		(start 197.734537 105.30473)
		(end 197.73203 105.326983)
		(width 0.1)
		(layer "In2.Cu")
		(net 27)
	)
	(segment
		(start 197.788641 105.236886)
		(end 197.769681 105.248799)
		(width 0.1)
		(layer "In2.Cu")
		(net 27)
	)
	(segment
		(start 202.986328 103.874306)
		(end 201.286328 105.574306)
		(width 0.1)
		(layer "In2.Cu")
		(net 27)
	)
	(segment
		(start 197.753846 105.264634)
		(end 197.741933 105.283594)
		(width 0.1)
		(layer "In2.Cu")
		(net 27)
	)
	(segment
		(start 198.075418 106.011726)
		(end 198.054282 106.019122)
		(width 0.1)
		(layer "In2.Cu")
		(net 27)
	)
	(segment
		(start 198.388641 105.564402)
		(end 198.369681 105.552489)
		(width 0.1)
		(layer "In2.Cu")
		(net 27)
	)
	(segment
		(start 198.134537 105.30473)
		(end 198.13203 105.326983)
		(width 0.1)
		(layer "In2.Cu")
		(net 27)
	)
	(segment
		(start 197.43203 105.574306)
		(end 182.013477 105.574306)
		(width 0.1)
		(layer "In2.Cu")
		(net 27)
	)
	(segment
		(start 197.73203 105.921629)
		(end 197.729522 105.943882)
		(width 0.1)
		(layer "In2.Cu")
		(net 27)
	)
	(segment
		(start 205.386328 102.274306)
		(end 203.486328 102.274306)
		(width 0.1)
		(layer "In2.Cu")
		(net 27)
	)
	(segment
		(start 197.941933 105.965018)
		(end 197.934537 105.943882)
		(width 0.1)
		(layer "In2.Cu")
		(net 27)
	)
	(segment
		(start 198.13203 105.326983)
		(end 198.13203 105.921629)
		(width 0.1)
		(layer "In2.Cu")
		(net 27)
	)
	(segment
		(start 197.894378 105.248799)
		(end 197.875418 105.236886)
		(width 0.1)
		(layer "In2.Cu")
		(net 27)
	)
	(segment
		(start 197.710213 105.983978)
		(end 197.694378 105.999813)
		(width 0.1)
		(layer "In2.Cu")
		(net 27)
	)
	(segment
		(start 197.588641 106.011726)
		(end 197.569681 105.999813)
		(width 0.1)
		(layer "In2.Cu")
		(net 27)
	)
	(segment
		(start 197.529522 105.652054)
		(end 197.522126 105.630918)
		(width 0.1)
		(layer "In2.Cu")
		(net 27)
	)
	(segment
		(start 202.986328 102.774306)
		(end 202.986328 103.874306)
		(width 0.1)
		(layer "In2.Cu")
		(net 27)
	)
	(segment
		(start 198.310213 105.264634)
		(end 198.294378 105.248799)
		(width 0.1)
		(layer "In2.Cu")
		(net 27)
	)
	(segment
		(start 182.013477 105.574306)
		(end 180.436327 103.997156)
		(width 0.1)
		(layer "In2.Cu")
		(net 27)
	)
	(segment
		(start 197.522126 105.630918)
		(end 197.510213 105.611958)
		(width 0.1)
		(layer "In2.Cu")
		(net 27)
	)
	(segment
		(start 198.110213 105.983978)
		(end 198.094378 105.999813)
		(width 0.1)
		(layer "In2.Cu")
		(net 27)
	)
	(segment
		(start 197.922126 105.283594)
		(end 197.910213 105.264634)
		(width 0.1)
		(layer "In2.Cu")
		(net 27)
	)
	(segment
		(start 198.334537 105.496558)
		(end 198.33203 105.474306)
		(width 0.1)
		(layer "In2.Cu")
		(net 27)
	)
	(segment
		(start 197.953846 105.983978)
		(end 197.941933 105.965018)
		(width 0.1)
		(layer "In2.Cu")
		(net 27)
	)
	(segment
		(start 198.209777 105.22949)
		(end 198.188641 105.236886)
		(width 0.1)
		(layer "In2.Cu")
		(net 27)
	)
	(segment
		(start 198.094378 105.999813)
		(end 198.075418 106.011726)
		(width 0.1)
		(layer "In2.Cu")
		(net 27)
	)
	(segment
		(start 198.322126 105.283594)
		(end 198.310213 105.264634)
		(width 0.1)
		(layer "In2.Cu")
		(net 27)
	)
	(segment
		(start 198.43203 105.574306)
		(end 198.409777 105.571798)
		(width 0.1)
		(layer "In2.Cu")
		(net 27)
	)
	(segment
		(start 198.329522 105.30473)
		(end 198.322126 105.283594)
		(width 0.1)
		(layer "In2.Cu")
		(net 27)
	)
	(segment
		(start 198.23203 105.226983)
		(end 198.209777 105.22949)
		(width 0.1)
		(layer "In2.Cu")
		(net 27)
	)
	(segment
		(start 197.722126 105.965018)
		(end 197.710213 105.983978)
		(width 0.1)
		(layer "In2.Cu")
		(net 27)
	)
	(segment
		(start 198.141933 105.283594)
		(end 198.134537 105.30473)
		(width 0.1)
		(layer "In2.Cu")
		(net 27)
	)
	(segment
		(start 197.83203 105.226983)
		(end 197.809777 105.22949)
		(width 0.1)
		(layer "In2.Cu")
		(net 27)
	)
	(segment
		(start 198.409777 105.571798)
		(end 198.388641 105.564402)
		(width 0.1)
		(layer "In2.Cu")
		(net 27)
	)
	(segment
		(start 179.536328 103.497157)
		(end 181.163477 103.497157)
		(width 0.1)
		(layer "F.Cu")
		(net 28)
	)
	(segment
		(start 204.863477 101.797157)
		(end 204.886328 101.774306)
		(width 0.15)
		(layer "F.Cu")
		(net 28)
	)
	(segment
		(start 181.163477 103.497157)
		(end 181.186328 103.474306)
		(width 0.1)
		(layer "F.Cu")
		(net 28)
	)
	(segment
		(start 203.863477 101.797157)
		(end 204.863477 101.797157)
		(width 0.15)
		(layer "F.Cu")
		(net 28)
	)
	(via blind
		(at 181.186328 103.474306)
		(size 0.5)
		(drill 0.2)
		(layers "F.Cu" "In2.Cu")
		(net 28)
	)
	(via
		(at 204.886328 101.774306)
		(size 0.5)
		(drill 0.2)
		(layers "F.Cu" "B.Cu")
		(net 28)
	)
	(segment
		(start 189.318809 105.284856)
		(end 189.330722 105.265896)
		(width 0.1)
		(layer "In2.Cu")
		(net 28)
	)
	(segment
		(start 189.162442 105.284856)
		(end 189.178277 105.300691)
		(width 0.1)
		(layer "In2.Cu")
		(net 28)
	)
	(segment
		(start 188.538118 105.24476)
		(end 188.540626 105.222508)
		(width 0.1)
		(layer "In2.Cu")
		(net 28)
	)
	(segment
		(start 189.378277 104.996122)
		(end 189.397237 104.984209)
		(width 0.1)
		(layer "In2.Cu")
		(net 28)
	)
	(segment
		(start 188.818373 105.32)
		(end 188.840626 105.322508)
		(width 0.1)
		(layer "In2.Cu")
		(net 28)
	)
	(segment
		(start 188.397237 105.312604)
		(end 188.418373 105.32)
		(width 0.1)
		(layer "In2.Cu")
		(net 28)
	)
	(segment
		(start 189.218373 105.32)
		(end 189.240626 105.322508)
		(width 0.1)
		(layer "In2.Cu")
		(net 28)
	)
	(segment
		(start 188.130722 105.265896)
		(end 188.138118 105.24476)
		(width 0.1)
		(layer "In2.Cu")
		(net 28)
	)
	(segment
		(start 188.330722 104.582716)
		(end 188.338118 104.603852)
		(width 0.1)
		(layer "In2.Cu")
		(net 28)
	)
	(segment
		(start 188.730722 104.582716)
		(end 188.738118 104.603852)
		(width 0.1)
		(layer "In2.Cu")
		(net 28)
	)
	(segment
		(start 188.862878 105.32)
		(end 188.884014 105.312604)
		(width 0.1)
		(layer "In2.Cu")
		(net 28)
	)
	(segment
		(start 187.943133 105.24476)
		(end 187.950529 105.265896)
		(width 0.1)
		(layer "In2.Cu")
		(net 28)
	)
	(segment
		(start 188.740626 104.626104)
		(end 188.740626 105.222508)
		(width 0.1)
		(layer "In2.Cu")
		(net 28)
	)
	(segment
		(start 187.950529 105.265896)
		(end 187.962442 105.284856)
		(width 0.1)
		(layer "In2.Cu")
		(net 28)
	)
	(segment
		(start 189.178277 105.300691)
		(end 189.197237 105.312604)
		(width 0.1)
		(layer "In2.Cu")
		(net 28)
	)
	(segment
		(start 188.684014 104.536008)
		(end 188.702974 104.547921)
		(width 0.1)
		(layer "In2.Cu")
		(net 28)
	)
	(segment
		(start 188.302974 104.547921)
		(end 188.318809 104.563756)
		(width 0.1)
		(layer "In2.Cu")
		(net 28)
	)
	(segment
		(start 188.918809 105.284856)
		(end 188.930722 105.265896)
		(width 0.1)
		(layer "In2.Cu")
		(net 28)
	)
	(segment
		(start 187.862878 104.976813)
		(end 187.884014 104.984209)
		(width 0.1)
		(layer "In2.Cu")
		(net 28)
	)
	(segment
		(start 188.550529 104.582716)
		(end 188.562442 104.563756)
		(width 0.1)
		(layer "In2.Cu")
		(net 28)
	)
	(segment
		(start 187.940626 105.074306)
		(end 187.940626 105.222508)
		(width 0.1)
		(layer "In2.Cu")
		(net 28)
	)
	(segment
		(start 189.362442 105.011957)
		(end 189.378277 104.996122)
		(width 0.1)
		(layer "In2.Cu")
		(net 28)
	)
	(segment
		(start 188.962442 104.563756)
		(end 188.978277 104.547921)
		(width 0.1)
		(layer "In2.Cu")
		(net 28)
	)
	(segment
		(start 188.618373 104.528612)
		(end 188.640626 104.526104)
		(width 0.1)
		(layer "In2.Cu")
		(net 28)
	)
	(segment
		(start 187.997237 105.312604)
		(end 188.018373 105.32)
		(width 0.1)
		(layer "In2.Cu")
		(net 28)
	)
	(segment
		(start 188.218373 104.528612)
		(end 188.240626 104.526104)
		(width 0.1)
		(layer "In2.Cu")
		(net 28)
	)
	(segment
		(start 188.318809 104.563756)
		(end 188.330722 104.582716)
		(width 0.1)
		(layer "In2.Cu")
		(net 28)
	)
	(segment
		(start 202.586328 102.274306)
		(end 203.086328 101.774306)
		(width 0.1)
		(layer "In2.Cu")
		(net 28)
	)
	(segment
		(start 188.350529 105.265896)
		(end 188.362442 105.284856)
		(width 0.1)
		(layer "In2.Cu")
		(net 28)
	)
	(segment
		(start 189.284014 105.312604)
		(end 189.302974 105.300691)
		(width 0.1)
		(layer "In2.Cu")
		(net 28)
	)
	(segment
		(start 188.978277 104.547921)
		(end 188.997237 104.536008)
		(width 0.1)
		(layer "In2.Cu")
		(net 28)
	)
	(segment
		(start 188.740626 105.222508)
		(end 188.743133 105.24476)
		(width 0.1)
		(layer "In2.Cu")
		(net 28)
	)
	(segment
		(start 189.262878 105.32)
		(end 189.284014 105.312604)
		(width 0.1)
		(layer "In2.Cu")
		(net 28)
	)
	(segment
		(start 202.586328 103.774306)
		(end 202.586328 102.274306)
		(width 0.1)
		(layer "In2.Cu")
		(net 28)
	)
	(segment
		(start 181.913477 103.474306)
		(end 183.413477 104.974306)
		(width 0.1)
		(layer "In2.Cu")
		(net 28)
	)
	(segment
		(start 189.418373 104.976813)
		(end 189.440626 104.974306)
		(width 0.1)
		(layer "In2.Cu")
		(net 28)
	)
	(segment
		(start 188.884014 105.312604)
		(end 188.902974 105.300691)
		(width 0.1)
		(layer "In2.Cu")
		(net 28)
	)
	(segment
		(start 188.518809 105.284856)
		(end 188.530722 105.265896)
		(width 0.1)
		(layer "In2.Cu")
		(net 28)
	)
	(segment
		(start 188.240626 104.526104)
		(end 188.262878 104.528612)
		(width 0.1)
		(layer "In2.Cu")
		(net 28)
	)
	(segment
		(start 188.340626 105.222508)
		(end 188.343133 105.24476)
		(width 0.1)
		(layer "In2.Cu")
		(net 28)
	)
	(segment
		(start 187.918809 105.011957)
		(end 187.930722 105.030917)
		(width 0.1)
		(layer "In2.Cu")
		(net 28)
	)
	(segment
		(start 188.102974 105.300691)
		(end 188.118809 105.284856)
		(width 0.1)
		(layer "In2.Cu")
		(net 28)
	)
	(segment
		(start 188.343133 105.24476)
		(end 188.350529 105.265896)
		(width 0.1)
		(layer "In2.Cu")
		(net 28)
	)
	(segment
		(start 183.413477 104.974306)
		(end 187.840626 104.974306)
		(width 0.1)
		(layer "In2.Cu")
		(net 28)
	)
	(segment
		(start 189.150529 105.265896)
		(end 189.162442 105.284856)
		(width 0.1)
		(layer "In2.Cu")
		(net 28)
	)
	(segment
		(start 188.743133 105.24476)
		(end 188.750529 105.265896)
		(width 0.1)
		(layer "In2.Cu")
		(net 28)
	)
	(segment
		(start 189.197237 105.312604)
		(end 189.218373 105.32)
		(width 0.1)
		(layer "In2.Cu")
		(net 28)
	)
	(segment
		(start 188.340626 104.626104)
		(end 188.340626 105.222508)
		(width 0.1)
		(layer "In2.Cu")
		(net 28)
	)
	(segment
		(start 188.484014 105.312604)
		(end 188.502974 105.300691)
		(width 0.1)
		(layer "In2.Cu")
		(net 28)
	)
	(segment
		(start 188.540626 104.626104)
		(end 188.543133 104.603852)
		(width 0.1)
		(layer "In2.Cu")
		(net 28)
	)
	(segment
		(start 189.140626 104.626104)
		(end 189.140626 105.222508)
		(width 0.1)
		(layer "In2.Cu")
		(net 28)
	)
	(segment
		(start 188.018373 105.32)
		(end 188.040626 105.322508)
		(width 0.1)
		(layer "In2.Cu")
		(net 28)
	)
	(segment
		(start 201.386328 104.974306)
		(end 202.586328 103.774306)
		(width 0.1)
		(layer "In2.Cu")
		(net 28)
	)
	(segment
		(start 188.797237 105.312604)
		(end 188.818373 105.32)
		(width 0.1)
		(layer "In2.Cu")
		(net 28)
	)
	(segment
		(start 203.086328 101.774306)
		(end 204.886328 101.774306)
		(width 0.1)
		(layer "In2.Cu")
		(net 28)
	)
	(segment
		(start 188.440626 105.322508)
		(end 188.462878 105.32)
		(width 0.1)
		(layer "In2.Cu")
		(net 28)
	)
	(segment
		(start 189.138118 104.603852)
		(end 189.140626 104.626104)
		(width 0.1)
		(layer "In2.Cu")
		(net 28)
	)
	(segment
		(start 188.762442 105.284856)
		(end 188.778277 105.300691)
		(width 0.1)
		(layer "In2.Cu")
		(net 28)
	)
	(segment
		(start 188.338118 104.603852)
		(end 188.340626 104.626104)
		(width 0.1)
		(layer "In2.Cu")
		(net 28)
	)
	(segment
		(start 188.040626 105.322508)
		(end 188.062878 105.32)
		(width 0.1)
		(layer "In2.Cu")
		(net 28)
	)
	(segment
		(start 188.162442 104.563756)
		(end 188.178277 104.547921)
		(width 0.1)
		(layer "In2.Cu")
		(net 28)
	)
	(segment
		(start 187.978277 105.300691)
		(end 187.997237 105.312604)
		(width 0.1)
		(layer "In2.Cu")
		(net 28)
	)
	(segment
		(start 187.938118 105.052053)
		(end 187.940626 105.074306)
		(width 0.1)
		(layer "In2.Cu")
		(net 28)
	)
	(segment
		(start 188.178277 104.547921)
		(end 188.197237 104.536008)
		(width 0.1)
		(layer "In2.Cu")
		(net 28)
	)
	(segment
		(start 187.840626 104.974306)
		(end 187.862878 104.976813)
		(width 0.1)
		(layer "In2.Cu")
		(net 28)
	)
	(segment
		(start 188.197237 104.536008)
		(end 188.218373 104.528612)
		(width 0.1)
		(layer "In2.Cu")
		(net 28)
	)
	(segment
		(start 189.440626 104.974306)
		(end 201.386328 104.974306)
		(width 0.1)
		(layer "In2.Cu")
		(net 28)
	)
	(segment
		(start 189.340626 105.074306)
		(end 189.343133 105.052053)
		(width 0.1)
		(layer "In2.Cu")
		(net 28)
	)
	(segment
		(start 188.662878 104.528612)
		(end 188.684014 104.536008)
		(width 0.1)
		(layer "In2.Cu")
		(net 28)
	)
	(segment
		(start 188.378277 105.300691)
		(end 188.397237 105.312604)
		(width 0.1)
		(layer "In2.Cu")
		(net 28)
	)
	(segment
		(start 189.018373 104.528612)
		(end 189.040626 104.526104)
		(width 0.1)
		(layer "In2.Cu")
		(net 28)
	)
	(segment
		(start 188.150529 104.582716)
		(end 188.162442 104.563756)
		(width 0.1)
		(layer "In2.Cu")
		(net 28)
	)
	(segment
		(start 189.350529 105.030917)
		(end 189.362442 105.011957)
		(width 0.1)
		(layer "In2.Cu")
		(net 28)
	)
	(segment
		(start 188.530722 105.265896)
		(end 188.538118 105.24476)
		(width 0.1)
		(layer "In2.Cu")
		(net 28)
	)
	(segment
		(start 189.343133 105.052053)
		(end 189.350529 105.030917)
		(width 0.1)
		(layer "In2.Cu")
		(net 28)
	)
	(segment
		(start 187.962442 105.284856)
		(end 187.978277 105.300691)
		(width 0.1)
		(layer "In2.Cu")
		(net 28)
	)
	(segment
		(start 188.138118 105.24476)
		(end 188.140626 105.222508)
		(width 0.1)
		(layer "In2.Cu")
		(net 28)
	)
	(segment
		(start 189.102974 104.547921)
		(end 189.118809 104.563756)
		(width 0.1)
		(layer "In2.Cu")
		(net 28)
	)
	(segment
		(start 188.084014 105.312604)
		(end 188.102974 105.300691)
		(width 0.1)
		(layer "In2.Cu")
		(net 28)
	)
	(segment
		(start 189.340626 105.222508)
		(end 189.340626 105.074306)
		(width 0.1)
		(layer "In2.Cu")
		(net 28)
	)
	(segment
		(start 189.062878 104.528612)
		(end 189.084014 104.536008)
		(width 0.1)
		(layer "In2.Cu")
		(net 28)
	)
	(segment
		(start 189.240626 105.322508)
		(end 189.262878 105.32)
		(width 0.1)
		(layer "In2.Cu")
		(net 28)
	)
	(segment
		(start 189.338118 105.24476)
		(end 189.340626 105.222508)
		(width 0.1)
		(layer "In2.Cu")
		(net 28)
	)
	(segment
		(start 181.186328 103.474306)
		(end 181.913477 103.474306)
		(width 0.1)
		(layer "In2.Cu")
		(net 28)
	)
	(segment
		(start 188.502974 105.300691)
		(end 188.518809 105.284856)
		(width 0.1)
		(layer "In2.Cu")
		(net 28)
	)
	(segment
		(start 188.418373 105.32)
		(end 188.440626 105.322508)
		(width 0.1)
		(layer "In2.Cu")
		(net 28)
	)
	(segment
		(start 189.040626 104.526104)
		(end 189.062878 104.528612)
		(width 0.1)
		(layer "In2.Cu")
		(net 28)
	)
	(segment
		(start 188.062878 105.32)
		(end 188.084014 105.312604)
		(width 0.1)
		(layer "In2.Cu")
		(net 28)
	)
	(segment
		(start 189.140626 105.222508)
		(end 189.143133 105.24476)
		(width 0.1)
		(layer "In2.Cu")
		(net 28)
	)
	(segment
		(start 188.738118 104.603852)
		(end 188.740626 104.626104)
		(width 0.1)
		(layer "In2.Cu")
		(net 28)
	)
	(segment
		(start 188.140626 105.222508)
		(end 188.140626 104.626104)
		(width 0.1)
		(layer "In2.Cu")
		(net 28)
	)
	(segment
		(start 188.540626 105.222508)
		(end 188.540626 104.626104)
		(width 0.1)
		(layer "In2.Cu")
		(net 28)
	)
	(segment
		(start 187.884014 104.984209)
		(end 187.902974 104.996122)
		(width 0.1)
		(layer "In2.Cu")
		(net 28)
	)
	(segment
		(start 187.930722 105.030917)
		(end 187.938118 105.052053)
		(width 0.1)
		(layer "In2.Cu")
		(net 28)
	)
	(segment
		(start 188.143133 104.603852)
		(end 188.150529 104.582716)
		(width 0.1)
		(layer "In2.Cu")
		(net 28)
	)
	(segment
		(start 189.084014 104.536008)
		(end 189.102974 104.547921)
		(width 0.1)
		(layer "In2.Cu")
		(net 28)
	)
	(segment
		(start 188.938118 105.24476)
		(end 188.940626 105.222508)
		(width 0.1)
		(layer "In2.Cu")
		(net 28)
	)
	(segment
		(start 189.118809 104.563756)
		(end 189.130722 104.582716)
		(width 0.1)
		(layer "In2.Cu")
		(net 28)
	)
	(segment
		(start 188.702974 104.547921)
		(end 188.718809 104.563756)
		(width 0.1)
		(layer "In2.Cu")
		(net 28)
	)
	(segment
		(start 187.902974 104.996122)
		(end 187.918809 105.011957)
		(width 0.1)
		(layer "In2.Cu")
		(net 28)
	)
	(segment
		(start 188.778277 105.300691)
		(end 188.797237 105.312604)
		(width 0.1)
		(layer "In2.Cu")
		(net 28)
	)
	(segment
		(start 188.940626 105.222508)
		(end 188.940626 104.626104)
		(width 0.1)
		(layer "In2.Cu")
		(net 28)
	)
	(segment
		(start 188.362442 105.284856)
		(end 188.378277 105.300691)
		(width 0.1)
		(layer "In2.Cu")
		(net 28)
	)
	(segment
		(start 188.597237 104.536008)
		(end 188.618373 104.528612)
		(width 0.1)
		(layer "In2.Cu")
		(net 28)
	)
	(segment
		(start 189.143133 105.24476)
		(end 189.150529 105.265896)
		(width 0.1)
		(layer "In2.Cu")
		(net 28)
	)
	(segment
		(start 188.140626 104.626104)
		(end 188.143133 104.603852)
		(width 0.1)
		(layer "In2.Cu")
		(net 28)
	)
	(segment
		(start 188.640626 104.526104)
		(end 188.662878 104.528612)
		(width 0.1)
		(layer "In2.Cu")
		(net 28)
	)
	(segment
		(start 188.950529 104.582716)
		(end 188.962442 104.563756)
		(width 0.1)
		(layer "In2.Cu")
		(net 28)
	)
	(segment
		(start 189.130722 104.582716)
		(end 189.138118 104.603852)
		(width 0.1)
		(layer "In2.Cu")
		(net 28)
	)
	(segment
		(start 188.262878 104.528612)
		(end 188.284014 104.536008)
		(width 0.1)
		(layer "In2.Cu")
		(net 28)
	)
	(segment
		(start 188.940626 104.626104)
		(end 188.943133 104.603852)
		(width 0.1)
		(layer "In2.Cu")
		(net 28)
	)
	(segment
		(start 188.284014 104.536008)
		(end 188.302974 104.547921)
		(width 0.1)
		(layer "In2.Cu")
		(net 28)
	)
	(segment
		(start 188.997237 104.536008)
		(end 189.018373 104.528612)
		(width 0.1)
		(layer "In2.Cu")
		(net 28)
	)
	(segment
		(start 189.302974 105.300691)
		(end 189.318809 105.284856)
		(width 0.1)
		(layer "In2.Cu")
		(net 28)
	)
	(segment
		(start 188.750529 105.265896)
		(end 188.762442 105.284856)
		(width 0.1)
		(layer "In2.Cu")
		(net 28)
	)
	(segment
		(start 188.902974 105.300691)
		(end 188.918809 105.284856)
		(width 0.1)
		(layer "In2.Cu")
		(net 28)
	)
	(segment
		(start 188.543133 104.603852)
		(end 188.550529 104.582716)
		(width 0.1)
		(layer "In2.Cu")
		(net 28)
	)
	(segment
		(start 189.397237 104.984209)
		(end 189.418373 104.976813)
		(width 0.1)
		(layer "In2.Cu")
		(net 28)
	)
	(segment
		(start 188.118809 105.284856)
		(end 188.130722 105.265896)
		(width 0.1)
		(layer "In2.Cu")
		(net 28)
	)
	(segment
		(start 188.840626 105.322508)
		(end 188.862878 105.32)
		(width 0.1)
		(layer "In2.Cu")
		(net 28)
	)
	(segment
		(start 188.578277 104.547921)
		(end 188.597237 104.536008)
		(width 0.1)
		(layer "In2.Cu")
		(net 28)
	)
	(segment
		(start 188.562442 104.563756)
		(end 188.578277 104.547921)
		(width 0.1)
		(layer "In2.Cu")
		(net 28)
	)
	(segment
		(start 188.930722 105.265896)
		(end 188.938118 105.24476)
		(width 0.1)
		(layer "In2.Cu")
		(net 28)
	)
	(segment
		(start 189.330722 105.265896)
		(end 189.338118 105.24476)
		(width 0.1)
		(layer "In2.Cu")
		(net 28)
	)
	(segment
		(start 188.462878 105.32)
		(end 188.484014 105.312604)
		(width 0.1)
		(layer "In2.Cu")
		(net 28)
	)
	(segment
		(start 188.718809 104.563756)
		(end 188.730722 104.582716)
		(width 0.1)
		(layer "In2.Cu")
		(net 28)
	)
	(segment
		(start 188.943133 104.603852)
		(end 188.950529 104.582716)
		(width 0.1)
		(layer "In2.Cu")
		(net 28)
	)
	(segment
		(start 187.940626 105.222508)
		(end 187.943133 105.24476)
		(width 0.1)
		(layer "In2.Cu")
		(net 28)
	)
	(segment
		(start 181.159179 102.497157)
		(end 181.186328 102.524306)
		(width 0.1)
		(layer "F.Cu")
		(net 29)
	)
	(segment
		(start 203.863477 101.297157)
		(end 205.363477 101.297157)
		(width 0.15)
		(layer "F.Cu")
		(net 29)
	)
	(segment
		(start 179.536328 102.497157)
		(end 181.159179 102.497157)
		(width 0.1)
		(layer "F.Cu")
		(net 29)
	)
	(segment
		(start 205.363477 101.297157)
		(end 205.386328 101.274306)
		(width 0.15)
		(layer "F.Cu")
		(net 29)
	)
	(via blind
		(at 181.186328 102.524306)
		(size 0.5)
		(drill 0.2)
		(layers "F.Cu" "In2.Cu")
		(net 29)
	)
	(via
		(at 205.386328 101.274306)
		(size 0.5)
		(drill 0.2)
		(layers "F.Cu" "B.Cu")
		(net 29)
	)
	(segment
		(start 186.478277 104.005073)
		(end 186.497237 103.99316)
		(width 0.1)
		(layer "In2.Cu")
		(net 29)
	)
	(segment
		(start 186.450529 104.039868)
		(end 186.462442 104.020908)
		(width 0.1)
		(layer "In2.Cu")
		(net 29)
	)
	(segment
		(start 186.640626 104.083256)
		(end 186.640626 104.615356)
		(width 0.1)
		(layer "In2.Cu")
		(net 29)
	)
	(segment
		(start 186.184014 104.284209)
		(end 186.202974 104.296122)
		(width 0.1)
		(layer "In2.Cu")
		(net 29)
	)
	(segment
		(start 186.430722 104.658744)
		(end 186.438118 104.637608)
		(width 0.1)
		(layer "In2.Cu")
		(net 29)
	)
	(segment
		(start 187.078277 104.693539)
		(end 187.097237 104.705452)
		(width 0.1)
		(layer "In2.Cu")
		(net 29)
	)
	(segment
		(start 187.438118 104.061004)
		(end 187.440626 104.083256)
		(width 0.1)
		(layer "In2.Cu")
		(net 29)
	)
	(segment
		(start 186.240626 104.615356)
		(end 186.243133 104.637608)
		(width 0.1)
		(layer "In2.Cu")
		(net 29)
	)
	(segment
		(start 186.250529 104.658744)
		(end 186.262442 104.677704)
		(width 0.1)
		(layer "In2.Cu")
		(net 29)
	)
	(segment
		(start 186.640626 104.615356)
		(end 186.643133 104.637608)
		(width 0.1)
		(layer "In2.Cu")
		(net 29)
	)
	(segment
		(start 186.418809 104.677704)
		(end 186.430722 104.658744)
		(width 0.1)
		(layer "In2.Cu")
		(net 29)
	)
	(segment
		(start 186.697237 104.705452)
		(end 186.718373 104.712848)
		(width 0.1)
		(layer "In2.Cu")
		(net 29)
	)
	(segment
		(start 187.184014 104.705452)
		(end 187.202974 104.693539)
		(width 0.1)
		(layer "In2.Cu")
		(net 29)
	)
	(segment
		(start 186.984014 103.99316)
		(end 187.002974 104.005073)
		(width 0.1)
		(layer "In2.Cu")
		(net 29)
	)
	(segment
		(start 187.518373 104.271799)
		(end 187.540626 104.274306)
		(width 0.1)
		(layer "In2.Cu")
		(net 29)
	)
	(segment
		(start 187.002974 104.005073)
		(end 187.018809 104.020908)
		(width 0.1)
		(layer "In2.Cu")
		(net 29)
	)
	(segment
		(start 186.584014 103.99316)
		(end 186.602974 104.005073)
		(width 0.1)
		(layer "In2.Cu")
		(net 29)
	)
	(segment
		(start 187.240626 104.083256)
		(end 187.243133 104.061004)
		(width 0.1)
		(layer "In2.Cu")
		(net 29)
	)
	(segment
		(start 186.940626 103.983256)
		(end 186.962878 103.985764)
		(width 0.1)
		(layer "In2.Cu")
		(net 29)
	)
	(segment
		(start 202.186328 103.574306)
		(end 202.186328 102.120008)
		(width 0.1)
		(layer "In2.Cu")
		(net 29)
	)
	(segment
		(start 202.186328 102.120008)
		(end 203.03203 101.274306)
		(width 0.1)
		(layer "In2.Cu")
		(net 29)
	)
	(segment
		(start 187.050529 104.658744)
		(end 187.062442 104.677704)
		(width 0.1)
		(layer "In2.Cu")
		(net 29)
	)
	(segment
		(start 187.202974 104.693539)
		(end 187.218809 104.677704)
		(width 0.1)
		(layer "In2.Cu")
		(net 29)
	)
	(segment
		(start 186.818809 104.677704)
		(end 186.830722 104.658744)
		(width 0.1)
		(layer "In2.Cu")
		(net 29)
	)
	(segment
		(start 187.340626 103.983256)
		(end 187.362878 103.985764)
		(width 0.1)
		(layer "In2.Cu")
		(net 29)
	)
	(segment
		(start 187.230722 104.658744)
		(end 187.238118 104.637608)
		(width 0.1)
		(layer "In2.Cu")
		(net 29)
	)
	(segment
		(start 186.602974 104.005073)
		(end 186.618809 104.020908)
		(width 0.1)
		(layer "In2.Cu")
		(net 29)
	)
	(segment
		(start 186.238118 104.352053)
		(end 186.240626 104.374306)
		(width 0.1)
		(layer "In2.Cu")
		(net 29)
	)
	(segment
		(start 187.318373 103.985764)
		(end 187.340626 103.983256)
		(width 0.1)
		(layer "In2.Cu")
		(net 29)
	)
	(segment
		(start 187.030722 104.039868)
		(end 187.038118 104.061004)
		(width 0.1)
		(layer "In2.Cu")
		(net 29)
	)
	(segment
		(start 186.340626 104.715356)
		(end 186.362878 104.712848)
		(width 0.1)
		(layer "In2.Cu")
		(net 29)
	)
	(segment
		(start 187.140626 104.715356)
		(end 187.162878 104.712848)
		(width 0.1)
		(layer "In2.Cu")
		(net 29)
	)
	(segment
		(start 187.218809 104.677704)
		(end 187.230722 104.658744)
		(width 0.1)
		(layer "In2.Cu")
		(net 29)
	)
	(segment
		(start 186.784014 104.705452)
		(end 186.802974 104.693539)
		(width 0.1)
		(layer "In2.Cu")
		(net 29)
	)
	(segment
		(start 187.162878 104.712848)
		(end 187.184014 104.705452)
		(width 0.1)
		(layer "In2.Cu")
		(net 29)
	)
	(segment
		(start 186.762878 104.712848)
		(end 186.784014 104.705452)
		(width 0.1)
		(layer "In2.Cu")
		(net 29)
	)
	(segment
		(start 186.243133 104.637608)
		(end 186.250529 104.658744)
		(width 0.1)
		(layer "In2.Cu")
		(net 29)
	)
	(segment
		(start 186.630722 104.039868)
		(end 186.638118 104.061004)
		(width 0.1)
		(layer "In2.Cu")
		(net 29)
	)
	(segment
		(start 186.518373 103.985764)
		(end 186.540626 103.983256)
		(width 0.1)
		(layer "In2.Cu")
		(net 29)
	)
	(segment
		(start 187.040626 104.615356)
		(end 187.043133 104.637608)
		(width 0.1)
		(layer "In2.Cu")
		(net 29)
	)
	(segment
		(start 186.650529 104.658744)
		(end 186.662442 104.677704)
		(width 0.1)
		(layer "In2.Cu")
		(net 29)
	)
	(segment
		(start 186.840626 104.615356)
		(end 186.840626 104.083256)
		(width 0.1)
		(layer "In2.Cu")
		(net 29)
	)
	(segment
		(start 186.362878 104.712848)
		(end 186.384014 104.705452)
		(width 0.1)
		(layer "In2.Cu")
		(net 29)
	)
	(segment
		(start 186.402974 104.693539)
		(end 186.418809 104.677704)
		(width 0.1)
		(layer "In2.Cu")
		(net 29)
	)
	(segment
		(start 186.843133 104.061004)
		(end 186.850529 104.039868)
		(width 0.1)
		(layer "In2.Cu")
		(net 29)
	)
	(segment
		(start 187.018809 104.020908)
		(end 187.030722 104.039868)
		(width 0.1)
		(layer "In2.Cu")
		(net 29)
	)
	(segment
		(start 187.450529 104.217695)
		(end 187.462442 104.236655)
		(width 0.1)
		(layer "In2.Cu")
		(net 29)
	)
	(segment
		(start 186.718373 104.712848)
		(end 186.740626 104.715356)
		(width 0.1)
		(layer "In2.Cu")
		(net 29)
	)
	(segment
		(start 187.250529 104.039868)
		(end 187.262442 104.020908)
		(width 0.1)
		(layer "In2.Cu")
		(net 29)
	)
	(segment
		(start 187.443133 104.196559)
		(end 187.450529 104.217695)
		(width 0.1)
		(layer "In2.Cu")
		(net 29)
	)
	(segment
		(start 187.384014 103.99316)
		(end 187.402974 104.005073)
		(width 0.1)
		(layer "In2.Cu")
		(net 29)
	)
	(segment
		(start 186.830722 104.658744)
		(end 186.838118 104.637608)
		(width 0.1)
		(layer "In2.Cu")
		(net 29)
	)
	(segment
		(start 186.440626 104.083256)
		(end 186.443133 104.061004)
		(width 0.1)
		(layer "In2.Cu")
		(net 29)
	)
	(segment
		(start 201.486328 104.274306)
		(end 202.186328 103.574306)
		(width 0.1)
		(layer "In2.Cu")
		(net 29)
	)
	(segment
		(start 186.618809 104.020908)
		(end 186.630722 104.039868)
		(width 0.1)
		(layer "In2.Cu")
		(net 29)
	)
	(segment
		(start 183.986328 104.274306)
		(end 186.140626 104.274306)
		(width 0.1)
		(layer "In2.Cu")
		(net 29)
	)
	(segment
		(start 186.540626 103.983256)
		(end 186.562878 103.985764)
		(width 0.1)
		(layer "In2.Cu")
		(net 29)
	)
	(segment
		(start 187.040626 104.083256)
		(end 187.040626 104.615356)
		(width 0.1)
		(layer "In2.Cu")
		(net 29)
	)
	(segment
		(start 187.440626 104.083256)
		(end 187.440626 104.174306)
		(width 0.1)
		(layer "In2.Cu")
		(net 29)
	)
	(segment
		(start 187.062442 104.677704)
		(end 187.078277 104.693539)
		(width 0.1)
		(layer "In2.Cu")
		(net 29)
	)
	(segment
		(start 186.562878 103.985764)
		(end 186.584014 103.99316)
		(width 0.1)
		(layer "In2.Cu")
		(net 29)
	)
	(segment
		(start 186.497237 103.99316)
		(end 186.518373 103.985764)
		(width 0.1)
		(layer "In2.Cu")
		(net 29)
	)
	(segment
		(start 186.643133 104.637608)
		(end 186.650529 104.658744)
		(width 0.1)
		(layer "In2.Cu")
		(net 29)
	)
	(segment
		(start 181.186328 102.524306)
		(end 182.236328 102.524306)
		(width 0.1)
		(layer "In2.Cu")
		(net 29)
	)
	(segment
		(start 186.140626 104.274306)
		(end 186.162878 104.276813)
		(width 0.1)
		(layer "In2.Cu")
		(net 29)
	)
	(segment
		(start 187.297237 103.99316)
		(end 187.318373 103.985764)
		(width 0.1)
		(layer "In2.Cu")
		(net 29)
	)
	(segment
		(start 187.097237 104.705452)
		(end 187.118373 104.712848)
		(width 0.1)
		(layer "In2.Cu")
		(net 29)
	)
	(segment
		(start 187.262442 104.020908)
		(end 187.278277 104.005073)
		(width 0.1)
		(layer "In2.Cu")
		(net 29)
	)
	(segment
		(start 182.236328 102.524306)
		(end 183.986328 104.274306)
		(width 0.1)
		(layer "In2.Cu")
		(net 29)
	)
	(segment
		(start 186.438118 104.637608)
		(end 186.440626 104.615356)
		(width 0.1)
		(layer "In2.Cu")
		(net 29)
	)
	(segment
		(start 186.740626 104.715356)
		(end 186.762878 104.712848)
		(width 0.1)
		(layer "In2.Cu")
		(net 29)
	)
	(segment
		(start 187.240626 104.615356)
		(end 187.240626 104.083256)
		(width 0.1)
		(layer "In2.Cu")
		(net 29)
	)
	(segment
		(start 186.230722 104.330917)
		(end 186.238118 104.352053)
		(width 0.1)
		(layer "In2.Cu")
		(net 29)
	)
	(segment
		(start 186.318373 104.712848)
		(end 186.340626 104.715356)
		(width 0.1)
		(layer "In2.Cu")
		(net 29)
	)
	(segment
		(start 186.638118 104.061004)
		(end 186.640626 104.083256)
		(width 0.1)
		(layer "In2.Cu")
		(net 29)
	)
	(segment
		(start 186.462442 104.020908)
		(end 186.478277 104.005073)
		(width 0.1)
		(layer "In2.Cu")
		(net 29)
	)
	(segment
		(start 186.897237 103.99316)
		(end 186.918373 103.985764)
		(width 0.1)
		(layer "In2.Cu")
		(net 29)
	)
	(segment
		(start 186.962878 103.985764)
		(end 186.984014 103.99316)
		(width 0.1)
		(layer "In2.Cu")
		(net 29)
	)
	(segment
		(start 186.443133 104.061004)
		(end 186.450529 104.039868)
		(width 0.1)
		(layer "In2.Cu")
		(net 29)
	)
	(segment
		(start 186.850529 104.039868)
		(end 186.862442 104.020908)
		(width 0.1)
		(layer "In2.Cu")
		(net 29)
	)
	(segment
		(start 186.162878 104.276813)
		(end 186.184014 104.284209)
		(width 0.1)
		(layer "In2.Cu")
		(net 29)
	)
	(segment
		(start 187.038118 104.061004)
		(end 187.040626 104.083256)
		(width 0.1)
		(layer "In2.Cu")
		(net 29)
	)
	(segment
		(start 186.384014 104.705452)
		(end 186.402974 104.693539)
		(width 0.1)
		(layer "In2.Cu")
		(net 29)
	)
	(segment
		(start 186.918373 103.985764)
		(end 186.940626 103.983256)
		(width 0.1)
		(layer "In2.Cu")
		(net 29)
	)
	(segment
		(start 187.118373 104.712848)
		(end 187.140626 104.715356)
		(width 0.1)
		(layer "In2.Cu")
		(net 29)
	)
	(segment
		(start 203.03203 101.274306)
		(end 205.386328 101.274306)
		(width 0.1)
		(layer "In2.Cu")
		(net 29)
	)
	(segment
		(start 187.478277 104.25249)
		(end 187.497237 104.264403)
		(width 0.1)
		(layer "In2.Cu")
		(net 29)
	)
	(segment
		(start 186.678277 104.693539)
		(end 186.697237 104.705452)
		(width 0.1)
		(layer "In2.Cu")
		(net 29)
	)
	(segment
		(start 187.430722 104.039868)
		(end 187.438118 104.061004)
		(width 0.1)
		(layer "In2.Cu")
		(net 29)
	)
	(segment
		(start 186.662442 104.677704)
		(end 186.678277 104.693539)
		(width 0.1)
		(layer "In2.Cu")
		(net 29)
	)
	(segment
		(start 186.297237 104.705452)
		(end 186.318373 104.712848)
		(width 0.1)
		(layer "In2.Cu")
		(net 29)
	)
	(segment
		(start 187.440626 104.174306)
		(end 187.443133 104.196559)
		(width 0.1)
		(layer "In2.Cu")
		(net 29)
	)
	(segment
		(start 187.462442 104.236655)
		(end 187.478277 104.25249)
		(width 0.1)
		(layer "In2.Cu")
		(net 29)
	)
	(segment
		(start 187.238118 104.637608)
		(end 187.240626 104.615356)
		(width 0.1)
		(layer "In2.Cu")
		(net 29)
	)
	(segment
		(start 186.878277 104.005073)
		(end 186.897237 103.99316)
		(width 0.1)
		(layer "In2.Cu")
		(net 29)
	)
	(segment
		(start 187.540626 104.274306)
		(end 201.486328 104.274306)
		(width 0.1)
		(layer "In2.Cu")
		(net 29)
	)
	(segment
		(start 186.262442 104.677704)
		(end 186.278277 104.693539)
		(width 0.1)
		(layer "In2.Cu")
		(net 29)
	)
	(segment
		(start 187.497237 104.264403)
		(end 187.518373 104.271799)
		(width 0.1)
		(layer "In2.Cu")
		(net 29)
	)
	(segment
		(start 187.418809 104.020908)
		(end 187.430722 104.039868)
		(width 0.1)
		(layer "In2.Cu")
		(net 29)
	)
	(segment
		(start 187.362878 103.985764)
		(end 187.384014 103.99316)
		(width 0.1)
		(layer "In2.Cu")
		(net 29)
	)
	(segment
		(start 187.278277 104.005073)
		(end 187.297237 103.99316)
		(width 0.1)
		(layer "In2.Cu")
		(net 29)
	)
	(segment
		(start 186.278277 104.693539)
		(end 186.297237 104.705452)
		(width 0.1)
		(layer "In2.Cu")
		(net 29)
	)
	(segment
		(start 186.218809 104.311957)
		(end 186.230722 104.330917)
		(width 0.1)
		(layer "In2.Cu")
		(net 29)
	)
	(segment
		(start 186.802974 104.693539)
		(end 186.818809 104.677704)
		(width 0.1)
		(layer "In2.Cu")
		(net 29)
	)
	(segment
		(start 186.862442 104.020908)
		(end 186.878277 104.005073)
		(width 0.1)
		(layer "In2.Cu")
		(net 29)
	)
	(segment
		(start 186.440626 104.615356)
		(end 186.440626 104.083256)
		(width 0.1)
		(layer "In2.Cu")
		(net 29)
	)
	(segment
		(start 186.838118 104.637608)
		(end 186.840626 104.615356)
		(width 0.1)
		(layer "In2.Cu")
		(net 29)
	)
	(segment
		(start 187.402974 104.005073)
		(end 187.418809 104.020908)
		(width 0.1)
		(layer "In2.Cu")
		(net 29)
	)
	(segment
		(start 186.202974 104.296122)
		(end 186.218809 104.311957)
		(width 0.1)
		(layer "In2.Cu")
		(net 29)
	)
	(segment
		(start 187.243133 104.061004)
		(end 187.250529 104.039868)
		(width 0.1)
		(layer "In2.Cu")
		(net 29)
	)
	(segment
		(start 186.240626 104.374306)
		(end 186.240626 104.615356)
		(width 0.1)
		(layer "In2.Cu")
		(net 29)
	)
	(segment
		(start 186.840626 104.083256)
		(end 186.843133 104.061004)
		(width 0.1)
		(layer "In2.Cu")
		(net 29)
	)
	(segment
		(start 187.043133 104.637608)
		(end 187.050529 104.658744)
		(width 0.1)
		(layer "In2.Cu")
		(net 29)
	)
	(segment
		(start 175.536329 101.497156)
		(end 176.036329 101.997156)
		(width 0.15)
		(layer "F.Cu")
		(net 30)
	)
	(segment
		(start 205.163477 100.297157)
		(end 205.186328 100.274306)
		(width 0.15)
		(layer "F.Cu")
		(net 30)
	)
	(segment
		(start 203.863477 100.297157)
		(end 205.163477 100.297157)
		(width 0.15)
		(layer "F.Cu")
		(net 30)
	)
	(via
		(at 205.186328 100.274306)
		(size 0.5)
		(drill 0.2)
		(layers "F.Cu" "B.Cu")
		(net 30)
	)
	(via blind
		(at 176.036329 101.997156)
		(size 0.5)
		(drill 0.2)
		(layers "F.Cu" "In2.Cu")
		(net 30)
	)
	(segment
		(start 186.186328 103.720008)
		(end 197.736328 103.720008)
		(width 0.1)
		(layer "In2.Cu")
		(net 30)
	)
	(segment
		(start 203.386328 100.320008)
		(end 205.140626 100.320008)
		(width 0.1)
		(layer "In2.Cu")
		(net 30)
	)
	(segment
		(start 176.036329 101.997156)
		(end 176.03633 101.997157)
		(width 0.1)
		(layer "In2.Cu")
		(net 30)
	)
	(segment
		(start 185.686328 103.820008)
		(end 185.786328 103.820008)
		(width 0.1)
		(layer "In2.Cu")
		(net 30)
	)
	(segment
		(start 186.088835 103.642261)
		(end 186.096231 103.663397)
		(width 0.1)
		(layer "In2.Cu")
		(net 30)
	)
	(segment
		(start 186.029716 103.322605)
		(end 186.048676 103.334518)
		(width 0.1)
		(layer "In2.Cu")
		(net 30)
	)
	(segment
		(start 185.586328 103.720008)
		(end 185.597454 103.721261)
		(width 0.1)
		(layer "In2.Cu")
		(net 30)
	)
	(segment
		(start 186.108144 103.682357)
		(end 186.123979 103.698192)
		(width 0.1)
		(layer "In2.Cu")
		(net 30)
	)
	(segment
		(start 185.786328 103.820008)
		(end 185.797454 103.818754)
		(width 0.1)
		(layer "In2.Cu")
		(net 30)
	)
	(segment
		(start 185.664633 103.815056)
		(end 185.675201 103.818754)
		(width 0.1)
		(layer "In2.Cu")
		(net 30)
	)
	(segment
		(start 197.736328 103.720008)
		(end 199.836328 101.620008)
		(width 0.1)
		(layer "In2.Cu")
		(net 30)
	)
	(segment
		(start 185.655153 103.809099)
		(end 185.664633 103.815056)
		(width 0.1)
		(layer "In2.Cu")
		(net 30)
	)
	(segment
		(start 186.08382 103.390449)
		(end 186.086328 103.412701)
		(width 0.1)
		(layer "In2.Cu")
		(net 30)
	)
	(segment
		(start 176.03633 101.997157)
		(end 183.336328 101.997157)
		(width 0.1)
		(layer "In2.Cu")
		(net 30)
	)
	(segment
		(start 205.140626 100.320008)
		(end 205.186328 100.274306)
		(width 0.1)
		(layer "In2.Cu")
		(net 30)
	)
	(segment
		(start 186.086328 103.412701)
		(end 186.086328 103.620008)
		(width 0.1)
		(layer "In2.Cu")
		(net 30)
	)
	(segment
		(start 186.00858 103.315209)
		(end 186.029716 103.322605)
		(width 0.1)
		(layer "In2.Cu")
		(net 30)
	)
	(segment
		(start 185.888835 103.390449)
		(end 185.896231 103.369313)
		(width 0.1)
		(layer "In2.Cu")
		(net 30)
	)
	(segment
		(start 185.942939 103.322605)
		(end 185.964075 103.315209)
		(width 0.1)
		(layer "In2.Cu")
		(net 30)
	)
	(segment
		(start 183.336328 101.997157)
		(end 185.059179 103.720008)
		(width 0.1)
		(layer "In2.Cu")
		(net 30)
	)
	(segment
		(start 185.647236 103.801182)
		(end 185.655153 103.809099)
		(width 0.1)
		(layer "In2.Cu")
		(net 30)
	)
	(segment
		(start 185.923979 103.334518)
		(end 185.942939 103.322605)
		(width 0.1)
		(layer "In2.Cu")
		(net 30)
	)
	(segment
		(start 186.096231 103.663397)
		(end 186.108144 103.682357)
		(width 0.1)
		(layer "In2.Cu")
		(net 30)
	)
	(segment
		(start 186.164075 103.717501)
		(end 186.186328 103.720008)
		(width 0.1)
		(layer "In2.Cu")
		(net 30)
	)
	(segment
		(start 185.836328 103.720008)
		(end 185.886328 103.720008)
		(width 0.1)
		(layer "In2.Cu")
		(net 30)
	)
	(segment
		(start 186.064511 103.350353)
		(end 186.076424 103.369313)
		(width 0.1)
		(layer "In2.Cu")
		(net 30)
	)
	(segment
		(start 202.086328 101.620008)
		(end 203.386328 100.320008)
		(width 0.1)
		(layer "In2.Cu")
		(net 30)
	)
	(segment
		(start 185.964075 103.315209)
		(end 185.986328 103.312701)
		(width 0.1)
		(layer "In2.Cu")
		(net 30)
	)
	(segment
		(start 185.825419 103.801182)
		(end 185.831376 103.791702)
		(width 0.1)
		(layer "In2.Cu")
		(net 30)
	)
	(segment
		(start 185.797454 103.818754)
		(end 185.808022 103.815056)
		(width 0.1)
		(layer "In2.Cu")
		(net 30)
	)
	(segment
		(start 199.836328 101.620008)
		(end 202.086328 101.620008)
		(width 0.1)
		(layer "In2.Cu")
		(net 30)
	)
	(segment
		(start 186.076424 103.369313)
		(end 186.08382 103.390449)
		(width 0.1)
		(layer "In2.Cu")
		(net 30)
	)
	(segment
		(start 185.835074 103.781134)
		(end 185.836328 103.770008)
		(width 0.1)
		(layer "In2.Cu")
		(net 30)
	)
	(segment
		(start 185.836328 103.770008)
		(end 185.836328 103.720008)
		(width 0.1)
		(layer "In2.Cu")
		(net 30)
	)
	(segment
		(start 185.986328 103.312701)
		(end 186.00858 103.315209)
		(width 0.1)
		(layer "In2.Cu")
		(net 30)
	)
	(segment
		(start 185.908144 103.350353)
		(end 185.923979 103.334518)
		(width 0.1)
		(layer "In2.Cu")
		(net 30)
	)
	(segment
		(start 185.886328 103.412701)
		(end 185.888835 103.390449)
		(width 0.1)
		(layer "In2.Cu")
		(net 30)
	)
	(segment
		(start 185.817502 103.809099)
		(end 185.825419 103.801182)
		(width 0.1)
		(layer "In2.Cu")
		(net 30)
	)
	(segment
		(start 186.086328 103.620008)
		(end 186.088835 103.642261)
		(width 0.1)
		(layer "In2.Cu")
		(net 30)
	)
	(segment
		(start 186.123979 103.698192)
		(end 186.142939 103.710105)
		(width 0.1)
		(layer "In2.Cu")
		(net 30)
	)
	(segment
		(start 185.808022 103.815056)
		(end 185.817502 103.809099)
		(width 0.1)
		(layer "In2.Cu")
		(net 30)
	)
	(segment
		(start 185.059179 103.720008)
		(end 185.586328 103.720008)
		(width 0.1)
		(layer "In2.Cu")
		(net 30)
	)
	(segment
		(start 185.896231 103.369313)
		(end 185.908144 103.350353)
		(width 0.1)
		(layer "In2.Cu")
		(net 30)
	)
	(segment
		(start 185.637581 103.781134)
		(end 185.641279 103.791702)
		(width 0.1)
		(layer "In2.Cu")
		(net 30)
	)
	(segment
		(start 186.048676 103.334518)
		(end 186.064511 103.350353)
		(width 0.1)
		(layer "In2.Cu")
		(net 30)
	)
	(segment
		(start 185.597454 103.721261)
		(end 185.608022 103.724959)
		(width 0.1)
		(layer "In2.Cu")
		(net 30)
	)
	(segment
		(start 185.608022 103.724959)
		(end 185.617502 103.730916)
		(width 0.1)
		(layer "In2.Cu")
		(net 30)
	)
	(segment
		(start 185.617502 103.730916)
		(end 185.625419 103.738833)
		(width 0.1)
		(layer "In2.Cu")
		(net 30)
	)
	(segment
		(start 185.831376 103.791702)
		(end 185.835074 103.781134)
		(width 0.1)
		(layer "In2.Cu")
		(net 30)
	)
	(segment
		(start 185.675201 103.818754)
		(end 185.686328 103.820008)
		(width 0.1)
		(layer "In2.Cu")
		(net 30)
	)
	(segment
		(start 185.631376 103.748313)
		(end 185.635074 103.758881)
		(width 0.1)
		(layer "In2.Cu")
		(net 30)
	)
	(segment
		(start 185.886328 103.720008)
		(end 185.886328 103.412701)
		(width 0.1)
		(layer "In2.Cu")
		(net 30)
	)
	(segment
		(start 185.625419 103.738833)
		(end 185.631376 103.748313)
		(width 0.1)
		(layer "In2.Cu")
		(net 30)
	)
	(segment
		(start 185.635074 103.758881)
		(end 185.637581 103.781134)
		(width 0.1)
		(layer "In2.Cu")
		(net 30)
	)
	(segment
		(start 186.142939 103.710105)
		(end 186.164075 103.717501)
		(width 0.1)
		(layer "In2.Cu")
		(net 30)
	)
	(segment
		(start 185.641279 103.791702)
		(end 185.647236 103.801182)
		(width 0.1)
		(layer "In2.Cu")
		(net 30)
	)
	(segment
		(start 187.286328 93.674306)
		(end 200.586328 93.674306)
		(width 0.1)
		(layer "F.Cu")
		(net 31)
	)
	(segment
		(start 203.186328 96.274306)
		(end 203.186328 99.620008)
		(width 0.1)
		(layer "F.Cu")
		(net 31)
	)
	(segment
		(start 183.463477 97.497157)
		(end 187.286328 93.674306)
		(width 0.1)
		(layer "F.Cu")
		(net 31)
	)
	(segment
		(start 179.536328 97.497157)
		(end 183.463477 97.497157)
		(width 0.1)
		(layer "F.Cu")
		(net 31)
	)
	(segment
		(start 200.586328 93.674306)
		(end 203.186328 96.274306)
		(width 0.1)
		(layer "F.Cu")
		(net 31)
	)
	(segment
		(start 204.763477 102.797157)
		(end 204.786328 102.774306)
		(width 0.15)
		(layer "F.Cu")
		(net 32)
	)
	(segment
		(start 203.863477 102.797157)
		(end 204.763477 102.797157)
		(width 0.15)
		(layer "F.Cu")
		(net 32)
	)
	(segment
		(start 178.536327 105.497156)
		(end 179.036327 104.997156)
		(width 0.15)
		(layer "F.Cu")
		(net 32)
	)
	(via
		(at 204.786328 102.774306)
		(size 0.5)
		(drill 0.2)
		(layers "F.Cu" "B.Cu")
		(net 32)
	)
	(via blind
		(at 179.036327 104.997156)
		(size 0.5)
		(drill 0.2)
		(layers "F.Cu" "In2.Cu")
		(net 32)
	)
	(segment
		(start 196.040626 107.031096)
		(end 196.038118 107.053349)
		(width 0.1)
		(layer "In2.Cu")
		(net 32)
	)
	(segment
		(start 196.250529 106.217694)
		(end 196.243133 106.196558)
		(width 0.1)
		(layer "In2.Cu")
		(net 32)
	)
	(segment
		(start 196.162878 105.970023)
		(end 196.140626 105.967516)
		(width 0.1)
		(layer "In2.Cu")
		(net 32)
	)
	(segment
		(start 196.097237 105.977419)
		(end 196.078277 105.989332)
		(width 0.1)
		(layer "In2.Cu")
		(net 32)
	)
	(segment
		(start 195.897237 107.121193)
		(end 195.878277 107.10928)
		(width 0.1)
		(layer "In2.Cu")
		(net 32)
	)
	(segment
		(start 195.418809 106.311958)
		(end 195.402974 106.296123)
		(width 0.1)
		(layer "In2.Cu")
		(net 32)
	)
	(segment
		(start 196.243133 106.196558)
		(end 196.240626 106.174306)
		(width 0.1)
		(layer "In2.Cu")
		(net 32)
	)
	(segment
		(start 195.518373 107.128589)
		(end 195.497237 107.121193)
		(width 0.1)
		(layer "In2.Cu")
		(net 32)
	)
	(segment
		(start 195.450529 107.074485)
		(end 195.443133 107.053349)
		(width 0.1)
		(layer "In2.Cu")
		(net 32)
	)
	(segment
		(start 196.040626 106.067516)
		(end 196.040626 107.031096)
		(width 0.1)
		(layer "In2.Cu")
		(net 32)
	)
	(segment
		(start 196.038118 107.053349)
		(end 196.030722 107.074485)
		(width 0.1)
		(layer "In2.Cu")
		(net 32)
	)
	(segment
		(start 196.202974 105.989332)
		(end 196.184014 105.977419)
		(width 0.1)
		(layer "In2.Cu")
		(net 32)
	)
	(segment
		(start 195.840626 107.031096)
		(end 195.840626 106.067516)
		(width 0.1)
		(layer "In2.Cu")
		(net 32)
	)
	(segment
		(start 195.762878 105.970023)
		(end 195.740626 105.967516)
		(width 0.1)
		(layer "In2.Cu")
		(net 32)
	)
	(segment
		(start 180.009178 104.997156)
		(end 179.036327 104.997156)
		(width 0.1)
		(layer "In2.Cu")
		(net 32)
	)
	(segment
		(start 195.643133 106.045263)
		(end 195.640626 106.067516)
		(width 0.1)
		(layer "In2.Cu")
		(net 32)
	)
	(segment
		(start 195.584014 107.121193)
		(end 195.562878 107.128589)
		(width 0.1)
		(layer "In2.Cu")
		(net 32)
	)
	(segment
		(start 196.062442 106.005167)
		(end 196.050529 106.024127)
		(width 0.1)
		(layer "In2.Cu")
		(net 32)
	)
	(segment
		(start 196.218809 106.005167)
		(end 196.202974 105.989332)
		(width 0.1)
		(layer "In2.Cu")
		(net 32)
	)
	(segment
		(start 196.318373 106.271798)
		(end 196.297237 106.264402)
		(width 0.1)
		(layer "In2.Cu")
		(net 32)
	)
	(segment
		(start 195.430722 106.330918)
		(end 195.418809 106.311958)
		(width 0.1)
		(layer "In2.Cu")
		(net 32)
	)
	(segment
		(start 196.043133 106.045263)
		(end 196.040626 106.067516)
		(width 0.1)
		(layer "In2.Cu")
		(net 32)
	)
	(segment
		(start 195.438118 106.352054)
		(end 195.430722 106.330918)
		(width 0.1)
		(layer "In2.Cu")
		(net 32)
	)
	(segment
		(start 196.240626 106.174306)
		(end 196.240626 106.067516)
		(width 0.1)
		(layer "In2.Cu")
		(net 32)
	)
	(segment
		(start 195.497237 107.121193)
		(end 195.478277 107.10928)
		(width 0.1)
		(layer "In2.Cu")
		(net 32)
	)
	(segment
		(start 196.278277 106.252489)
		(end 196.262442 106.236654)
		(width 0.1)
		(layer "In2.Cu")
		(net 32)
	)
	(segment
		(start 195.850529 107.074485)
		(end 195.843133 107.053349)
		(width 0.1)
		(layer "In2.Cu")
		(net 32)
	)
	(segment
		(start 196.340626 106.274306)
		(end 196.318373 106.271798)
		(width 0.1)
		(layer "In2.Cu")
		(net 32)
	)
	(segment
		(start 196.184014 105.977419)
		(end 196.162878 105.970023)
		(width 0.1)
		(layer "In2.Cu")
		(net 32)
	)
	(segment
		(start 196.240626 106.067516)
		(end 196.238118 106.045263)
		(width 0.1)
		(layer "In2.Cu")
		(net 32)
	)
	(segment
		(start 195.802974 105.989332)
		(end 195.784014 105.977419)
		(width 0.1)
		(layer "In2.Cu")
		(net 32)
	)
	(segment
		(start 196.238118 106.045263)
		(end 196.230722 106.024127)
		(width 0.1)
		(layer "In2.Cu")
		(net 32)
	)
	(segment
		(start 195.650529 106.024127)
		(end 195.643133 106.045263)
		(width 0.1)
		(layer "In2.Cu")
		(net 32)
	)
	(segment
		(start 195.540626 107.131096)
		(end 195.518373 107.128589)
		(width 0.1)
		(layer "In2.Cu")
		(net 32)
	)
	(segment
		(start 203.386328 103.974306)
		(end 201.086328 106.274306)
		(width 0.1)
		(layer "In2.Cu")
		(net 32)
	)
	(segment
		(start 195.440626 106.374306)
		(end 195.438118 106.352054)
		(width 0.1)
		(layer "In2.Cu")
		(net 32)
	)
	(segment
		(start 196.230722 106.024127)
		(end 196.218809 106.005167)
		(width 0.1)
		(layer "In2.Cu")
		(net 32)
	)
	(segment
		(start 195.630722 107.074485)
		(end 195.618809 107.093445)
		(width 0.1)
		(layer "In2.Cu")
		(net 32)
	)
	(segment
		(start 196.002974 107.10928)
		(end 195.984014 107.121193)
		(width 0.1)
		(layer "In2.Cu")
		(net 32)
	)
	(segment
		(start 195.602974 107.10928)
		(end 195.584014 107.121193)
		(width 0.1)
		(layer "In2.Cu")
		(net 32)
	)
	(segment
		(start 195.440626 107.031096)
		(end 195.440626 106.374306)
		(width 0.1)
		(layer "In2.Cu")
		(net 32)
	)
	(segment
		(start 195.362878 106.276814)
		(end 195.340626 106.274306)
		(width 0.1)
		(layer "In2.Cu")
		(net 32)
	)
	(segment
		(start 195.862442 107.093445)
		(end 195.850529 107.074485)
		(width 0.1)
		(layer "In2.Cu")
		(net 32)
	)
	(segment
		(start 195.678277 105.989332)
		(end 195.662442 106.005167)
		(width 0.1)
		(layer "In2.Cu")
		(net 32)
	)
	(segment
		(start 195.918373 107.128589)
		(end 195.897237 107.121193)
		(width 0.1)
		(layer "In2.Cu")
		(net 32)
	)
	(segment
		(start 195.830722 106.024127)
		(end 195.818809 106.005167)
		(width 0.1)
		(layer "In2.Cu")
		(net 32)
	)
	(segment
		(start 195.384014 106.28421)
		(end 195.362878 106.276814)
		(width 0.1)
		(layer "In2.Cu")
		(net 32)
	)
	(segment
		(start 201.086328 106.274306)
		(end 196.340626 106.274306)
		(width 0.1)
		(layer "In2.Cu")
		(net 32)
	)
	(segment
		(start 195.940626 107.131096)
		(end 195.918373 107.128589)
		(width 0.1)
		(layer "In2.Cu")
		(net 32)
	)
	(segment
		(start 195.443133 107.053349)
		(end 195.440626 107.031096)
		(width 0.1)
		(layer "In2.Cu")
		(net 32)
	)
	(segment
		(start 195.640626 106.067516)
		(end 195.640626 107.031096)
		(width 0.1)
		(layer "In2.Cu")
		(net 32)
	)
	(segment
		(start 195.984014 107.121193)
		(end 195.962878 107.128589)
		(width 0.1)
		(layer "In2.Cu")
		(net 32)
	)
	(segment
		(start 196.078277 105.989332)
		(end 196.062442 106.005167)
		(width 0.1)
		(layer "In2.Cu")
		(net 32)
	)
	(segment
		(start 195.818809 106.005167)
		(end 195.802974 105.989332)
		(width 0.1)
		(layer "In2.Cu")
		(net 32)
	)
	(segment
		(start 195.962878 107.128589)
		(end 195.940626 107.131096)
		(width 0.1)
		(layer "In2.Cu")
		(net 32)
	)
	(segment
		(start 196.030722 107.074485)
		(end 196.018809 107.093445)
		(width 0.1)
		(layer "In2.Cu")
		(net 32)
	)
	(segment
		(start 195.340626 106.274306)
		(end 181.286328 106.274306)
		(width 0.1)
		(layer "In2.Cu")
		(net 32)
	)
	(segment
		(start 195.740626 105.967516)
		(end 195.718373 105.970023)
		(width 0.1)
		(layer "In2.Cu")
		(net 32)
	)
	(segment
		(start 203.386328 103.274306)
		(end 203.386328 103.974306)
		(width 0.1)
		(layer "In2.Cu")
		(net 32)
	)
	(segment
		(start 195.618809 107.093445)
		(end 195.602974 107.10928)
		(width 0.1)
		(layer "In2.Cu")
		(net 32)
	)
	(segment
		(start 195.784014 105.977419)
		(end 195.762878 105.970023)
		(width 0.1)
		(layer "In2.Cu")
		(net 32)
	)
	(segment
		(start 195.640626 107.031096)
		(end 195.638118 107.053349)
		(width 0.1)
		(layer "In2.Cu")
		(net 32)
	)
	(segment
		(start 204.786328 102.774306)
		(end 203.886328 102.774306)
		(width 0.1)
		(layer "In2.Cu")
		(net 32)
	)
	(segment
		(start 196.050529 106.024127)
		(end 196.043133 106.045263)
		(width 0.1)
		(layer "In2.Cu")
		(net 32)
	)
	(segment
		(start 196.118373 105.970023)
		(end 196.097237 105.977419)
		(width 0.1)
		(layer "In2.Cu")
		(net 32)
	)
	(segment
		(start 195.843133 107.053349)
		(end 195.840626 107.031096)
		(width 0.1)
		(layer "In2.Cu")
		(net 32)
	)
	(segment
		(start 196.018809 107.093445)
		(end 196.002974 107.10928)
		(width 0.1)
		(layer "In2.Cu")
		(net 32)
	)
	(segment
		(start 195.878277 107.10928)
		(end 195.862442 107.093445)
		(width 0.1)
		(layer "In2.Cu")
		(net 32)
	)
	(segment
		(start 195.462442 107.093445)
		(end 195.450529 107.074485)
		(width 0.1)
		(layer "In2.Cu")
		(net 32)
	)
	(segment
		(start 196.262442 106.236654)
		(end 196.250529 106.217694)
		(width 0.1)
		(layer "In2.Cu")
		(net 32)
	)
	(segment
		(start 196.140626 105.967516)
		(end 196.118373 105.970023)
		(width 0.1)
		(layer "In2.Cu")
		(net 32)
	)
	(segment
		(start 181.286328 106.274306)
		(end 180.009178 104.997156)
		(width 0.1)
		(layer "In2.Cu")
		(net 32)
	)
	(segment
		(start 195.840626 106.067516)
		(end 195.838118 106.045263)
		(width 0.1)
		(layer "In2.Cu")
		(net 32)
	)
	(segment
		(start 195.402974 106.296123)
		(end 195.384014 106.28421)
		(width 0.1)
		(layer "In2.Cu")
		(net 32)
	)
	(segment
		(start 195.562878 107.128589)
		(end 195.540626 107.131096)
		(width 0.1)
		(layer "In2.Cu")
		(net 32)
	)
	(segment
		(start 203.886328 102.774306)
		(end 203.386328 103.274306)
		(width 0.1)
		(layer "In2.Cu")
		(net 32)
	)
	(segment
		(start 195.638118 107.053349)
		(end 195.630722 107.074485)
		(width 0.1)
		(layer "In2.Cu")
		(net 32)
	)
	(segment
		(start 195.697237 105.977419)
		(end 195.678277 105.989332)
		(width 0.1)
		(layer "In2.Cu")
		(net 32)
	)
	(segment
		(start 195.718373 105.970023)
		(end 195.697237 105.977419)
		(width 0.1)
		(layer "In2.Cu")
		(net 32)
	)
	(segment
		(start 195.838118 106.045263)
		(end 195.830722 106.024127)
		(width 0.1)
		(layer "In2.Cu")
		(net 32)
	)
	(segment
		(start 195.478277 107.10928)
		(end 195.462442 107.093445)
		(width 0.1)
		(layer "In2.Cu")
		(net 32)
	)
	(segment
		(start 196.297237 106.264402)
		(end 196.278277 106.252489)
		(width 0.1)
		(layer "In2.Cu")
		(net 32)
	)
	(segment
		(start 195.662442 106.005167)
		(end 195.650529 106.024127)
		(width 0.1)
		(layer "In2.Cu")
		(net 32)
	)
	(segment
		(start 199.83203 94.374306)
		(end 200.286328 94.374306)
		(width 0.1)
		(layer "F.Cu")
		(net 33)
	)
	(segment
		(start 200.286328 94.374306)
		(end 202.186328 96.274306)
		(width 0.1)
		(layer "F.Cu")
		(net 33)
	)
	(segment
		(start 202.186328 96.274306)
		(end 202.186328 99.620008)
		(width 0.1)
		(layer "F.Cu")
		(net 33)
	)
	(segment
		(start 179.536328 98.497157)
		(end 183.963477 98.497157)
		(width 0.1)
		(layer "F.Cu")
		(net 33)
	)
	(segment
		(start 188.086328 94.374306)
		(end 199.83203 94.374306)
		(width 0.1)
		(layer "F.Cu")
		(net 33)
	)
	(segment
		(start 183.963477 98.497157)
		(end 188.086328 94.374306)
		(width 0.1)
		(layer "F.Cu")
		(net 33)
	)
	(via
		(at 199.83203 94.374306)
		(size 0.5)
		(drill 0.2)
		(layers "F.Cu" "B.Cu")
		(net 33)
	)
	(segment
		(start 199.836328 94.955008)
		(end 199.836328 94.378604)
		(width 0.2)
		(layer "B.Cu")
		(net 33)
	)
	(segment
		(start 199.786328 93.705008)
		(end 199.786328 94.320008)
		(width 0.2)
		(layer "B.Cu")
		(net 33)
	)
	(segment
		(start 199.836328 94.378604)
		(end 199.83203 94.374306)
		(width 0.2)
		(layer "B.Cu")
		(net 33)
	)
	(segment
		(start 198.586328 96.974306)
		(end 199.186328 97.574306)
		(width 0.1)
		(layer "F.Cu")
		(net 34)
	)
	(segment
		(start 199.186328 97.574306)
		(end 199.186328 99.620008)
		(width 0.1)
		(layer "F.Cu")
		(net 34)
	)
	(segment
		(start 185.763477 100.497157)
		(end 189.286328 96.974306)
		(width 0.1)
		(layer "F.Cu")
		(net 34)
	)
	(segment
		(start 179.536328 100.497157)
		(end 185.763477 100.497157)
		(width 0.1)
		(layer "F.Cu")
		(net 34)
	)
	(segment
		(start 189.286328 96.974306)
		(end 198.586328 96.974306)
		(width 0.1)
		(layer "F.Cu")
		(net 34)
	)
	(via
		(at 194.686328 96.920008)
		(size 0.5)
		(drill 0.2)
		(layers "F.Cu" "B.Cu")
		(net 34)
	)
	(segment
		(start 194.396328 97.210008)
		(end 194.686328 96.920008)
		(width 0.2)
		(layer "B.Cu")
		(net 34)
	)
	(segment
		(start 193.971328 97.210008)
		(end 194.396328 97.210008)
		(width 0.2)
		(layer "B.Cu")
		(net 34)
	)
	(segment
		(start 194.686328 96.205008)
		(end 194.686328 96.920008)
		(width 0.2)
		(layer "B.Cu")
		(net 34)
	)
	(segment
		(start 190.286328 98.174306)
		(end 197.286328 98.174306)
		(width 0.1)
		(layer "F.Cu")
		(net 35)
	)
	(segment
		(start 178.536328 101.497157)
		(end 178.991329 101.952158)
		(width 0.1)
		(layer "F.Cu")
		(net 35)
	)
	(segment
		(start 186.508476 101.952158)
		(end 190.286328 98.174306)
		(width 0.1)
		(layer "F.Cu")
		(net 35)
	)
	(segment
		(start 197.686328 98.574306)
		(end 197.686328 99.620008)
		(width 0.1)
		(layer "F.Cu")
		(net 35)
	)
	(segment
		(start 178.991329 101.952158)
		(end 186.508476 101.952158)
		(width 0.1)
		(layer "F.Cu")
		(net 35)
	)
	(segment
		(start 197.286328 98.174306)
		(end 197.686328 98.574306)
		(width 0.1)
		(layer "F.Cu")
		(net 35)
	)
	(segment
		(start 195.73203 97.474306)
		(end 197.540626 97.474306)
		(width 0.1)
		(layer "F.Cu")
		(net 36)
	)
	(segment
		(start 192.041933 97.867694)
		(end 192.053846 97.886654)
		(width 0.1)
		(layer "F.Cu")
		(net 36)
	)
	(segment
		(start 192.13203 97.924306)
		(end 192.154282 97.921798)
		(width 0.1)
		(layer "F.Cu")
		(net 36)
	)
	(segment
		(start 190.994378 97.902489)
		(end 191.010213 97.886654)
		(width 0.1)
		(layer "F.Cu")
		(net 36)
	)
	(segment
		(start 192.269681 97.496122)
		(end 192.288641 97.484209)
		(width 0.1)
		(layer "F.Cu")
		(net 36)
	)
	(segment
		(start 191.754282 97.921798)
		(end 191.775418 97.914402)
		(width 0.1)
		(layer "F.Cu")
		(net 36)
	)
	(segment
		(start 191.069681 97.246123)
		(end 191.088641 97.23421)
		(width 0.1)
		(layer "F.Cu")
		(net 36)
	)
	(segment
		(start 191.022126 97.867694)
		(end 191.029522 97.846558)
		(width 0.1)
		(layer "F.Cu")
		(net 36)
	)
	(segment
		(start 191.354282 97.921798)
		(end 191.375418 97.914402)
		(width 0.1)
		(layer "F.Cu")
		(net 36)
	)
	(segment
		(start 189.886328 97.474306)
		(end 190.73203 97.474306)
		(width 0.1)
		(layer "F.Cu")
		(net 36)
	)
	(segment
		(start 191.853846 97.261958)
		(end 191.869681 97.246123)
		(width 0.1)
		(layer "F.Cu")
		(net 36)
	)
	(segment
		(start 191.375418 97.914402)
		(end 191.394378 97.902489)
		(width 0.1)
		(layer "F.Cu")
		(net 36)
	)
	(segment
		(start 191.634537 97.846558)
		(end 191.641933 97.867694)
		(width 0.1)
		(layer "F.Cu")
		(net 36)
	)
	(segment
		(start 191.041933 97.280918)
		(end 191.053846 97.261958)
		(width 0.1)
		(layer "F.Cu")
		(net 36)
	)
	(segment
		(start 191.394378 97.902489)
		(end 191.410213 97.886654)
		(width 0.1)
		(layer "F.Cu")
		(net 36)
	)
	(segment
		(start 191.43203 97.824306)
		(end 191.43203 97.324306)
		(width 0.1)
		(layer "F.Cu")
		(net 36)
	)
	(segment
		(start 191.234537 97.846558)
		(end 191.241933 97.867694)
		(width 0.1)
		(layer "F.Cu")
		(net 36)
	)
	(segment
		(start 191.629522 97.302054)
		(end 191.63203 97.324306)
		(width 0.1)
		(layer "F.Cu")
		(net 36)
	)
	(segment
		(start 191.288641 97.914402)
		(end 191.309777 97.921798)
		(width 0.1)
		(layer "F.Cu")
		(net 36)
	)
	(segment
		(start 191.653846 97.886654)
		(end 191.669681 97.902489)
		(width 0.1)
		(layer "F.Cu")
		(net 36)
	)
	(segment
		(start 191.33203 97.924306)
		(end 191.354282 97.921798)
		(width 0.1)
		(layer "F.Cu")
		(net 36)
	)
	(segment
		(start 191.222126 97.280918)
		(end 191.229522 97.302054)
		(width 0.1)
		(layer "F.Cu")
		(net 36)
	)
	(segment
		(start 192.154282 97.921798)
		(end 192.175418 97.914402)
		(width 0.1)
		(layer "F.Cu")
		(net 36)
	)
	(segment
		(start 191.775418 97.914402)
		(end 191.794378 97.902489)
		(width 0.1)
		(layer "F.Cu")
		(net 36)
	)
	(segment
		(start 177.536328 101.497157)
		(end 177.991329 101.042156)
		(width 0.1)
		(layer "F.Cu")
		(net 36)
	)
	(segment
		(start 191.810213 97.886654)
		(end 191.822126 97.867694)
		(width 0.1)
		(layer "F.Cu")
		(net 36)
	)
	(segment
		(start 192.022126 97.280918)
		(end 192.029522 97.302054)
		(width 0.1)
		(layer "F.Cu")
		(net 36)
	)
	(segment
		(start 191.575418 97.23421)
		(end 191.594378 97.246123)
		(width 0.1)
		(layer "F.Cu")
		(net 36)
	)
	(segment
		(start 192.222126 97.867694)
		(end 192.229522 97.846558)
		(width 0.1)
		(layer "F.Cu")
		(net 36)
	)
	(segment
		(start 190.775418 97.484209)
		(end 190.794378 97.496122)
		(width 0.1)
		(layer "F.Cu")
		(net 36)
	)
	(segment
		(start 191.488641 97.23421)
		(end 191.509777 97.226814)
		(width 0.1)
		(layer "F.Cu")
		(net 36)
	)
	(segment
		(start 191.83203 97.324306)
		(end 191.834537 97.302054)
		(width 0.1)
		(layer "F.Cu")
		(net 36)
	)
	(segment
		(start 197.540626 97.474306)
		(end 198.186328 98.120008)
		(width 0.1)
		(layer "F.Cu")
		(net 36)
	)
	(segment
		(start 191.154282 97.226814)
		(end 191.175418 97.23421)
		(width 0.1)
		(layer "F.Cu")
		(net 36)
	)
	(segment
		(start 192.23203 97.824306)
		(end 192.23203 97.574306)
		(width 0.1)
		(layer "F.Cu")
		(net 36)
	)
	(segment
		(start 192.03203 97.324306)
		(end 192.03203 97.824306)
		(width 0.1)
		(layer "F.Cu")
		(net 36)
	)
	(segment
		(start 192.109777 97.921798)
		(end 192.13203 97.924306)
		(width 0.1)
		(layer "F.Cu")
		(net 36)
	)
	(segment
		(start 186.318478 101.042156)
		(end 189.886328 97.474306)
		(width 0.1)
		(layer "F.Cu")
		(net 36)
	)
	(segment
		(start 191.829522 97.846558)
		(end 191.83203 97.824306)
		(width 0.1)
		(layer "F.Cu")
		(net 36)
	)
	(segment
		(start 192.029522 97.302054)
		(end 192.03203 97.324306)
		(width 0.1)
		(layer "F.Cu")
		(net 36)
	)
	(segment
		(start 191.994378 97.246123)
		(end 192.010213 97.261958)
		(width 0.1)
		(layer "F.Cu")
		(net 36)
	)
	(segment
		(start 190.888641 97.914402)
		(end 190.909777 97.921798)
		(width 0.1)
		(layer "F.Cu")
		(net 36)
	)
	(segment
		(start 191.23203 97.824306)
		(end 191.234537 97.846558)
		(width 0.1)
		(layer "F.Cu")
		(net 36)
	)
	(segment
		(start 192.229522 97.846558)
		(end 192.23203 97.824306)
		(width 0.1)
		(layer "F.Cu")
		(net 36)
	)
	(segment
		(start 190.754282 97.476813)
		(end 190.775418 97.484209)
		(width 0.1)
		(layer "F.Cu")
		(net 36)
	)
	(segment
		(start 191.429522 97.846558)
		(end 191.43203 97.824306)
		(width 0.1)
		(layer "F.Cu")
		(net 36)
	)
	(segment
		(start 191.43203 97.324306)
		(end 191.434537 97.302054)
		(width 0.1)
		(layer "F.Cu")
		(net 36)
	)
	(segment
		(start 190.975418 97.914402)
		(end 190.994378 97.902489)
		(width 0.1)
		(layer "F.Cu")
		(net 36)
	)
	(segment
		(start 192.069681 97.902489)
		(end 192.088641 97.914402)
		(width 0.1)
		(layer "F.Cu")
		(net 36)
	)
	(segment
		(start 191.253846 97.886654)
		(end 191.269681 97.902489)
		(width 0.1)
		(layer "F.Cu")
		(net 36)
	)
	(segment
		(start 192.03203 97.824306)
		(end 192.034537 97.846558)
		(width 0.1)
		(layer "F.Cu")
		(net 36)
	)
	(segment
		(start 191.410213 97.886654)
		(end 191.422126 97.867694)
		(width 0.1)
		(layer "F.Cu")
		(net 36)
	)
	(segment
		(start 191.641933 97.867694)
		(end 191.653846 97.886654)
		(width 0.1)
		(layer "F.Cu")
		(net 36)
	)
	(segment
		(start 191.210213 97.261958)
		(end 191.222126 97.280918)
		(width 0.1)
		(layer "F.Cu")
		(net 36)
	)
	(segment
		(start 191.175418 97.23421)
		(end 191.194378 97.246123)
		(width 0.1)
		(layer "F.Cu")
		(net 36)
	)
	(segment
		(start 192.088641 97.914402)
		(end 192.109777 97.921798)
		(width 0.1)
		(layer "F.Cu")
		(net 36)
	)
	(segment
		(start 190.794378 97.496122)
		(end 190.810213 97.511957)
		(width 0.1)
		(layer "F.Cu")
		(net 36)
	)
	(segment
		(start 191.109777 97.226814)
		(end 191.13203 97.224306)
		(width 0.1)
		(layer "F.Cu")
		(net 36)
	)
	(segment
		(start 191.594378 97.246123)
		(end 191.610213 97.261958)
		(width 0.1)
		(layer "F.Cu")
		(net 36)
	)
	(segment
		(start 192.210213 97.886654)
		(end 192.222126 97.867694)
		(width 0.1)
		(layer "F.Cu")
		(net 36)
	)
	(segment
		(start 192.253846 97.511957)
		(end 192.269681 97.496122)
		(width 0.1)
		(layer "F.Cu")
		(net 36)
	)
	(segment
		(start 192.33203 97.474306)
		(end 195.73203 97.474306)
		(width 0.1)
		(layer "F.Cu")
		(net 36)
	)
	(segment
		(start 191.794378 97.902489)
		(end 191.810213 97.886654)
		(width 0.1)
		(layer "F.Cu")
		(net 36)
	)
	(segment
		(start 191.309777 97.921798)
		(end 191.33203 97.924306)
		(width 0.1)
		(layer "F.Cu")
		(net 36)
	)
	(segment
		(start 191.469681 97.246123)
		(end 191.488641 97.23421)
		(width 0.1)
		(layer "F.Cu")
		(net 36)
	)
	(segment
		(start 192.241933 97.530917)
		(end 192.253846 97.511957)
		(width 0.1)
		(layer "F.Cu")
		(net 36)
	)
	(segment
		(start 192.053846 97.886654)
		(end 192.069681 97.902489)
		(width 0.1)
		(layer "F.Cu")
		(net 36)
	)
	(segment
		(start 191.73203 97.924306)
		(end 191.754282 97.921798)
		(width 0.1)
		(layer "F.Cu")
		(net 36)
	)
	(segment
		(start 190.909777 97.921798)
		(end 190.93203 97.924306)
		(width 0.1)
		(layer "F.Cu")
		(net 36)
	)
	(segment
		(start 191.03203 97.824306)
		(end 191.03203 97.324306)
		(width 0.1)
		(layer "F.Cu")
		(net 36)
	)
	(segment
		(start 191.63203 97.824306)
		(end 191.634537 97.846558)
		(width 0.1)
		(layer "F.Cu")
		(net 36)
	)
	(segment
		(start 191.83203 97.824306)
		(end 191.83203 97.324306)
		(width 0.1)
		(layer "F.Cu")
		(net 36)
	)
	(segment
		(start 190.954282 97.921798)
		(end 190.975418 97.914402)
		(width 0.1)
		(layer "F.Cu")
		(net 36)
	)
	(segment
		(start 191.441933 97.280918)
		(end 191.453846 97.261958)
		(width 0.1)
		(layer "F.Cu")
		(net 36)
	)
	(segment
		(start 190.810213 97.511957)
		(end 190.822126 97.530917)
		(width 0.1)
		(layer "F.Cu")
		(net 36)
	)
	(segment
		(start 191.03203 97.324306)
		(end 191.034537 97.302054)
		(width 0.1)
		(layer "F.Cu")
		(net 36)
	)
	(segment
		(start 191.669681 97.902489)
		(end 191.688641 97.914402)
		(width 0.1)
		(layer "F.Cu")
		(net 36)
	)
	(segment
		(start 192.309777 97.476813)
		(end 192.33203 97.474306)
		(width 0.1)
		(layer "F.Cu")
		(net 36)
	)
	(segment
		(start 191.909777 97.226814)
		(end 191.93203 97.224306)
		(width 0.1)
		(layer "F.Cu")
		(net 36)
	)
	(segment
		(start 191.93203 97.224306)
		(end 191.954282 97.226814)
		(width 0.1)
		(layer "F.Cu")
		(net 36)
	)
	(segment
		(start 190.83203 97.824306)
		(end 190.834537 97.846558)
		(width 0.1)
		(layer "F.Cu")
		(net 36)
	)
	(segment
		(start 191.422126 97.867694)
		(end 191.429522 97.846558)
		(width 0.1)
		(layer "F.Cu")
		(net 36)
	)
	(segment
		(start 191.954282 97.226814)
		(end 191.975418 97.23421)
		(width 0.1)
		(layer "F.Cu")
		(net 36)
	)
	(segment
		(start 191.841933 97.280918)
		(end 191.853846 97.261958)
		(width 0.1)
		(layer "F.Cu")
		(net 36)
	)
	(segment
		(start 190.841933 97.867694)
		(end 190.853846 97.886654)
		(width 0.1)
		(layer "F.Cu")
		(net 36)
	)
	(segment
		(start 190.822126 97.530917)
		(end 190.829522 97.552053)
		(width 0.1)
		(layer "F.Cu")
		(net 36)
	)
	(segment
		(start 190.853846 97.886654)
		(end 190.869681 97.902489)
		(width 0.1)
		(layer "F.Cu")
		(net 36)
	)
	(segment
		(start 191.269681 97.902489)
		(end 191.288641 97.914402)
		(width 0.1)
		(layer "F.Cu")
		(net 36)
	)
	(segment
		(start 190.829522 97.552053)
		(end 190.83203 97.574306)
		(width 0.1)
		(layer "F.Cu")
		(net 36)
	)
	(segment
		(start 191.010213 97.886654)
		(end 191.022126 97.867694)
		(width 0.1)
		(layer "F.Cu")
		(net 36)
	)
	(segment
		(start 190.93203 97.924306)
		(end 190.954282 97.921798)
		(width 0.1)
		(layer "F.Cu")
		(net 36)
	)
	(segment
		(start 192.234537 97.552053)
		(end 192.241933 97.530917)
		(width 0.1)
		(layer "F.Cu")
		(net 36)
	)
	(segment
		(start 191.709777 97.921798)
		(end 191.73203 97.924306)
		(width 0.1)
		(layer "F.Cu")
		(net 36)
	)
	(segment
		(start 190.73203 97.474306)
		(end 190.754282 97.476813)
		(width 0.1)
		(layer "F.Cu")
		(net 36)
	)
	(segment
		(start 192.175418 97.914402)
		(end 192.194378 97.902489)
		(width 0.1)
		(layer "F.Cu")
		(net 36)
	)
	(segment
		(start 192.23203 97.574306)
		(end 192.234537 97.552053)
		(width 0.1)
		(layer "F.Cu")
		(net 36)
	)
	(segment
		(start 191.053846 97.261958)
		(end 191.069681 97.246123)
		(width 0.1)
		(layer "F.Cu")
		(net 36)
	)
	(segment
		(start 192.288641 97.484209)
		(end 192.309777 97.476813)
		(width 0.1)
		(layer "F.Cu")
		(net 36)
	)
	(segment
		(start 191.869681 97.246123)
		(end 191.888641 97.23421)
		(width 0.1)
		(layer "F.Cu")
		(net 36)
	)
	(segment
		(start 191.888641 97.23421)
		(end 191.909777 97.226814)
		(width 0.1)
		(layer "F.Cu")
		(net 36)
	)
	(segment
		(start 191.034537 97.302054)
		(end 191.041933 97.280918)
		(width 0.1)
		(layer "F.Cu")
		(net 36)
	)
	(segment
		(start 191.229522 97.302054)
		(end 191.23203 97.324306)
		(width 0.1)
		(layer "F.Cu")
		(net 36)
	)
	(segment
		(start 190.869681 97.902489)
		(end 190.888641 97.914402)
		(width 0.1)
		(layer "F.Cu")
		(net 36)
	)
	(segment
		(start 191.834537 97.302054)
		(end 191.841933 97.280918)
		(width 0.1)
		(layer "F.Cu")
		(net 36)
	)
	(segment
		(start 191.241933 97.867694)
		(end 191.253846 97.886654)
		(width 0.1)
		(layer "F.Cu")
		(net 36)
	)
	(segment
		(start 191.029522 97.846558)
		(end 191.03203 97.824306)
		(width 0.1)
		(layer "F.Cu")
		(net 36)
	)
	(segment
		(start 191.822126 97.867694)
		(end 191.829522 97.846558)
		(width 0.1)
		(layer "F.Cu")
		(net 36)
	)
	(segment
		(start 191.13203 97.224306)
		(end 191.154282 97.226814)
		(width 0.1)
		(layer "F.Cu")
		(net 36)
	)
	(segment
		(start 191.434537 97.302054)
		(end 191.441933 97.280918)
		(width 0.1)
		(layer "F.Cu")
		(net 36)
	)
	(segment
		(start 191.554282 97.226814)
		(end 191.575418 97.23421)
		(width 0.1)
		(layer "F.Cu")
		(net 36)
	)
	(segment
		(start 191.63203 97.324306)
		(end 191.63203 97.824306)
		(width 0.1)
		(layer "F.Cu")
		(net 36)
	)
	(segment
		(start 190.834537 97.846558)
		(end 190.841933 97.867694)
		(width 0.1)
		(layer "F.Cu")
		(net 36)
	)
	(segment
		(start 191.194378 97.246123)
		(end 191.210213 97.261958)
		(width 0.1)
		(layer "F.Cu")
		(net 36)
	)
	(segment
		(start 191.610213 97.261958)
		(end 191.622126 97.280918)
		(width 0.1)
		(layer "F.Cu")
		(net 36)
	)
	(segment
		(start 192.010213 97.261958)
		(end 192.022126 97.280918)
		(width 0.1)
		(layer "F.Cu")
		(net 36)
	)
	(segment
		(start 191.453846 97.261958)
		(end 191.469681 97.246123)
		(width 0.1)
		(layer "F.Cu")
		(net 36)
	)
	(segment
		(start 191.975418 97.23421)
		(end 191.994378 97.246123)
		(width 0.1)
		(layer "F.Cu")
		(net 36)
	)
	(segment
		(start 191.509777 97.226814)
		(end 191.53203 97.224306)
		(width 0.1)
		(layer "F.Cu")
		(net 36)
	)
	(segment
		(start 191.688641 97.914402)
		(end 191.709777 97.921798)
		(width 0.1)
		(layer "F.Cu")
		(net 36)
	)
	(segment
		(start 177.991329 101.042156)
		(end 186.318478 101.042156)
		(width 0.1)
		(layer "F.Cu")
		(net 36)
	)
	(segment
		(start 192.034537 97.846558)
		(end 192.041933 97.867694)
		(width 0.1)
		(layer "F.Cu")
		(net 36)
	)
	(segment
		(start 198.186328 98.120008)
		(end 198.186328 99.620008)
		(width 0.1)
		(layer "F.Cu")
		(net 36)
	)
	(segment
		(start 190.83203 97.574306)
		(end 190.83203 97.824306)
		(width 0.1)
		(layer "F.Cu")
		(net 36)
	)
	(segment
		(start 191.088641 97.23421)
		(end 191.109777 97.226814)
		(width 0.1)
		(layer "F.Cu")
		(net 36)
	)
	(segment
		(start 191.622126 97.280918)
		(end 191.629522 97.302054)
		(width 0.1)
		(layer "F.Cu")
		(net 36)
	)
	(segment
		(start 192.194378 97.902489)
		(end 192.210213 97.886654)
		(width 0.1)
		(layer "F.Cu")
		(net 36)
	)
	(segment
		(start 191.53203 97.224306)
		(end 191.554282 97.226814)
		(width 0.1)
		(layer "F.Cu")
		(net 36)
	)
	(segment
		(start 191.23203 97.324306)
		(end 191.23203 97.824306)
		(width 0.1)
		(layer "F.Cu")
		(net 36)
	)
	(via
		(at 195.73203 97.474306)
		(size 0.5)
		(drill 0.2)
		(layers "F.Cu" "B.Cu")
		(net 36)
	)
	(segment
		(start 195.686328 96.705008)
		(end 195.686328 97.424306)
		(width 0.2)
		(layer "B.Cu")
		(net 36)
	)
	(segment
		(start 195.731328 97.475008)
		(end 195.73203 97.474306)
		(width 0.2)
		(layer "B.Cu")
		(net 36)
	)
	(segment
		(start 195.731328 98.210008)
		(end 195.731328 97.475008)
		(width 0.2)
		(layer "B.Cu")
		(net 36)
	)
	(segment
		(start 189.271464 95.424294)
		(end 189.308921 95.411188)
		(width 0.1)
		(layer "F.Cu")
		(net 37)
	)
	(segment
		(start 188.875969 95.390075)
		(end 188.90957 95.411188)
		(width 0.1)
		(layer "F.Cu")
		(net 37)
	)
	(segment
		(start 189.391696 95.328413)
		(end 189.404802 95.290956)
		(width 0.1)
		(layer "F.Cu")
		(net 37)
	)
	(segment
		(start 188.826795 95.328413)
		(end 188.847908 95.362014)
		(width 0.1)
		(layer "F.Cu")
		(net 37)
	)
	(segment
		(start 189.342522 95.390075)
		(end 189.370583 95.362014)
		(width 0.1)
		(layer "F.Cu")
		(net 37)
	)
	(segment
		(start 189.404802 95.290956)
		(end 189.413689 95.212087)
		(width 0.1)
		(layer "F.Cu")
		(net 37)
	)
	(segment
		(start 188.947027 95.424294)
		(end 188.986462 95.428738)
		(width 0.1)
		(layer "F.Cu")
		(net 37)
	)
	(segment
		(start 188.708921 95.091855)
		(end 188.742522 95.112968)
		(width 0.1)
		(layer "F.Cu")
		(net 37)
	)
	(segment
		(start 189.50957 95.091855)
		(end 189.547027 95.078749)
		(width 0.1)
		(layer "F.Cu")
		(net 37)
	)
	(segment
		(start 188.742522 95.112968)
		(end 188.770583 95.141029)
		(width 0.1)
		(layer "F.Cu")
		(net 37)
	)
	(segment
		(start 188.770583 95.141029)
		(end 188.791696 95.17463)
		(width 0.1)
		(layer "F.Cu")
		(net 37)
	)
	(segment
		(start 179.036328 98.997157)
		(end 184.163477 98.997157)
		(width 0.1)
		(layer "F.Cu")
		(net 37)
	)
	(segment
		(start 189.413689 95.212087)
		(end 189.426795 95.17463)
		(width 0.1)
		(layer "F.Cu")
		(net 37)
	)
	(segment
		(start 188.63203 95.074306)
		(end 188.671464 95.078749)
		(width 0.1)
		(layer "F.Cu")
		(net 37)
	)
	(segment
		(start 188.90957 95.411188)
		(end 188.947027 95.424294)
		(width 0.1)
		(layer "F.Cu")
		(net 37)
	)
	(segment
		(start 188.086328 95.074306)
		(end 188.63203 95.074306)
		(width 0.1)
		(layer "F.Cu")
		(net 37)
	)
	(segment
		(start 188.671464 95.078749)
		(end 188.708921 95.091855)
		(width 0.1)
		(layer "F.Cu")
		(net 37)
	)
	(segment
		(start 188.804802 95.212087)
		(end 188.813689 95.290956)
		(width 0.1)
		(layer "F.Cu")
		(net 37)
	)
	(segment
		(start 189.447908 95.141029)
		(end 189.475969 95.112968)
		(width 0.1)
		(layer "F.Cu")
		(net 37)
	)
	(segment
		(start 184.163477 98.997157)
		(end 188.086328 95.074306)
		(width 0.1)
		(layer "F.Cu")
		(net 37)
	)
	(segment
		(start 188.847908 95.362014)
		(end 188.875969 95.390075)
		(width 0.1)
		(layer "F.Cu")
		(net 37)
	)
	(segment
		(start 178.536328 99.497157)
		(end 179.036328 98.997157)
		(width 0.1)
		(layer "F.Cu")
		(net 37)
	)
	(segment
		(start 189.475969 95.112968)
		(end 189.50957 95.091855)
		(width 0.1)
		(layer "F.Cu")
		(net 37)
	)
	(segment
		(start 189.23203 95.428738)
		(end 189.271464 95.424294)
		(width 0.1)
		(layer "F.Cu")
		(net 37)
	)
	(segment
		(start 188.791696 95.17463)
		(end 188.804802 95.212087)
		(width 0.1)
		(layer "F.Cu")
		(net 37)
	)
	(segment
		(start 189.308921 95.411188)
		(end 189.342522 95.390075)
		(width 0.1)
		(layer "F.Cu")
		(net 37)
	)
	(segment
		(start 189.370583 95.362014)
		(end 189.391696 95.328413)
		(width 0.1)
		(layer "F.Cu")
		(net 37)
	)
	(segment
		(start 188.813689 95.290956)
		(end 188.826795 95.328413)
		(width 0.1)
		(layer "F.Cu")
		(net 37)
	)
	(segment
		(start 199.386328 95.074306)
		(end 201.686328 97.374306)
		(width 0.1)
		(layer "F.Cu")
		(net 37)
	)
	(segment
		(start 189.586462 95.074306)
		(end 199.386328 95.074306)
		(width 0.1)
		(layer "F.Cu")
		(net 37)
	)
	(segment
		(start 189.426795 95.17463)
		(end 189.447908 95.141029)
		(width 0.1)
		(layer "F.Cu")
		(net 37)
	)
	(segment
		(start 188.986462 95.428738)
		(end 189.23203 95.428738)
		(width 0.1)
		(layer "F.Cu")
		(net 37)
	)
	(segment
		(start 189.547027 95.078749)
		(end 189.586462 95.074306)
		(width 0.1)
		(layer "F.Cu")
		(net 37)
	)
	(segment
		(start 201.686328 97.374306)
		(end 201.686328 99.620008)
		(width 0.1)
		(layer "F.Cu")
		(net 37)
	)
	(via
		(at 197.686328 95.120008)
		(size 0.5)
		(drill 0.2)
		(layers "F.Cu" "B.Cu")
		(net 37)
	)
	(segment
		(start 197.686328 95.795008)
		(end 197.686328 95.120008)
		(width 0.2)
		(layer "B.Cu")
		(net 37)
	)
	(segment
		(start 197.686328 94.505008)
		(end 197.686328 95.120008)
		(width 0.2)
		(layer "B.Cu")
		(net 37)
	)
	(segment
		(start 174.036328 109.297157)
		(end 174.036328 112.270008)
		(width 0.2)
		(layer "F.Cu")
		(net 38)
	)
	(segment
		(start 174.036328 112.270008)
		(end 174.736328 112.970008)
		(width 0.2)
		(layer "F.Cu")
		(net 38)
	)
	(segment
		(start 174.736328 112.970008)
		(end 176.216328 112.970008)
		(width 0.2)
		(layer "F.Cu")
		(net 38)
	)
	(segment
		(start 169.536329 103.497158)
		(end 169.036329 103.997158)
		(width 0.15)
		(layer "F.Cu")
		(net 38)
	)
	(via
		(at 169.036329 103.997158)
		(size 0.5)
		(drill 0.2)
		(layers "F.Cu" "B.Cu")
		(net 38)
	)
	(via
		(at 174.036328 109.297157)
		(size 0.5)
		(drill 0.2)
		(layers "F.Cu" "B.Cu")
		(net 38)
	)
	(segment
		(start 169.036329 108.097158)
		(end 170.236328 109.297157)
		(width 0.15)
		(layer "In5.Cu")
		(net 38)
	)
	(segment
		(start 170.236328 109.297157)
		(end 174.036328 109.297157)
		(width 0.15)
		(layer "In5.Cu")
		(net 38)
	)
	(segment
		(start 169.036329 103.997158)
		(end 169.036329 108.097158)
		(width 0.15)
		(layer "In5.Cu")
		(net 38)
	)
	(segment
		(start 111.121328 117.097157)
		(end 110.771328 116.747157)
		(width 0.3)
		(layer "F.Cu")
		(net 39)
	)
	(segment
		(start 112.286328 117.097157)
		(end 111.121328 117.097157)
		(width 0.3)
		(layer "F.Cu")
		(net 39)
	)
	(segment
		(start 116.575829 117.097157)
		(end 117.438672 117.96)
		(width 0.2)
		(layer "F.Cu")
		(net 40)
	)
	(segment
		(start 116.286328 117.097157)
		(end 116.575829 117.097157)
		(width 0.2)
		(layer "F.Cu")
		(net 40)
	)
	(segment
		(start 118.415 117.975)
		(end 117.453672 117.975)
		(width 0.2)
		(layer "F.Cu")
		(net 40)
	)
	(segment
		(start 117.453672 117.975)
		(end 117.438672 117.96)
		(width 0.2)
		(layer "F.Cu")
		(net 40)
	)
	(segment
		(start 119.385 116.975)
		(end 119.385 117.975)
		(width 0.2)
		(layer "F.Cu")
		(net 41)
	)
	(segment
		(start 115.885 113.747157)
		(end 117.247157 113.747157)
		(width 0.2)
		(layer "F.Cu")
		(net 42)
	)
	(segment
		(start 117.247157 113.747157)
		(end 118.375 114.875)
		(width 0.2)
		(layer "F.Cu")
		(net 42)
	)
	(segment
		(start 113.1 114.175)
		(end 114.487157 114.175)
		(width 0.15)
		(layer "F.Cu")
		(net 43)
	)
	(segment
		(start 112.577843 114.697157)
		(end 113.1 114.175)
		(width 0.15)
		(layer "F.Cu")
		(net 43)
	)
	(segment
		(start 112.286328 114.697157)
		(end 112.577843 114.697157)
		(width 0.15)
		(layer "F.Cu")
		(net 43)
	)
	(segment
		(start 114.487157 114.175)
		(end 114.915 113.747157)
		(width 0.15)
		(layer "F.Cu")
		(net 43)
	)
	(segment
		(start 165.536328 105.497157)
		(end 166.036328 105.997157)
		(width 0.14)
		(layer "F.Cu")
		(net 44)
	)
	(segment
		(start 163.627962 107.617513)
		(end 163.610687 107.645006)
		(width 0.14)
		(layer "F.Cu")
		(net 44)
	)
	(segment
		(start 163.585579 108.191696)
		(end 163.553872 108.282309)
		(width 0.14)
		(layer "F.Cu")
		(net 44)
	)
	(segment
		(start 163.650921 107.594554)
		(end 163.627962 107.617513)
		(width 0.14)
		(layer "F.Cu")
		(net 44)
	)
	(segment
		(start 163.886328 108.096299)
		(end 163.886328 107.70792)
		(width 0.14)
		(layer "F.Cu")
		(net 44)
	)
	(segment
		(start 163.886328 107.70792)
		(end 163.882692 107.675654)
		(width 0.14)
		(layer "F.Cu")
		(net 44)
	)
	(segment
		(start 164.700532 108.525008)
		(end 164.315036 108.525008)
		(width 0.14)
		(layer "F.Cu")
		(net 44)
	)
	(segment
		(start 166.036328 105.997157)
		(end 166.036328 107.189212)
		(width 0.14)
		(layer "F.Cu")
		(net 44)
	)
	(segment
		(start 163.773593 107.566555)
		(end 163.741328 107.56292)
		(width 0.14)
		(layer "F.Cu")
		(net 44)
	)
	(segment
		(start 163.596328 108.096299)
		(end 163.585579 108.191696)
		(width 0.14)
		(layer "F.Cu")
		(net 44)
	)
	(segment
		(start 164.315036 108.525008)
		(end 164.219639 108.514259)
		(width 0.14)
		(layer "F.Cu")
		(net 44)
	)
	(segment
		(start 155.084 111.92268)
		(end 155.084 112.65)
		(width 0.14)
		(layer "F.Cu")
		(net 44)
	)
	(segment
		(start 163.599963 107.675654)
		(end 163.596328 107.70792)
		(width 0.14)
		(layer "F.Cu")
		(net 44)
	)
	(segment
		(start 166.036328 107.189212)
		(end 164.700532 108.525008)
		(width 0.14)
		(layer "F.Cu")
		(net 44)
	)
	(segment
		(start 163.596328 107.70792)
		(end 163.596328 108.096299)
		(width 0.14)
		(layer "F.Cu")
		(net 44)
	)
	(segment
		(start 163.502797 108.363594)
		(end 163.434914 108.431477)
		(width 0.14)
		(layer "F.Cu")
		(net 44)
	)
	(segment
		(start 163.804241 107.577279)
		(end 163.773593 107.566555)
		(width 0.14)
		(layer "F.Cu")
		(net 44)
	)
	(segment
		(start 163.928783 108.282309)
		(end 163.897076 108.191696)
		(width 0.14)
		(layer "F.Cu")
		(net 44)
	)
	(segment
		(start 163.831734 107.594554)
		(end 163.804241 107.577279)
		(width 0.14)
		(layer "F.Cu")
		(net 44)
	)
	(segment
		(start 154.731328 109.304212)
		(end 154.731328 111.570008)
		(width 0.14)
		(layer "F.Cu")
		(net 44)
	)
	(segment
		(start 164.219639 108.514259)
		(end 164.129026 108.482552)
		(width 0.14)
		(layer "F.Cu")
		(net 44)
	)
	(segment
		(start 163.709062 107.566555)
		(end 163.678414 107.577279)
		(width 0.14)
		(layer "F.Cu")
		(net 44)
	)
	(segment
		(start 163.897076 108.191696)
		(end 163.886328 108.096299)
		(width 0.14)
		(layer "F.Cu")
		(net 44)
	)
	(segment
		(start 163.979858 108.363594)
		(end 163.928783 108.282309)
		(width 0.14)
		(layer "F.Cu")
		(net 44)
	)
	(segment
		(start 154.731328 111.570008)
		(end 155.084 111.92268)
		(width 0.14)
		(layer "F.Cu")
		(net 44)
	)
	(segment
		(start 163.882692 107.675654)
		(end 163.871968 107.645006)
		(width 0.14)
		(layer "F.Cu")
		(net 44)
	)
	(segment
		(start 163.871968 107.645006)
		(end 163.854693 107.617513)
		(width 0.14)
		(layer "F.Cu")
		(net 44)
	)
	(segment
		(start 163.678414 107.577279)
		(end 163.650921 107.594554)
		(width 0.14)
		(layer "F.Cu")
		(net 44)
	)
	(segment
		(start 164.129026 108.482552)
		(end 164.047741 108.431477)
		(width 0.14)
		(layer "F.Cu")
		(net 44)
	)
	(segment
		(start 163.854693 107.617513)
		(end 163.831734 107.594554)
		(width 0.14)
		(layer "F.Cu")
		(net 44)
	)
	(segment
		(start 163.610687 107.645006)
		(end 163.599963 107.675654)
		(width 0.14)
		(layer "F.Cu")
		(net 44)
	)
	(segment
		(start 163.167619 108.525008)
		(end 155.510532 108.525008)
		(width 0.14)
		(layer "F.Cu")
		(net 44)
	)
	(segment
		(start 163.741328 107.56292)
		(end 163.709062 107.566555)
		(width 0.14)
		(layer "F.Cu")
		(net 44)
	)
	(segment
		(start 155.510532 108.525008)
		(end 154.731328 109.304212)
		(width 0.14)
		(layer "F.Cu")
		(net 44)
	)
	(segment
		(start 163.353629 108.482552)
		(end 163.263016 108.514259)
		(width 0.14)
		(layer "F.Cu")
		(net 44)
	)
	(segment
		(start 163.434914 108.431477)
		(end 163.353629 108.482552)
		(width 0.14)
		(layer "F.Cu")
		(net 44)
	)
	(segment
		(start 163.263016 108.514259)
		(end 163.167619 108.525008)
		(width 0.14)
		(layer "F.Cu")
		(net 44)
	)
	(segment
		(start 164.047741 108.431477)
		(end 163.979858 108.363594)
		(width 0.14)
		(layer "F.Cu")
		(net 44)
	)
	(segment
		(start 163.553872 108.282309)
		(end 163.502797 108.363594)
		(width 0.14)
		(layer "F.Cu")
		(net 44)
	)
	(segment
		(start 164.250921 108.183373)
		(end 164.227962 108.160414)
		(width 0.14)
		(layer "F.Cu")
		(net 45)
	)
	(segment
		(start 164.572124 108.215008)
		(end 164.341328 108.215008)
		(width 0.14)
		(layer "F.Cu")
		(net 45)
	)
	(segment
		(start 163.297076 107.586231)
		(end 163.286328 107.681628)
		(width 0.14)
		(layer "F.Cu")
		(net 45)
	)
	(segment
		(start 163.282692 108.102273)
		(end 163.271968 108.132921)
		(width 0.14)
		(layer "F.Cu")
		(net 45)
	)
	(segment
		(start 163.204241 108.200648)
		(end 163.173593 108.211372)
		(width 0.14)
		(layer "F.Cu")
		(net 45)
	)
	(segment
		(start 154.421328 109.175804)
		(end 154.421328 109.528672)
		(width 0.14)
		(layer "F.Cu")
		(net 45)
	)
	(segment
		(start 163.141328 108.215008)
		(end 155.382124 108.215008)
		(width 0.14)
		(layer "F.Cu")
		(net 45)
	)
	(segment
		(start 164.341328 108.215008)
		(end 164.309062 108.211372)
		(width 0.14)
		(layer "F.Cu")
		(net 45)
	)
	(segment
		(start 164.196328 107.681628)
		(end 164.185579 107.586231)
		(width 0.14)
		(layer "F.Cu")
		(net 45)
	)
	(segment
		(start 154.421328 110.978672)
		(end 154.421328 111.570008)
		(width 0.14)
		(layer "F.Cu")
		(net 45)
	)
	(segment
		(start 164.153872 107.495618)
		(end 164.102797 107.414333)
		(width 0.14)
		(layer "F.Cu")
		(net 45)
	)
	(segment
		(start 164.102797 107.414333)
		(end 164.034914 107.34645)
		(width 0.14)
		(layer "F.Cu")
		(net 45)
	)
	(segment
		(start 163.767619 107.25292)
		(end 163.715036 107.25292)
		(width 0.14)
		(layer "F.Cu")
		(net 45)
	)
	(segment
		(start 163.286328 108.070008)
		(end 163.282692 108.102273)
		(width 0.14)
		(layer "F.Cu")
		(net 45)
	)
	(segment
		(start 155.382124 108.215008)
		(end 154.421328 109.175804)
		(width 0.14)
		(layer "F.Cu")
		(net 45)
	)
	(segment
		(start 163.254693 108.160414)
		(end 163.231734 108.183373)
		(width 0.14)
		(layer "F.Cu")
		(net 45)
	)
	(segment
		(start 154.421328 110.928672)
		(end 154.421328 110.978672)
		(width 0.14)
		(layer "F.Cu")
		(net 45)
	)
	(segment
		(start 164.034914 107.34645)
		(end 163.953629 107.295375)
		(width 0.14)
		(layer "F.Cu")
		(net 45)
	)
	(segment
		(start 154.059 111.932336)
		(end 154.059 112.65)
		(width 0.14)
		(layer "F.Cu")
		(net 45)
	)
	(segment
		(start 164.278414 108.200648)
		(end 164.250921 108.183373)
		(width 0.14)
		(layer "F.Cu")
		(net 45)
	)
	(segment
		(start 154.246328 109.703672)
		(end 154.125698 109.703672)
		(width 0.14)
		(layer "F.Cu")
		(net 45)
	)
	(segment
		(start 154.125698 110.053672)
		(end 154.246328 110.053672)
		(width 0.14)
		(layer "F.Cu")
		(net 45)
	)
	(segment
		(start 164.199963 108.102273)
		(end 164.196328 108.070008)
		(width 0.14)
		(layer "F.Cu")
		(net 45)
	)
	(segment
		(start 163.529026 107.295375)
		(end 163.447741 107.34645)
		(width 0.14)
		(layer "F.Cu")
		(net 45)
	)
	(segment
		(start 163.173593 108.211372)
		(end 163.141328 108.215008)
		(width 0.14)
		(layer "F.Cu")
		(net 45)
	)
	(segment
		(start 163.619639 107.263668)
		(end 163.529026 107.295375)
		(width 0.14)
		(layer "F.Cu")
		(net 45)
	)
	(segment
		(start 154.246328 110.403672)
		(end 154.125698 110.403672)
		(width 0.14)
		(layer "F.Cu")
		(net 45)
	)
	(segment
		(start 163.231734 108.183373)
		(end 163.204241 108.200648)
		(width 0.14)
		(layer "F.Cu")
		(net 45)
	)
	(segment
		(start 154.125698 110.753672)
		(end 154.246328 110.753672)
		(width 0.14)
		(layer "F.Cu")
		(net 45)
	)
	(segment
		(start 164.185579 107.586231)
		(end 164.153872 107.495618)
		(width 0.14)
		(layer "F.Cu")
		(net 45)
	)
	(segment
		(start 165.536328 106.497157)
		(end 165.536328 107.250804)
		(width 0.14)
		(layer "F.Cu")
		(net 45)
	)
	(segment
		(start 164.309062 108.211372)
		(end 164.278414 108.200648)
		(width 0.14)
		(layer "F.Cu")
		(net 45)
	)
	(segment
		(start 164.196328 108.070008)
		(end 164.196328 107.681628)
		(width 0.14)
		(layer "F.Cu")
		(net 45)
	)
	(segment
		(start 165.536328 107.250804)
		(end 164.572124 108.215008)
		(width 0.14)
		(layer "F.Cu")
		(net 45)
	)
	(segment
		(start 163.863016 107.263668)
		(end 163.767619 107.25292)
		(width 0.14)
		(layer "F.Cu")
		(net 45)
	)
	(segment
		(start 154.421328 111.570008)
		(end 154.059 111.932336)
		(width 0.14)
		(layer "F.Cu")
		(net 45)
	)
	(segment
		(start 163.447741 107.34645)
		(end 163.379858 107.414333)
		(width 0.14)
		(layer "F.Cu")
		(net 45)
	)
	(segment
		(start 163.715036 107.25292)
		(end 163.619639 107.263668)
		(width 0.14)
		(layer "F.Cu")
		(net 45)
	)
	(segment
		(start 163.271968 108.132921)
		(end 163.254693 108.160414)
		(width 0.14)
		(layer "F.Cu")
		(net 45)
	)
	(segment
		(start 164.227962 108.160414)
		(end 164.210687 108.132921)
		(width 0.14)
		(layer "F.Cu")
		(net 45)
	)
	(segment
		(start 163.328783 107.495618)
		(end 163.297076 107.586231)
		(width 0.14)
		(layer "F.Cu")
		(net 45)
	)
	(segment
		(start 164.210687 108.132921)
		(end 164.199963 108.102273)
		(width 0.14)
		(layer "F.Cu")
		(net 45)
	)
	(segment
		(start 163.286328 107.681628)
		(end 163.286328 108.070008)
		(width 0.14)
		(layer "F.Cu")
		(net 45)
	)
	(segment
		(start 163.953629 107.295375)
		(end 163.863016 107.263668)
		(width 0.14)
		(layer "F.Cu")
		(net 45)
	)
	(segment
		(start 163.379858 107.414333)
		(end 163.328783 107.495618)
		(width 0.14)
		(layer "F.Cu")
		(net 45)
	)
	(arc
		(start 154.125698 109.703672)
		(mid 154.001954 109.754928)
		(end 153.950698 109.878672)
		(width 0.14)
		(layer "F.Cu")
		(net 45)
	)
	(arc
		(start 154.421328 109.528672)
		(mid 154.370072 109.652416)
		(end 154.246328 109.703672)
		(width 0.14)
		(layer "F.Cu")
		(net 45)
	)
	(arc
		(start 153.950698 110.578672)
		(mid 154.001954 110.702416)
		(end 154.125698 110.753672)
		(width 0.14)
		(layer "F.Cu")
		(net 45)
	)
	(arc
		(start 154.246328 110.753672)
		(mid 154.370072 110.804928)
		(end 154.421328 110.928672)
		(width 0.14)
		(layer "F.Cu")
		(net 45)
	)
	(arc
		(start 154.421328 110.228672)
		(mid 154.370072 110.352416)
		(end 154.246328 110.403672)
		(width 0.14)
		(layer "F.Cu")
		(net 45)
	)
	(arc
		(start 154.246328 110.053672)
		(mid 154.370072 110.104928)
		(end 154.421328 110.228672)
		(width 0.14)
		(layer "F.Cu")
		(net 45)
	)
	(arc
		(start 154.125698 110.403672)
		(mid 154.001954 110.454928)
		(end 153.950698 110.578672)
		(width 0.14)
		(layer "F.Cu")
		(net 45)
	)
	(arc
		(start 153.950698 109.878672)
		(mid 154.001954 110.002416)
		(end 154.125698 110.053672)
		(width 0.14)
		(layer "F.Cu")
		(net 45)
	)
	(segment
		(start 166.846328 106.823554)
		(end 166.986328 106.683554)
		(width 0.14)
		(layer "F.Cu")
		(net 46)
	)
	(segment
		(start 166.453838 108.405777)
		(end 166.695484 108.647423)
		(width 0.14)
		(layer "F.Cu")
		(net 46)
	)
	(segment
		(start 166.986328 106.683554)
		(end 166.986328 106.31076)
		(width 0.14)
		(layer "F.Cu")
		(net 46)
	)
	(segment
		(start 166.45384 108.165362)
		(end 166.846328 107.772876)
		(width 0.14)
		(layer "F.Cu")
		(net 46)
	)
	(segment
		(start 166.846328 106.17076)
		(end 166.846328 105.807157)
		(width 0.14)
		(layer "F.Cu")
		(net 46)
	)
	(segment
		(start 166.986328 106.31076)
		(end 166.846328 106.17076)
		(width 0.14)
		(layer "F.Cu")
		(net 46)
	)
	(segment
		(start 156.241328 110.404212)
		(end 156.94054 109.705)
		(width 0.14)
		(layer "F.Cu")
		(net 46)
	)
	(segment
		(start 166.846328 107.772876)
		(end 166.846328 106.823554)
		(width 0.14)
		(layer "F.Cu")
		(net 46)
	)
	(segment
		(start 166.453838 108.165361)
		(end 166.45384 108.165362)
		(width 0.14)
		(layer "F.Cu")
		(net 46)
	)
	(segment
		(start 156.584 114.60768)
		(end 156.241328 114.265008)
		(width 0.14)
		(layer "F.Cu")
		(net 46)
	)
	(segment
		(start 165.775017 109.084601)
		(end 166.016662 109.326246)
		(width 0.14)
		(layer "F.Cu")
		(net 46)
	)
	(segment
		(start 156.94054 109.705)
		(end 164.914204 109.705)
		(width 0.14)
		(layer "F.Cu")
		(net 46)
	)
	(segment
		(start 156.241328 114.265008)
		(end 156.241328 110.404212)
		(width 0.14)
		(layer "F.Cu")
		(net 46)
	)
	(segment
		(start 164.914204 109.705)
		(end 165.534601 109.084601)
		(width 0.14)
		(layer "F.Cu")
		(net 46)
	)
	(segment
		(start 156.584 114.865)
		(end 156.584 114.60768)
		(width 0.14)
		(layer "F.Cu")
		(net 46)
	)
	(segment
		(start 166.846328 105.807157)
		(end 166.536328 105.497157)
		(width 0.14)
		(layer "F.Cu")
		(net 46)
	)
	(arc
		(start 166.453838 108.405777)
		(mid 166.404046 108.285569)
		(end 166.453838 108.165361)
		(width 0.14)
		(layer "F.Cu")
		(net 46)
	)
	(arc
		(start 166.016662 109.326246)
		(mid 166.356073 109.466835)
		(end 166.695484 109.326246)
		(width 0.14)
		(layer "F.Cu")
		(net 46)
	)
	(arc
		(start 165.534601 109.084601)
		(mid 165.654809 109.034809)
		(end 165.775017 109.084601)
		(width 0.14)
		(layer "F.Cu")
		(net 46)
	)
	(arc
		(start 166.695484 109.326246)
		(mid 166.836073 108.986834)
		(end 166.695484 108.647422)
		(width 0.14)
		(layer "F.Cu")
		(net 46)
	)
	(segment
		(start 155.931328 110.275804)
		(end 155.931328 110.481328)
		(width 0.14)
		(layer "F.Cu")
		(net 47)
	)
	(segment
		(start 164.785796 109.395)
		(end 156.812132 109.395)
		(width 0.14)
		(layer "F.Cu")
		(net 47)
	)
	(segment
		(start 155.756328 111.356328)
		(end 155.646263 111.356328)
		(width 0.14)
		(layer "F.Cu")
		(net 47)
	)
	(segment
		(start 155.646263 111.006328)
		(end 155.756328 111.006328)
		(width 0.14)
		(layer "F.Cu")
		(net 47)
	)
	(segment
		(start 166.234637 107.946159)
		(end 166.234635 107.946158)
		(width 0.14)
		(layer "F.Cu")
		(net 47)
	)
	(segment
		(start 155.756328 110.656328)
		(end 155.646263 110.656328)
		(width 0.14)
		(layer "F.Cu")
		(net 47)
	)
	(segment
		(start 166.234635 108.62498)
		(end 166.476281 108.866626)
		(width 0.14)
		(layer "F.Cu")
		(net 47)
	)
	(segment
		(start 155.931328 114.265008)
		(end 155.559 114.637336)
		(width 0.14)
		(layer "F.Cu")
		(net 47)
	)
	(segment
		(start 166.536328 107.644468)
		(end 166.234637 107.946159)
		(width 0.14)
		(layer "F.Cu")
		(net 47)
	)
	(segment
		(start 155.559 114.637336)
		(end 155.559 114.865)
		(width 0.14)
		(layer "F.Cu")
		(net 47)
	)
	(segment
		(start 166.536328 106.497157)
		(end 166.536328 107.644468)
		(width 0.14)
		(layer "F.Cu")
		(net 47)
	)
	(segment
		(start 166.235865 109.107043)
		(end 165.99422 108.865398)
		(width 0.14)
		(layer "F.Cu")
		(net 47)
	)
	(segment
		(start 155.931328 111.881328)
		(end 155.931328 114.265008)
		(width 0.14)
		(layer "F.Cu")
		(net 47)
	)
	(segment
		(start 155.646263 111.706328)
		(end 155.756328 111.706328)
		(width 0.14)
		(layer "F.Cu")
		(net 47)
	)
	(segment
		(start 156.812132 109.395)
		(end 155.931328 110.275804)
		(width 0.14)
		(layer "F.Cu")
		(net 47)
	)
	(segment
		(start 165.315398 108.865398)
		(end 164.785796 109.395)
		(width 0.14)
		(layer "F.Cu")
		(net 47)
	)
	(arc
		(start 155.756328 111.006328)
		(mid 155.880072 111.057584)
		(end 155.931328 111.181328)
		(width 0.14)
		(layer "F.Cu")
		(net 47)
	)
	(arc
		(start 155.471263 111.531328)
		(mid 155.522519 111.655072)
		(end 155.646263 111.706328)
		(width 0.14)
		(layer "F.Cu")
		(net 47)
	)
	(arc
		(start 166.476281 108.866625)
		(mid 166.526073 108.986834)
		(end 166.476281 109.107043)
		(width 0.14)
		(layer "F.Cu")
		(net 47)
	)
	(arc
		(start 155.471263 110.831328)
		(mid 155.522519 110.955072)
		(end 155.646263 111.006328)
		(width 0.14)
		(layer "F.Cu")
		(net 47)
	)
	(arc
		(start 165.99422 108.865398)
		(mid 165.654809 108.724809)
		(end 165.315398 108.865398)
		(width 0.14)
		(layer "F.Cu")
		(net 47)
	)
	(arc
		(start 155.931328 111.181328)
		(mid 155.880072 111.305072)
		(end 155.756328 111.356328)
		(width 0.14)
		(layer "F.Cu")
		(net 47)
	)
	(arc
		(start 166.234635 107.946158)
		(mid 166.094046 108.285569)
		(end 166.234635 108.62498)
		(width 0.14)
		(layer "F.Cu")
		(net 47)
	)
	(arc
		(start 155.646263 111.356328)
		(mid 155.522519 111.407584)
		(end 155.471263 111.531328)
		(width 0.14)
		(layer "F.Cu")
		(net 47)
	)
	(arc
		(start 155.931328 110.481328)
		(mid 155.880072 110.605072)
		(end 155.756328 110.656328)
		(width 0.14)
		(layer "F.Cu")
		(net 47)
	)
	(arc
		(start 155.756328 111.706328)
		(mid 155.880072 111.757584)
		(end 155.931328 111.881328)
		(width 0.14)
		(layer "F.Cu")
		(net 47)
	)
	(arc
		(start 166.476281 109.107043)
		(mid 166.356073 109.156835)
		(end 166.235865 109.107043)
		(width 0.14)
		(layer "F.Cu")
		(net 47)
	)
	(arc
		(start 155.646263 110.656328)
		(mid 155.522519 110.707584)
		(end 155.471263 110.831328)
		(width 0.14)
		(layer "F.Cu")
		(net 47)
	)
	(segment
		(start 170.846328 108.360008)
		(end 168.096328 111.110008)
		(width 0.14)
		(layer "F.Cu")
		(net 48)
	)
	(segment
		(start 157.761328 111.625008)
		(end 157.761328 112.222328)
		(width 0.14)
		(layer "F.Cu")
		(net 48)
	)
	(segment
		(start 157.761328 112.222328)
		(end 158.104 112.565)
		(width 0.14)
		(layer "F.Cu")
		(net 48)
	)
	(segment
		(start 170.536328 105.497157)
		(end 170.986328 105.947158)
		(width 0.14)
		(layer "F.Cu")
		(net 48)
	)
	(segment
		(start 168.096328 111.110008)
		(end 158.276328 111.110008)
		(width 0.14)
		(layer "F.Cu")
		(net 48)
	)
	(segment
		(start 170.986328 106.713672)
		(end 170.846328 106.853672)
		(width 0.14)
		(layer "F.Cu")
		(net 48)
	)
	(segment
		(start 170.986328 105.947158)
		(end 170.986328 106.713672)
		(width 0.14)
		(layer "F.Cu")
		(net 48)
	)
	(segment
		(start 158.276328 111.110008)
		(end 157.761328 111.625008)
		(width 0.14)
		(layer "F.Cu")
		(net 48)
	)
	(segment
		(start 170.846328 106.853672)
		(end 170.846328 108.360008)
		(width 0.14)
		(layer "F.Cu")
		(net 48)
	)
	(segment
		(start 170.536328 106.497157)
		(end 170.536328 108.270008)
		(width 0.14)
		(layer "F.Cu")
		(net 49)
	)
	(segment
		(start 160.409992 110.566875)
		(end 160.409992 110.640008)
		(width 0.14)
		(layer "F.Cu")
		(net 49)
	)
	(segment
		(start 170.536328 108.270008)
		(end 167.966328 110.840008)
		(width 0.14)
		(layer "F.Cu")
		(net 49)
	)
	(segment
		(start 158.136328 110.840008)
		(end 159.409992 110.840008)
		(width 0.14)
		(layer "F.Cu")
		(net 49)
	)
	(segment
		(start 159.609992 110.566875)
		(end 159.609992 110.640008)
		(width 0.14)
		(layer "F.Cu")
		(net 49)
	)
	(segment
		(start 157.476328 111.500008)
		(end 157.476328 112.260008)
		(width 0.14)
		(layer "F.Cu")
		(net 49)
	)
	(segment
		(start 158.136328 110.840008)
		(end 157.476328 111.500008)
		(width 0.14)
		(layer "F.Cu")
		(net 49)
	)
	(segment
		(start 167.966328 110.840008)
		(end 161.009992 110.840008)
		(width 0.14)
		(layer "F.Cu")
		(net 49)
	)
	(segment
		(start 157.476328 112.260008)
		(end 157.171336 112.565)
		(width 0.14)
		(layer "F.Cu")
		(net 49)
	)
	(segment
		(start 157.171336 112.565)
		(end 157.094 112.565)
		(width 0.14)
		(layer "F.Cu")
		(net 49)
	)
	(segment
		(start 160.009992 110.640008)
		(end 160.009992 110.566875)
		(width 0.14)
		(layer "F.Cu")
		(net 49)
	)
	(segment
		(start 160.809992 110.640008)
		(end 160.809992 110.566875)
		(width 0.14)
		(layer "F.Cu")
		(net 49)
	)
	(arc
		(start 159.809992 110.366875)
		(mid 159.668571 110.425454)
		(end 159.609992 110.566875)
		(width 0.14)
		(layer "F.Cu")
		(net 49)
	)
	(arc
		(start 161.009992 110.840008)
		(mid 160.868571 110.781429)
		(end 160.809992 110.640008)
		(width 0.14)
		(layer "F.Cu")
		(net 49)
	)
	(arc
		(start 160.609992 110.366875)
		(mid 160.468571 110.425454)
		(end 160.409992 110.566875)
		(width 0.14)
		(layer "F.Cu")
		(net 49)
	)
	(arc
		(start 160.009992 110.566875)
		(mid 159.951413 110.425454)
		(end 159.809992 110.366875)
		(width 0.14)
		(layer "F.Cu")
		(net 49)
	)
	(arc
		(start 159.609992 110.640008)
		(mid 159.551413 110.781429)
		(end 159.409992 110.840008)
		(width 0.14)
		(layer "F.Cu")
		(net 49)
	)
	(arc
		(start 160.409992 110.640008)
		(mid 160.351413 110.781429)
		(end 160.209992 110.840008)
		(width 0.14)
		(layer "F.Cu")
		(net 49)
	)
	(arc
		(start 160.209992 110.840008)
		(mid 160.068571 110.781429)
		(end 160.009992 110.640008)
		(width 0.14)
		(layer "F.Cu")
		(net 49)
	)
	(arc
		(start 160.809992 110.566875)
		(mid 160.751413 110.425454)
		(end 160.609992 110.366875)
		(width 0.14)
		(layer "F.Cu")
		(net 49)
	)
	(segment
		(start 159.659 114.992)
		(end 159.659 114.697)
		(width 0.14)
		(layer "F.Cu")
		(net 50)
	)
	(segment
		(start 171.986328 106.756328)
		(end 171.846328 106.896328)
		(width 0.14)
		(layer "F.Cu")
		(net 50)
	)
	(segment
		(start 169.080532 113.065008)
		(end 160.290532 113.065008)
		(width 0.14)
		(layer "F.Cu")
		(net 50)
	)
	(segment
		(start 171.846328 106.896328)
		(end 171.846328 110.299212)
		(width 0.14)
		(layer "F.Cu")
		(net 50)
	)
	(segment
		(start 171.986328 105.947157)
		(end 171.986328 106.756328)
		(width 0.14)
		(layer "F.Cu")
		(net 50)
	)
	(segment
		(start 159.659 114.697)
		(end 159.296328 114.334328)
		(width 0.14)
		(layer "F.Cu")
		(net 50)
	)
	(segment
		(start 159.296328 114.334328)
		(end 159.296328 114.050008)
		(width 0.14)
		(layer "F.Cu")
		(net 50)
	)
	(segment
		(start 171.846328 110.299212)
		(end 169.080532 113.065008)
		(width 0.14)
		(layer "F.Cu")
		(net 50)
	)
	(segment
		(start 171.536328 105.497157)
		(end 171.986328 105.947157)
		(width 0.14)
		(layer "F.Cu")
		(net 50)
	)
	(segment
		(start 160.290532 113.065008)
		(end 159.296328 114.050008)
		(width 0.14)
		(layer "F.Cu")
		(net 50)
	)
	(segment
		(start 158.643 114.992)
		(end 158.643 114.663336)
		(width 0.14)
		(layer "F.Cu")
		(net 51)
	)
	(segment
		(start 161.730008 112.465995)
		(end 161.730008 112.580008)
		(width 0.14)
		(layer "F.Cu")
		(net 51)
	)
	(segment
		(start 161.030008 112.465995)
		(end 161.030008 112.580008)
		(width 0.14)
		(layer "F.Cu")
		(net 51)
	)
	(segment
		(start 171.536328 110.170804)
		(end 171.536328 106.497157)
		(width 0.14)
		(layer "F.Cu")
		(net 51)
	)
	(segment
		(start 158.996328 114.310008)
		(end 158.996328 113.920804)
		(width 0.14)
		(layer "F.Cu")
		(net 51)
	)
	(segment
		(start 160.680008 112.580008)
		(end 160.680008 112.465995)
		(width 0.14)
		(layer "F.Cu")
		(net 51)
	)
	(segment
		(start 161.380008 112.580008)
		(end 161.380008 112.465995)
		(width 0.14)
		(layer "F.Cu")
		(net 51)
	)
	(segment
		(start 158.996328 113.920804)
		(end 160.162124 112.755008)
		(width 0.14)
		(layer "F.Cu")
		(net 51)
	)
	(segment
		(start 161.905008 112.755008)
		(end 168.952124 112.755008)
		(width 0.14)
		(layer "F.Cu")
		(net 51)
	)
	(segment
		(start 168.952124 112.755008)
		(end 171.536328 110.170804)
		(width 0.14)
		(layer "F.Cu")
		(net 51)
	)
	(segment
		(start 158.643 114.663336)
		(end 158.996328 114.310008)
		(width 0.14)
		(layer "F.Cu")
		(net 51)
	)
	(segment
		(start 160.162124 112.755008)
		(end 160.505008 112.755008)
		(width 0.14)
		(layer "F.Cu")
		(net 51)
	)
	(arc
		(start 160.505008 112.755008)
		(mid 160.628752 112.703752)
		(end 160.680008 112.580008)
		(width 0.14)
		(layer "F.Cu")
		(net 51)
	)
	(arc
		(start 160.680008 112.465995)
		(mid 160.731264 112.342251)
		(end 160.855008 112.290995)
		(width 0.14)
		(layer "F.Cu")
		(net 51)
	)
	(arc
		(start 161.030008 112.580008)
		(mid 161.081264 112.703752)
		(end 161.205008 112.755008)
		(width 0.14)
		(layer "F.Cu")
		(net 51)
	)
	(arc
		(start 160.855008 112.290995)
		(mid 160.978752 112.342251)
		(end 161.030008 112.465995)
		(width 0.14)
		(layer "F.Cu")
		(net 51)
	)
	(arc
		(start 161.555008 112.290995)
		(mid 161.678752 112.342251)
		(end 161.730008 112.465995)
		(width 0.14)
		(layer "F.Cu")
		(net 51)
	)
	(arc
		(start 161.730008 112.580008)
		(mid 161.781264 112.703752)
		(end 161.905008 112.755008)
		(width 0.14)
		(layer "F.Cu")
		(net 51)
	)
	(arc
		(start 161.380008 112.465995)
		(mid 161.431264 112.342251)
		(end 161.555008 112.290995)
		(width 0.14)
		(layer "F.Cu")
		(net 51)
	)
	(arc
		(start 161.205008 112.755008)
		(mid 161.328752 112.703752)
		(end 161.380008 112.580008)
		(width 0.14)
		(layer "F.Cu")
		(net 51)
	)
	(segment
		(start 202.736328 66.070008)
		(end 204.136328 64.670008)
		(width 0.1)
		(layer "F.Cu")
		(net 52)
	)
	(segment
		(start 204.136328 64.670008)
		(end 204.136328 64.020008)
		(width 0.1)
		(layer "F.Cu")
		(net 52)
	)
	(segment
		(start 202.736328 66.070008)
		(end 202.736328 71.212157)
		(width 0.1)
		(layer "F.Cu")
		(net 52)
	)
	(segment
		(start 206.736328 71.212157)
		(end 206.736328 66.170008)
		(width 0.1)
		(layer "F.Cu")
		(net 53)
	)
	(segment
		(start 206.736328 66.170008)
		(end 207.736328 65.170008)
		(width 0.1)
		(layer "F.Cu")
		(net 53)
	)
	(segment
		(start 207.736328 65.170008)
		(end 207.736328 64.020008)
		(width 0.1)
		(layer "F.Cu")
		(net 53)
	)
	(segment
		(start 204.536328 84.820008)
		(end 202.871328 84.820008)
		(width 0.2)
		(layer "F.Cu")
		(net 54)
	)
	(segment
		(start 119.388672 118.975)
		(end 120.175 118.975)
		(width 0.2)
		(layer "F.Cu")
		(net 55)
	)
	(segment
		(start 120.175 118.975)
		(end 120.2 119)
		(width 0.2)
		(layer "F.Cu")
		(net 55)
	)
	(segment
		(start 121.575 113.475)
		(end 121.6 113.5)
		(width 0.2)
		(layer "F.Cu")
		(net 55)
	)
	(segment
		(start 120.8 113.475)
		(end 121.575 113.475)
		(width 0.2)
		(layer "F.Cu")
		(net 55)
	)
	(via
		(at 120.2 119)
		(size 0.5)
		(drill 0.2)
		(layers "F.Cu" "B.Cu")
		(net 55)
	)
	(via
		(at 121.6 113.5)
		(size 0.5)
		(drill 0.2)
		(layers "F.Cu" "B.Cu")
		(net 55)
	)
	(segment
		(start 121.6 113.5)
		(end 121.6 117.6)
		(width 0.2)
		(layer "In5.Cu")
		(net 55)
	)
	(segment
		(start 121.6 117.6)
		(end 120.2 119)
		(width 0.2)
		(layer "In5.Cu")
		(net 55)
	)
	(segment
		(start 174.536329 92.497157)
		(end 175.036329 91.997157)
		(width 0.15)
		(layer "F.Cu")
		(net 56)
	)
	(segment
		(start 190.086328 82.820008)
		(end 188.786328 84.120008)
		(width 0.15)
		(layer "F.Cu")
		(net 56)
	)
	(segment
		(start 190.086328 75.647157)
		(end 190.086328 82.820008)
		(width 0.15)
		(layer "F.Cu")
		(net 56)
	)
	(segment
		(start 188.786328 84.120008)
		(end 188.786328 85.720008)
		(width 0.15)
		(layer "F.Cu")
		(net 56)
	)
	(via blind
		(at 175.036329 91.997157)
		(size 0.5)
		(drill 0.2)
		(layers "F.Cu" "In2.Cu")
		(net 56)
	)
	(via
		(at 188.786328 85.720008)
		(size 0.5)
		(drill 0.2)
		(layers "F.Cu" "B.Cu")
		(net 56)
	)
	(segment
		(start 175.036329 91.997157)
		(end 175.036329 91.372156)
		(width 0.1)
		(layer "In2.Cu")
		(net 56)
	)
	(segment
		(start 188.786328 86.282418)
		(end 188.786328 85.720008)
		(width 0.1)
		(layer "In2.Cu")
		(net 56)
	)
	(segment
		(start 188.767533 86.301213)
		(end 188.786328 86.282418)
		(width 0.1)
		(layer "In2.Cu")
		(net 56)
	)
	(segment
		(start 184.321588 90.747157)
		(end 188.767533 86.301213)
		(width 0.1)
		(layer "In2.Cu")
		(net 56)
	)
	(segment
		(start 175.036329 91.372156)
		(end 175.661328 90.747157)
		(width 0.1)
		(layer "In2.Cu")
		(net 56)
	)
	(segment
		(start 175.661328 90.747157)
		(end 184.321588 90.747157)
		(width 0.1)
		(layer "In2.Cu")
		(net 56)
	)
	(segment
		(start 179.536329 92.497157)
		(end 181.536329 92.497156)
		(width 0.15)
		(layer "F.Cu")
		(net 57)
	)
	(segment
		(start 198.086328 76.320008)
		(end 196.786328 77.620008)
		(width 0.15)
		(layer "F.Cu")
		(net 57)
	)
	(segment
		(start 196.786328 77.620008)
		(end 196.786328 78.820008)
		(width 0.15)
		(layer "F.Cu")
		(net 57)
	)
	(segment
		(start 198.086328 75.647157)
		(end 198.086328 76.320008)
		(width 0.15)
		(layer "F.Cu")
		(net 57)
	)
	(via blind
		(at 181.536329 92.497156)
		(size 0.5)
		(drill 0.2)
		(layers "F.Cu" "In2.Cu")
		(net 57)
	)
	(via
		(at 196.786328 78.820008)
		(size 0.5)
		(drill 0.2)
		(layers "F.Cu" "B.Cu")
		(net 57)
	)
	(segment
		(start 184.612012 91.887201)
		(end 195.182767 81.316447)
		(width 0.1)
		(layer "In2.Cu")
		(net 57)
	)
	(segment
		(start 181.536329 92.497156)
		(end 182.146284 91.887201)
		(width 0.1)
		(layer "In2.Cu")
		(net 57)
	)
	(segment
		(start 195.889889 81.316447)
		(end 196.786328 80.420008)
		(width 0.1)
		(layer "In2.Cu")
		(net 57)
	)
	(segment
		(start 196.786328 80.420008)
		(end 196.786328 78.820008)
		(width 0.1)
		(layer "In2.Cu")
		(net 57)
	)
	(segment
		(start 182.146284 91.887201)
		(end 184.612012 91.887201)
		(width 0.1)
		(layer "In2.Cu")
		(net 57)
	)
	(segment
		(start 195.182767 81.316447)
		(end 195.889889 81.316447)
		(width 0.1)
		(layer "In2.Cu")
		(net 57)
	)
	(segment
		(start 140.225857 96.475)
		(end 140.225857 98.224143)
		(width 0.2)
		(layer "F.Cu")
		(net 58)
	)
	(segment
		(start 140.225857 98.224143)
		(end 140.2 98.25)
		(width 0.2)
		(layer "F.Cu")
		(net 58)
	)
	(segment
		(start 177.536329 92.497156)
		(end 178.036328 91.997157)
		(width 0.15)
		(layer "F.Cu")
		(net 59)
	)
	(segment
		(start 194.086328 75.647157)
		(end 194.086328 75.920008)
		(width 0.15)
		(layer "F.Cu")
		(net 59)
	)
	(segment
		(start 193.086328 78.120008)
		(end 193.086328 81.820008)
		(width 0.15)
		(layer "F.Cu")
		(net 59)
	)
	(segment
		(start 194.086328 75.920008)
		(end 194.086328 77.120008)
		(width 0.15)
		(layer "F.Cu")
		(net 59)
	)
	(segment
		(start 194.086328 77.120008)
		(end 193.086328 78.120008)
		(width 0.15)
		(layer "F.Cu")
		(net 59)
	)
	(via blind
		(at 178.036328 91.997157)
		(size 0.5)
		(drill 0.2)
		(layers "F.Cu" "In2.Cu")
		(net 59)
	)
	(via
		(at 193.086328 81.820008)
		(size 0.5)
		(drill 0.2)
		(layers "F.Cu" "B.Cu")
		(net 59)
	)
	(segment
		(start 178.646306 91.387179)
		(end 184.404898 91.387179)
		(width 0.1)
		(layer "In2.Cu")
		(net 59)
	)
	(segment
		(start 193.086328 82.70575)
		(end 193.086328 81.820008)
		(width 0.1)
		(layer "In2.Cu")
		(net 59)
	)
	(segment
		(start 193.079199 82.712879)
		(end 193.086328 82.70575)
		(width 0.1)
		(layer "In2.Cu")
		(net 59)
	)
	(segment
		(start 178.036328 91.997157)
		(end 178.646306 91.387179)
		(width 0.1)
		(layer "In2.Cu")
		(net 59)
	)
	(segment
		(start 184.404898 91.387179)
		(end 193.079199 82.712879)
		(width 0.1)
		(layer "In2.Cu")
		(net 59)
	)
	(segment
		(start 137.335 78.15)
		(end 137.9 78.715)
		(width 0.2)
		(layer "B.Cu")
		(net 60)
	)
	(segment
		(start 136.875 78.15)
		(end 137.335 78.15)
		(width 0.2)
		(layer "B.Cu")
		(net 60)
	)
	(segment
		(start 176.536329 93.497156)
		(end 177.036329 92.997156)
		(width 0.15)
		(layer "F.Cu")
		(net 61)
	)
	(segment
		(start 200.959179 75.647157)
		(end 199.986328 76.620008)
		(width 0.1)
		(layer "F.Cu")
		(net 61)
	)
	(segment
		(start 199.986328 76.620008)
		(end 199.986328 78.820008)
		(width 0.1)
		(layer "F.Cu")
		(net 61)
	)
	(segment
		(start 202.086328 75.647157)
		(end 200.959179 75.647157)
		(width 0.1)
		(layer "F.Cu")
		(net 61)
	)
	(via blind
		(at 177.036329 92.997156)
		(size 0.5)
		(drill 0.2)
		(layers "F.Cu" "In2.Cu")
		(net 61)
	)
	(via
		(at 199.986328 78.820008)
		(size 0.5)
		(drill 0.2)
		(layers "F.Cu" "B.Cu")
		(net 61)
	)
	(segment
		(start 195.315463 81.890886)
		(end 197.91545 81.890886)
		(width 0.1)
		(layer "In2.Cu")
		(net 61)
	)
	(segment
		(start 177.036329 92.997156)
		(end 177.49634 93.457167)
		(width 0.1)
		(layer "In2.Cu")
		(net 61)
	)
	(segment
		(start 197.91545 81.890886)
		(end 199.986328 79.820008)
		(width 0.1)
		(layer "In2.Cu")
		(net 61)
	)
	(segment
		(start 199.986328 79.820008)
		(end 199.986328 78.820008)
		(width 0.1)
		(layer "In2.Cu")
		(net 61)
	)
	(segment
		(start 183.749181 93.457167)
		(end 195.315463 81.890886)
		(width 0.1)
		(layer "In2.Cu")
		(net 61)
	)
	(segment
		(start 177.49634 93.457167)
		(end 183.749181 93.457167)
		(width 0.1)
		(layer "In2.Cu")
		(net 61)
	)
	(segment
		(start 137.335 69.75)
		(end 137.9 70.315)
		(width 0.2)
		(layer "B.Cu")
		(net 62)
	)
	(segment
		(start 136.875 69.75)
		(end 137.335 69.75)
		(width 0.2)
		(layer "B.Cu")
		(net 62)
	)
	(segment
		(start 174.536329 93.497156)
		(end 175.036329 92.997157)
		(width 0.15)
		(layer "F.Cu")
		(net 63)
	)
	(segment
		(start 202.186328 78.820008)
		(end 202.186328 77.883672)
		(width 0.1)
		(layer "F.Cu")
		(net 63)
	)
	(segment
		(start 204.422843 75.647157)
		(end 206.086328 75.647157)
		(width 0.1)
		(layer "F.Cu")
		(net 63)
	)
	(segment
		(start 202.186328 77.883672)
		(end 204.422843 75.647157)
		(width 0.1)
		(layer "F.Cu")
		(net 63)
	)
	(via blind
		(at 175.036329 92.997157)
		(size 0.5)
		(drill 0.2)
		(layers "F.Cu" "In2.Cu")
		(net 63)
	)
	(via
		(at 202.186328 78.820008)
		(size 0.5)
		(drill 0.2)
		(layers "F.Cu" "B.Cu")
		(net 63)
	)
	(segment
		(start 183.956295 93.957189)
		(end 194.916328 82.997157)
		(width 0.1)
		(layer "In2.Cu")
		(net 63)
	)
	(segment
		(start 194.916328 82.997157)
		(end 199.009179 82.997157)
		(width 0.1)
		(layer "In2.Cu")
		(net 63)
	)
	(segment
		(start 202.186328 79.820008)
		(end 202.186328 78.820008)
		(width 0.1)
		(layer "In2.Cu")
		(net 63)
	)
	(segment
		(start 199.009179 82.997157)
		(end 202.186328 79.820008)
		(width 0.1)
		(layer "In2.Cu")
		(net 63)
	)
	(segment
		(start 175.036329 92.997157)
		(end 175.996361 93.957189)
		(width 0.1)
		(layer "In2.Cu")
		(net 63)
	)
	(segment
		(start 175.996361 93.957189)
		(end 183.956295 93.957189)
		(width 0.1)
		(layer "In2.Cu")
		(net 63)
	)
	(segment
		(start 209.111328 70.920008)
		(end 208.086328 70.920008)
		(width 0.2)
		(layer "B.Cu")
		(net 64)
	)
	(segment
		(start 208.086328 70.920008)
		(end 207.861328 70.920008)
		(width 0.2)
		(layer "B.Cu")
		(net 64)
	)
	(segment
		(start 209.111328 70.420008)
		(end 207.861328 70.420008)
		(width 0.2)
		(layer "B.Cu")
		(net 65)
	)
	(segment
		(start 168.536328 88.497158)
		(end 169.036328 87.997158)
		(width 0.15)
		(layer "F.Cu")
		(net 66)
	)
	(segment
		(start 163.536329 93.497156)
		(end 163.036329 92.997156)
		(width 0.15)
		(layer "F.Cu")
		(net 66)
	)
	(segment
		(start 165.536328 89.497156)
		(end 165.036328 89.997156)
		(width 0.15)
		(layer "F.Cu")
		(net 66)
	)
	(segment
		(start 160.536329 94.497157)
		(end 160.036329 93.997157)
		(width 0.15)
		(layer "F.Cu")
		(net 66)
	)
	(segment
		(start 161.536329 87.497157)
		(end 161.036329 86.997157)
		(width 0.15)
		(layer "F.Cu")
		(net 66)
	)
	(segment
		(start 162.536327 90.497156)
		(end 162.036327 90.997156)
		(width 0.15)
		(layer "F.Cu")
		(net 66)
	)
	(segment
		(start 164.536328 96.497157)
		(end 164.036329 96.997156)
		(width 0.15)
		(layer "F.Cu")
		(net 66)
	)
	(segment
		(start 161.536328 97.497156)
		(end 162.036328 97.997156)
		(width 0.15)
		(layer "F.Cu")
		(net 66)
	)
	(segment
		(start 158.513476 88.470008)
		(end 158.013477 88.970007)
		(width 0.15)
		(layer "F.Cu")
		(net 66)
	)
	(segment
		(start 158.536328 88.497157)
		(end 158.536328 88.497156)
		(width 0.15)
		(layer "F.Cu")
		(net 66)
	)
	(segment
		(start 164.536328 86.497157)
		(end 165.036328 86.997157)
		(width 0.15)
		(layer "F.Cu")
		(net 66)
	)
	(segment
		(start 167.536328 85.497157)
		(end 167.536328 84.9)
		(width 0.15)
		(layer "F.Cu")
		(net 66)
	)
	(segment
		(start 159.536329 91.497156)
		(end 159.036329 90.997156)
		(width 0.15)
		(layer "F.Cu")
		(net 66)
	)
	(segment
		(start 179.6 57.8)
		(end 179.6 58.4)
		(width 0.5)
		(layer "F.Cu")
		(net 66)
	)
	(segment
		(start 157.2 57.8)
		(end 157.2 58.5)
		(width 0.5)
		(layer "F.Cu")
		(net 66)
	)
	(via
		(at 169.036328 87.997158)
		(size 0.5)
		(drill 0.2)
		(layers "F.Cu" "B.Cu")
		(net 66)
	)
	(via
		(at 165.036328 86.997157)
		(size 0.5)
		(drill 0.2)
		(layers "F.Cu" "B.Cu")
		(net 66)
	)
	(via
		(at 158.036329 87.997157)
		(size 0.5)
		(drill 0.2)
		(layers "F.Cu" "B.Cu")
		(net 66)
	)
	(via
		(at 163.036329 92.997156)
		(size 0.5)
		(drill 0.2)
		(layers "F.Cu" "B.Cu")
		(net 66)
	)
	(via
		(at 165.036328 89.997156)
		(size 0.5)
		(drill 0.2)
		(layers "F.Cu" "B.Cu")
		(net 66)
	)
	(via
		(at 160.036329 93.997157)
		(size 0.5)
		(drill 0.2)
		(layers "F.Cu" "B.Cu")
		(net 66)
	)
	(via
		(at 161.036329 86.997157)
		(size 0.5)
		(drill 0.2)
		(layers "F.Cu" "B.Cu")
		(net 66)
	)
	(via
		(at 162.036327 90.997156)
		(size 0.5)
		(drill 0.2)
		(layers "F.Cu" "B.Cu")
		(net 66)
	)
	(via
		(at 164.036329 96.997156)
		(size 0.5)
		(drill 0.2)
		(layers "F.Cu" "B.Cu")
		(net 66)
	)
	(via
		(at 162.036328 97.997156)
		(size 0.5)
		(drill 0.2)
		(layers "F.Cu" "B.Cu")
		(net 66)
	)
	(via
		(at 157.936328 89.020008)
		(size 0.5)
		(drill 0.2)
		(layers "F.Cu" "B.Cu")
		(net 66)
	)
	(via
		(at 148.5 72.8)
		(size 0.5)
		(drill 0.2)
		(layers "F.Cu" "B.Cu")
		(free yes)
		(net 66)
	)
	(via
		(at 180.5 72)
		(size 0.5)
		(drill 0.2)
		(layers "F.Cu" "B.Cu")
		(free yes)
		(net 66)
	)
	(via
		(at 179.6 58.4)
		(size 0.5)
		(drill 0.2)
		(layers "F.Cu" "B.Cu")
		(net 66)
	)
	(via
		(at 148.5 72)
		(size 0.5)
		(drill 0.2)
		(layers "F.Cu" "B.Cu")
		(free yes)
		(net 66)
	)
	(via
		(at 180.5 72.8)
		(size 0.5)
		(drill 0.2)
		(layers "F.Cu" "B.Cu")
		(free yes)
		(net 66)
	)
	(via
		(at 181.1 72.4)
		(size 0.5)
		(drill 0.2)
		(layers "F.Cu" "B.Cu")
		(free yes)
		(net 66)
	)
	(via
		(at 156.936328 92.697157)
		(size 0.5)
		(drill 0.2)
		(layers "F.Cu" "B.Cu")
		(net 66)
	)
	(via
		(at 149.1 72.4)
		(size 0.5)
		(drill 0.2)
		(layers "F.Cu" "B.Cu")
		(free yes)
		(net 66)
	)
	(via
		(at 157.2 58.5)
		(size 0.5)
		(drill 0.2)
		(layers "F.Cu" "B.Cu")
		(net 66)
	)
	(via
		(at 172.3 80.975)
		(size 0.5)
		(drill 0.2)
		(layers "F.Cu" "B.Cu")
		(net 66)
	)
	(via
		(at 156.886328 86.220008)
		(size 0.5)
		(drill 0.2)
		(layers "F.Cu" "B.Cu")
		(net 66)
	)
	(via
		(at 167.536328 84.9)
		(size 0.5)
		(drill 0.2)
		(layers "F.Cu" "B.Cu")
		(net 66)
	)
	(via
		(at 159.036329 90.997156)
		(size 0.5)
		(drill 0.2)
		(layers "F.Cu" "B.Cu")
		(net 66)
	)
	(segment
		(start 158.476328 89.180008)
		(end 158.223478 89.180008)
		(width 0.15)
		(layer "B.Cu")
		(net 66)
	)
	(segment
		(start 156.936328 91.097157)
		(end 156.936328 92.697157)
		(width 0.2)
		(layer "B.Cu")
		(net 66)
	)
	(segment
		(start 161.25 91.055)
		(end 161.978483 91.055)
		(width 0.2)
		(layer "B.Cu")
		(net 66)
	)
	(segment
		(start 165.557844 89.997156)
		(end 165.68 89.875)
		(width 0.2)
		(layer "B.Cu")
		(net 66)
	)
	(segment
		(start 160.036329 93.997157)
		(end 160.036329 93.197156)
		(width 0.2)
		(layer "B.Cu")
		(net 66)
	)
	(segment
		(start 165.305 87.265829)
		(end 165.036328 86.997157)
		(width 0.2)
		(layer "B.Cu")
		(net 66)
	)
	(segment
		(start 160.036329 93.197156)
		(end 160.236328 92.997157)
		(width 0.2)
		(layer "B.Cu")
		(net 66)
	)
	(segment
		(start 158.036329 87.997157)
		(end 158.036329 87.547156)
		(width 0.15)
		(layer "B.Cu")
		(net 66)
	)
	(segment
		(start 162.375 93.18)
		(end 162.853485 93.18)
		(width 0.2)
		(layer "B.Cu")
		(net 66)
	)
	(segment
		(start 162.033484 98)
		(end 162.036328 97.997156)
		(width 0.2)
		(layer "B.Cu")
		(net 66)
	)
	(segment
		(start 161.978483 91.055)
		(end 162.036327 90.997156)
		(width 0.2)
		(layer "B.Cu")
		(net 66)
	)
	(segment
		(start 172.3 81.8)
		(end 172.3 80.975)
		(width 0.5)
		(layer "B.Cu")
		(net 66)
	)
	(segment
		(start 159.53633 91.497157)
		(end 159.036329 90.997156)
		(width 0.15)
		(layer "B.Cu")
		(net 66)
	)
	(segment
		(start 169.836328 87.697157)
		(end 169.836328 86.697157)
		(width 0.2)
		(layer "B.Cu")
		(net 66)
	)
	(segment
		(start 156.886328 85.847157)
		(end 156.886328 86.220008)
		(width 0.2)
		(layer "B.Cu")
		(net 66)
	)
	(segment
		(start 169.536327 87.997158)
		(end 169.836328 87.697157)
		(width 0.2)
		(layer "B.Cu")
		(net 66)
	)
	(segment
		(start 164.036329 96.997156)
		(end 163.447844 96.997156)
		(width 0.2)
		(layer "B.Cu")
		(net 66)
	)
	(segment
		(start 161.036329 86.997157)
		(end 161.456328 87.417156)
		(width 0.2)
		(layer "B.Cu")
		(net 66)
	)
	(segment
		(start 168.98417 87.945)
		(end 169.036328 87.997158)
		(width 0.2)
		(layer "B.Cu")
		(net 66)
	)
	(segment
		(start 167.5 84.783485)
		(end 167.5 85.555)
		(width 0.2)
		(layer "B.Cu")
		(net 66)
	)
	(segment
		(start 168.25 87.945)
		(end 168.98417 87.945)
		(width 0.2)
		(layer "B.Cu")
		(net 66)
	)
	(segment
		(start 165.036328 89.997156)
		(end 165.557844 89.997156)
		(width 0.2)
		(layer "B.Cu")
		(net 66)
	)
	(segment
		(start 161.32 98)
		(end 162.033484 98)
		(width 0.2)
		(layer "B.Cu")
		(net 66)
	)
	(segment
		(start 160.686328 94.470008)
		(end 160.50918 94.470008)
		(width 0.15)
		(layer "B.Cu")
		(net 66)
	)
	(segment
		(start 159.716328 91.497157)
		(end 159.53633 91.497157)
		(width 0.15)
		(layer "B.Cu")
		(net 66)
	)
	(segment
		(start 169.036328 87.997158)
		(end 169.536327 87.997158)
		(width 0.2)
		(layer "B.Cu")
		(net 66)
	)
	(segment
		(start 158.036329 87.547156)
		(end 158.336328 87.247157)
		(width 0.15)
		(layer "B.Cu")
		(net 66)
	)
	(segment
		(start 162.853485 93.18)
		(end 163.036329 92.997156)
		(width 0.2)
		(layer "B.Cu")
		(net 66)
	)
	(segment
		(start 161.456328 87.417156)
		(end 161.456328 87.597157)
		(width 0.2)
		(layer "B.Cu")
		(net 66)
	)
	(segment
		(start 165.305 87.625)
		(end 165.305 87.265829)
		(width 0.2)
		(layer "B.Cu")
		(net 66)
	)
	(segment
		(start 160.50918 94.470008)
		(end 160.036329 93.997157)
		(width 0.15)
		(layer "B.Cu")
		(net 66)
	)
	(segment
		(start 158.223478 89.180008)
		(end 158.013477 88.970007)
		(width 0.15)
		(layer "B.Cu")
		(net 66)
	)
	(segment
		(start 167.536328 84.9)
		(end 167.5 84.783485)
		(width 0.2)
		(layer "B.Cu")
		(net 66)
	)
	(segment
		(start 202.871328 86.620008)
		(end 204.536328 86.620008)
		(width 0.2)
		(layer "F.Cu")
		(net 67)
	)
	(segment
		(start 157.786328 70.647157)
		(end 157.786328 71.997157)
		(width 0.1)
		(layer "F.Cu")
		(net 68)
	)
	(segment
		(start 158.536328 86.497156)
		(end 158.036328 85.997156)
		(width 0.15)
		(layer "F.Cu")
		(net 68)
	)
	(via blind
		(at 157.786328 71.997157)
		(size 0.5)
		(drill 0.2)
		(layers "F.Cu" "In2.Cu")
		(net 68)
	)
	(via blind
		(at 158.036328 85.997156)
		(size 0.5)
		(drill 0.2)
		(layers "F.Cu" "In2.Cu")
		(net 68)
	)
	(segment
		(start 158.036328 85.997156)
		(end 157.786328 85.747156)
		(width 0.182)
		(layer "In2.Cu")
		(net 68)
	)
	(segment
		(start 157.786328 85.747156)
		(end 157.786328 79)
		(width 0.182)
		(layer "In2.Cu")
		(net 68)
	)
	(segment
		(start 157.786328 71.997157)
		(end 157.786328 72.511328)
		(width 0.182)
		(layer "In2.Cu")
		(net 68)
	)
	(segment
		(start 157.604328 78.818)
		(end 157.423741 78.818)
		(width 0.182)
		(layer "In2.Cu")
		(net 68)
	)
	(segment
		(start 157.423741 78.454)
		(end 157.604328 78.454)
		(width 0.182)
		(layer "In2.Cu")
		(net 68)
	)
	(segment
		(start 157.241741 72.875328)
		(end 157.241741 76.452)
		(width 0.182)
		(layer "In2.Cu")
		(net 68)
	)
	(segment
		(start 157.423741 76.998)
		(end 157.604328 76.998)
		(width 0.182)
		(layer "In2.Cu")
		(net 68)
	)
	(segment
		(start 157.604328 76.634)
		(end 157.423741 76.634)
		(width 0.182)
		(layer "In2.Cu")
		(net 68)
	)
	(segment
		(start 157.604328 78.09)
		(end 157.423741 78.09)
		(width 0.182)
		(layer "In2.Cu")
		(net 68)
	)
	(segment
		(start 157.423741 77.726)
		(end 157.604328 77.726)
		(width 0.182)
		(layer "In2.Cu")
		(net 68)
	)
	(segment
		(start 157.604328 77.362)
		(end 157.423741 77.362)
		(width 0.182)
		(layer "In2.Cu")
		(net 68)
	)
	(segment
		(start 157.604328 72.693328)
		(end 157.423741 72.693328)
		(width 0.182)
		(layer "In2.Cu")
		(net 68)
	)
	(arc
		(start 157.241741 78.636)
		(mid 157.295048 78.507307)
		(end 157.423741 78.454)
		(width 0.182)
		(layer "In2.Cu")
		(net 68)
	)
	(arc
		(start 157.423741 78.09)
		(mid 157.295048 78.036693)
		(end 157.241741 77.908)
		(width 0.182)
		(layer "In2.Cu")
		(net 68)
	)
	(arc
		(start 157.423741 78.818)
		(mid 157.295048 78.764693)
		(end 157.241741 78.636)
		(width 0.182)
		(layer "In2.Cu")
		(net 68)
	)
	(arc
		(start 157.604328 78.454)
		(mid 157.733021 78.400693)
		(end 157.786328 78.272)
		(width 0.182)
		(layer "In2.Cu")
		(net 68)
	)
	(arc
		(start 157.604328 76.998)
		(mid 157.733021 76.944693)
		(end 157.786328 76.816)
		(width 0.182)
		(layer "In2.Cu")
		(net 68)
	)
	(arc
		(start 157.423741 76.634)
		(mid 157.295048 76.580693)
		(end 157.241741 76.452)
		(width 0.182)
		(layer "In2.Cu")
		(net 68)
	)
	(arc
		(start 157.604328 77.726)
		(mid 157.733021 77.672693)
		(end 157.786328 77.544)
		(width 0.182)
		(layer "In2.Cu")
		(net 68)
	)
	(arc
		(start 157.786328 79)
		(mid 157.733021 78.871307)
		(end 157.604328 78.818)
		(width 0.182)
		(layer "In2.Cu")
		(net 68)
	)
	(arc
		(start 157.786328 72.511328)
		(mid 157.733021 72.640021)
		(end 157.604328 72.693328)
		(width 0.182)
		(layer "In2.Cu")
		(net 68)
	)
	(arc
		(start 157.423741 77.362)
		(mid 157.295048 77.308693)
		(end 157.241741 77.18)
		(width 0.182)
		(layer "In2.Cu")
		(net 68)
	)
	(arc
		(start 157.241741 77.18)
		(mid 157.295048 77.051307)
		(end 157.423741 76.998)
		(width 0.182)
		(layer "In2.Cu")
		(net 68)
	)
	(arc
		(start 157.786328 76.816)
		(mid 157.733021 76.687307)
		(end 157.604328 76.634)
		(width 0.182)
		(layer "In2.Cu")
		(net 68)
	)
	(arc
		(start 157.241741 77.908)
		(mid 157.295048 77.779307)
		(end 157.423741 77.726)
		(width 0.182)
		(layer "In2.Cu")
		(net 68)
	)
	(arc
		(start 157.786328 78.272)
		(mid 157.733021 78.143307)
		(end 157.604328 78.09)
		(width 0.182)
		(layer "In2.Cu")
		(net 68)
	)
	(arc
		(start 157.786328 77.544)
		(mid 157.733021 77.415307)
		(end 157.604328 77.362)
		(width 0.182)
		(layer "In2.Cu")
		(net 68)
	)
	(arc
		(start 157.423741 72.693328)
		(mid 157.295048 72.746635)
		(end 157.241741 72.875328)
		(width 0.182)
		(layer "In2.Cu")
		(net 68)
	)
	(segment
		(start 158.536328 87.497156)
		(end 158.036328 86.997156)
		(width 0.15)
		(layer "F.Cu")
		(net 69)
	)
	(segment
		(start 158.286328 70.647157)
		(end 158.286328 72.5)
		(width 0.1)
		(layer "F.Cu")
		(net 69)
	)
	(via blind
		(at 158.286328 72.5)
		(size 0.5)
		(drill 0.2)
		(layers "F.Cu" "In2.Cu")
		(net 69)
	)
	(via blind
		(at 158.036328 86.997156)
		(size 0.5)
		(drill 0.2)
		(layers "F.Cu" "In2.Cu")
		(net 69)
	)
	(segment
		(start 157.827352 75.65)
		(end 158.129328 75.65)
		(width 0.182)
		(layer "In2.Cu")
		(net 69)
	)
	(segment
		(start 157.670352 73.300328)
		(end 157.670352 75.493)
		(width 0.182)
		(layer "In2.Cu")
		(net 69)
	)
	(segment
		(start 158.129328 73.143328)
		(end 157.827352 73.143328)
		(width 0.182)
		(layer "In2.Cu")
		(net 69)
	)
	(segment
		(start 157.827352 76.278)
		(end 158.129328 76.278)
		(width 0.182)
		(layer "In2.Cu")
		(net 69)
	)
	(segment
		(start 158.286328 72.5)
		(end 158.286328 72.986328)
		(width 0.182)
		(layer "In2.Cu")
		(net 69)
	)
	(segment
		(start 158.286328 85.386328)
		(end 158.505828 85.605828)
		(width 0.182)
		(layer "In2.Cu")
		(net 69)
	)
	(segment
		(start 158.129328 75.964)
		(end 157.827352 75.964)
		(width 0.182)
		(layer "In2.Cu")
		(net 69)
	)
	(segment
		(start 158.286328 76.435)
		(end 158.286328 85.386328)
		(width 0.182)
		(layer "In2.Cu")
		(net 69)
	)
	(segment
		(start 158.505828 85.605828)
		(end 158.505828 86.527656)
		(width 0.182)
		(layer "In2.Cu")
		(net 69)
	)
	(segment
		(start 158.505828 86.527656)
		(end 158.036328 86.997156)
		(width 0.182)
		(layer "In2.Cu")
		(net 69)
	)
	(arc
		(start 158.286328 72.986328)
		(mid 158.240344 73.097344)
		(end 158.129328 73.143328)
		(width 0.182)
		(layer "In2.Cu")
		(net 69)
	)
	(arc
		(start 157.827352 73.143328)
		(mid 157.716336 73.189312)
		(end 157.670352 73.300328)
		(width 0.182)
		(layer "In2.Cu")
		(net 69)
	)
	(arc
		(start 157.670352 75.493)
		(mid 157.716336 75.604016)
		(end 157.827352 75.65)
		(width 0.182)
		(layer "In2.Cu")
		(net 69)
	)
	(arc
		(start 158.129328 76.278)
		(mid 158.240344 76.323984)
		(end 158.286328 76.435)
		(width 0.182)
		(layer "In2.Cu")
		(net 69)
	)
	(arc
		(start 158.286328 75.807)
		(mid 158.240344 75.918016)
		(end 158.129328 75.964)
		(width 0.182)
		(layer "In2.Cu")
		(net 69)
	)
	(arc
		(start 157.670352 76.121)
		(mid 157.716336 76.232016)
		(end 157.827352 76.278)
		(width 0.182)
		(layer "In2.Cu")
		(net 69)
	)
	(arc
		(start 158.129328 75.65)
		(mid 158.240344 75.695984)
		(end 158.286328 75.807)
		(width 0.182)
		(layer "In2.Cu")
		(net 69)
	)
	(arc
		(start 157.827352 75.964)
		(mid 157.716336 76.009984)
		(end 157.670352 76.121)
		(width 0.182)
		(layer "In2.Cu")
		(net 69)
	)
	(segment
		(start 158.786328 70.647157)
		(end 158.786328 71.997157)
		(width 0.1)
		(layer "F.Cu")
		(net 70)
	)
	(segment
		(start 159.536328 87.497156)
		(end 159.036328 86.997156)
		(width 0.15)
		(layer "F.Cu")
		(net 70)
	)
	(via blind
		(at 158.786328 71.997157)
		(size 0.5)
		(drill 0.2)
		(layers "F.Cu" "In2.Cu")
		(net 70)
	)
	(via blind
		(at 159.036328 86.997156)
		(size 0.5)
		(drill 0.2)
		(layers "F.Cu" "In2.Cu")
		(net 70)
	)
	(segment
		(start 158.786328 71.997157)
		(end 158.786328 73.413672)
		(width 0.182)
		(layer "In2.Cu")
		(net 70)
	)
	(segment
		(start 159.036328 85.286328)
		(end 159.036328 86.997156)
		(width 0.182)
		(layer "In2.Cu")
		(net 70)
	)
	(segment
		(start 158.281979 75.293)
		(end 158.629328 75.293)
		(width 0.182)
		(layer "In2.Cu")
		(net 70)
	)
	(segment
		(start 158.786328 85.036328)
		(end 159.036328 85.286328)
		(width 0.182)
		(layer "In2.Cu")
		(net 70)
	)
	(segment
		(start 158.281979 74.665)
		(end 158.629328 74.665)
		(width 0.182)
		(layer "In2.Cu")
		(net 70)
	)
	(segment
		(start 158.629328 73.570672)
		(end 158.281979 73.570672)
		(width 0.182)
		(layer "In2.Cu")
		(net 70)
	)
	(segment
		(start 158.124979 73.727672)
		(end 158.124979 74.508)
		(width 0.182)
		(layer "In2.Cu")
		(net 70)
	)
	(segment
		(start 158.629328 74.979)
		(end 158.281979 74.979)
		(width 0.182)
		(layer "In2.Cu")
		(net 70)
	)
	(segment
		(start 158.786328 75.45)
		(end 158.786328 85.036328)
		(width 0.182)
		(layer "In2.Cu")
		(net 70)
	)
	(arc
		(start 158.629328 74.665)
		(mid 158.740344 74.710984)
		(end 158.786328 74.822)
		(width 0.182)
		(layer "In2.Cu")
		(net 70)
	)
	(arc
		(start 158.281979 73.570672)
		(mid 158.170963 73.616656)
		(end 158.124979 73.727672)
		(width 0.182)
		(layer "In2.Cu")
		(net 70)
	)
	(arc
		(start 158.124979 75.136)
		(mid 158.170963 75.247016)
		(end 158.281979 75.293)
		(width 0.182)
		(layer "In2.Cu")
		(net 70)
	)
	(arc
		(start 158.281979 74.979)
		(mid 158.170963 75.024984)
		(end 158.124979 75.136)
		(width 0.182)
		(layer "In2.Cu")
		(net 70)
	)
	(arc
		(start 158.786328 74.822)
		(mid 158.740344 74.933016)
		(end 158.629328 74.979)
		(width 0.182)
		(layer "In2.Cu")
		(net 70)
	)
	(arc
		(start 158.629328 75.293)
		(mid 158.740344 75.338984)
		(end 158.786328 75.45)
		(width 0.182)
		(layer "In2.Cu")
		(net 70)
	)
	(arc
		(start 158.124979 74.508)
		(mid 158.170963 74.619016)
		(end 158.281979 74.665)
		(width 0.182)
		(layer "In2.Cu")
		(net 70)
	)
	(arc
		(start 158.786328 73.413672)
		(mid 158.740344 73.524688)
		(end 158.629328 73.570672)
		(width 0.182)
		(layer "In2.Cu")
		(net 70)
	)
	(segment
		(start 159.536328 88.497156)
		(end 159.036328 87.997156)
		(width 0.15)
		(layer "F.Cu")
		(net 71)
	)
	(segment
		(start 159.286328 70.647157)
		(end 159.286328 72.5)
		(width 0.1)
		(layer "F.Cu")
		(net 71)
	)
	(via blind
		(at 159.286328 72.5)
		(size 0.5)
		(drill 0.2)
		(layers "F.Cu" "In2.Cu")
		(net 71)
	)
	(via blind
		(at 159.036328 87.997156)
		(size 0.5)
		(drill 0.2)
		(layers "F.Cu" "In2.Cu")
		(net 71)
	)
	(segment
		(start 159.566828 85.133172)
		(end 159.566828 87.466656)
		(width 0.182)
		(layer "In2.Cu")
		(net 71)
	)
	(segment
		(start 159.286328 84.852672)
		(end 159.566828 85.133172)
		(width 0.182)
		(layer "In2.Cu")
		(net 71)
	)
	(segment
		(start 159.286328 72.5)
		(end 159.286328 73.813672)
		(width 0.182)
		(layer "In2.Cu")
		(net 71)
	)
	(segment
		(start 159.566828 87.466656)
		(end 159.036328 87.997156)
		(width 0.182)
		(layer "In2.Cu")
		(net 71)
	)
	(segment
		(start 158.871544 74.284672)
		(end 159.129328 74.284672)
		(width 0.182)
		(layer "In2.Cu")
		(net 71)
	)
	(segment
		(start 159.286328 74.441672)
		(end 159.286328 84.852672)
		(width 0.182)
		(layer "In2.Cu")
		(net 71)
	)
	(segment
		(start 159.129328 73.970672)
		(end 158.871544 73.970672)
		(width 0.182)
		(layer "In2.Cu")
		(net 71)
	)
	(arc
		(start 159.129328 74.284672)
		(mid 159.240344 74.330656)
		(end 159.286328 74.441672)
		(width 0.182)
		(layer "In2.Cu")
		(net 71)
	)
	(arc
		(start 158.714544 74.127672)
		(mid 158.760528 74.238688)
		(end 158.871544 74.284672)
		(width 0.182)
		(layer "In2.Cu")
		(net 71)
	)
	(arc
		(start 159.286328 73.813672)
		(mid 159.240344 73.924688)
		(end 159.129328 73.970672)
		(width 0.182)
		(layer "In2.Cu")
		(net 71)
	)
	(arc
		(start 158.871544 73.970672)
		(mid 158.760528 74.016656)
		(end 158.714544 74.127672)
		(width 0.182)
		(layer "In2.Cu")
		(net 71)
	)
	(segment
		(start 199.836328 64.870008)
		(end 199.836328 64.120008)
		(width 0.1)
		(layer "F.Cu")
		(net 72)
	)
	(segment
		(start 198.736328 65.970008)
		(end 199.836328 64.870008)
		(width 0.1)
		(layer "F.Cu")
		(net 72)
	)
	(segment
		(start 198.736328 71.212157)
		(end 198.736328 65.970008)
		(width 0.1)
		(layer "F.Cu")
		(net 72)
	)
	(segment
		(start 194.736328 71.212157)
		(end 194.736328 65.870008)
		(width 0.1)
		(layer "F.Cu")
		(net 73)
	)
	(segment
		(start 195.636328 64.970008)
		(end 195.636328 64.220008)
		(width 0.1)
		(layer "F.Cu")
		(net 73)
	)
	(segment
		(start 194.736328 65.870008)
		(end 195.636328 64.970008)
		(width 0.1)
		(layer "F.Cu")
		(net 73)
	)
	(segment
		(start 132.361328 130.047157)
		(end 132.361328 133.697157)
		(width 0.2)
		(layer "F.Cu")
		(net 74)
	)
	(segment
		(start 132.404 126.508)
		(end 132.525656 126.629656)
		(width 0.2)
		(layer "F.Cu")
		(net 74)
	)
	(segment
		(start 132.361328 133.697157)
		(end 140.111328 133.697157)
		(width 0.2)
		(layer "F.Cu")
		(net 74)
	)
	(segment
		(start 140.111328 133.697157)
		(end 140.111328 130.047157)
		(width 0.2)
		(layer "F.Cu")
		(net 74)
	)
	(segment
		(start 132.525656 126.629656)
		(end 132.525656 129.882829)
		(width 0.2)
		(layer "F.Cu")
		(net 74)
	)
	(segment
		(start 132.525656 129.882829)
		(end 132.361328 130.047157)
		(width 0.2)
		(layer "F.Cu")
		(net 74)
	)
	(segment
		(start 110.796328 117.897157)
		(end 110.771328 117.872157)
		(width 0.3)
		(layer "F.Cu")
		(net 77)
	)
	(segment
		(start 112.286328 117.897157)
		(end 110.796328 117.897157)
		(width 0.3)
		(layer "F.Cu")
		(net 77)
	)
	(segment
		(start 153.64 120.79)
		(end 152.01 119.16)
		(width 0.2)
		(layer "F.Cu")
		(net 80)
	)
	(segment
		(start 153.64 124.88)
		(end 153.64 120.79)
		(width 0.2)
		(layer "F.Cu")
		(net 80)
	)
	(segment
		(start 152.64 124.88)
		(end 152.64 122.474899)
		(width 0.2)
		(layer "F.Cu")
		(net 81)
	)
	(segment
		(start 152.64 122.474899)
		(end 151.325101 121.16)
		(width 0.2)
		(layer "F.Cu")
		(net 81)
	)
	(segment
		(start 150.434 121.66)
		(end 150.434 119.3354)
		(width 0.2)
		(layer "F.Cu")
		(net 82)
	)
	(segment
		(start 152.14 123.366)
		(end 150.434 121.66)
		(width 0.2)
		(layer "F.Cu")
		(net 82)
	)
	(segment
		(start 152.14 124.88)
		(end 152.14 123.366)
		(width 0.2)
		(layer "F.Cu")
		(net 82)
	)
	(segment
		(start 149.534 121.46)
		(end 149.534 121.16)
		(width 0.2)
		(layer "F.Cu")
		(net 83)
	)
	(segment
		(start 151.14 124.88)
		(end 151.14 123.066)
		(width 0.2)
		(layer "F.Cu")
		(net 83)
	)
	(segment
		(start 151.14 123.066)
		(end 149.534 121.46)
		(width 0.2)
		(layer "F.Cu")
		(net 83)
	)
	(segment
		(start 150.64 124.88)
		(end 150.64 123.525493)
		(width 0.2)
		(layer "F.Cu")
		(net 84)
	)
	(segment
		(start 148.534 121.419493)
		(end 148.534 119.16)
		(width 0.2)
		(layer "F.Cu")
		(net 84)
	)
	(segment
		(start 150.64 123.525493)
		(end 148.534 121.419493)
		(width 0.2)
		(layer "F.Cu")
		(net 84)
	)
	(segment
		(start 178.836 123.628)
		(end 181.353 123.628)
		(width 0.15)
		(layer "F.Cu")
		(net 85)
	)
	(segment
		(start 181.353 123.628)
		(end 181.376 123.605)
		(width 0.15)
		(layer "F.Cu")
		(net 85)
	)
	(via
		(at 181.376 123.605)
		(size 0.5)
		(drill 0.2)
		(layers "F.Cu" "B.Cu")
		(net 85)
	)
	(segment
		(start 181.376 123.605)
		(end 180.384 123.605)
		(width 0.15)
		(layer "B.Cu")
		(net 85)
	)
	(segment
		(start 192.171328 128.974306)
		(end 194.753477 128.974306)
		(width 0.2)
		(layer "B.Cu")
		(net 89)
	)
	(segment
		(start 194.753477 128.974306)
		(end 194.806328 129.027157)
		(width 0.2)
		(layer "B.Cu")
		(net 89)
	)
	(segment
		(start 203.171328 128.974306)
		(end 205.473477 128.974306)
		(width 0.2)
		(layer "B.Cu")
		(net 90)
	)
	(segment
		(start 205.473477 128.974306)
		(end 205.526328 129.027157)
		(width 0.2)
		(layer "B.Cu")
		(net 90)
	)
	(segment
		(start 170.536329 102.497157)
		(end 171.036328 102.997157)
		(width 0.15)
		(layer "F.Cu")
		(net 95)
	)
	(segment
		(start 172.0672 111.182)
		(end 171.3 111.9492)
		(width 0.1)
		(layer "F.Cu")
		(net 95)
	)
	(segment
		(start 172.359 111.182)
		(end 172.0672 111.182)
		(width 0.1)
		(layer "F.Cu")
		(net 95)
	)
	(segment
		(start 173.375 111.182)
		(end 173.375 110.651)
		(width 0.1)
		(layer "F.Cu")
		(net 95)
	)
	(segment
		(start 172.359 111.182)
		(end 173.375 111.182)
		(width 0.1)
		(layer "F.Cu")
		(net 95)
	)
	(via blind
		(at 171.04 102.997157)
		(size 0.5)
		(drill 0.2)
		(layers "F.Cu" "In2.Cu")
		(net 95)
	)
	(via
		(at 173.375 110.651)
		(size 0.5)
		(drill 0.2)
		(layers "F.Cu" "B.Cu")
		(net 95)
	)
	(segment
		(start 173.375 110.210829)
		(end 173.375 110.651)
		(width 0.1)
		(layer "In2.Cu")
		(net 95)
	)
	(segment
		(start 171.04 102.997157)
		(end 171.04 107.875829)
		(width 0.1)
		(layer "In2.Cu")
		(net 95)
	)
	(segment
		(start 171.04 107.875829)
		(end 173.375 110.210829)
		(width 0.1)
		(layer "In2.Cu")
		(net 95)
	)
	(segment
		(start 177.536329 106.497156)
		(end 177.536329 108.497157)
		(width 0.15)
		(layer "F.Cu")
		(net 192)
	)
	(segment
		(start 179.344 130.567)
		(end 179.344 131.352)
		(width 0.15)
		(layer "F.Cu")
		(net 192)
	)
	(via
		(at 177.536329 108.497157)
		(size 0.5)
		(drill 0.2)
		(layers "F.Cu" "B.Cu")
		(net 192)
	)
	(via
		(at 179.344 131.352)
		(size 0.5)
		(drill 0.2)
		(layers "F.Cu" "B.Cu")
		(net 192)
	)
	(segment
		(start 179.344 130.971)
		(end 179.344 131.86)
		(width 0.15)
		(layer "B.Cu")
		(net 192)
	)
	(segment
		(start 176.376989 128.003989)
		(end 179.344 130.971)
		(width 0.15)
		(layer "B.Cu")
		(net 192)
	)
	(segment
		(start 179.346666 132.973218)
		(end 179.344 131.86)
		(width 0.15)
		(layer "B.Cu")
		(net 192)
	)
	(segment
		(start 176.376989 110.316011)
		(end 176.376989 128.003989)
		(width 0.15)
		(layer "B.Cu")
		(net 192)
	)
	(segment
		(start 177.536329 109.156671)
		(end 176.376989 110.316011)
		(width 0.15)
		(layer "B.Cu")
		(net 192)
	)
	(segment
		(start 177.536329 108.497157)
		(end 177.536329 109.156671)
		(width 0.15)
		(layer "B.Cu")
		(net 192)
	)
	(segment
		(start 177.036329 105.997156)
		(end 177.03633 107.497157)
		(width 0.15)
		(layer "F.Cu")
		(net 193)
	)
	(segment
		(start 176.536329 105.497157)
		(end 177.036329 105.997156)
		(width 0.15)
		(layer "F.Cu")
		(net 193)
	)
	(segment
		(start 178.201 130.567)
		(end 178.201 131.352)
		(width 0.15)
		(layer "F.Cu")
		(net 193)
	)
	(segment
		(start 178.201 131.352)
		(end 178.246666 131.397666)
		(width 0.15)
		(layer "F.Cu")
		(net 193)
	)
	(via
		(at 177.03633 107.497157)
		(size 0.5)
		(drill 0.2)
		(layers "F.Cu" "B.Cu")
		(net 193)
	)
	(via
		(at 178.246666 131.397666)
		(size 0.5)
		(drill 0.2)
		(layers "F.Cu" "B.Cu")
		(net 193)
	)
	(segment
		(start 178.246666 132.973218)
		(end 178.246666 131.397666)
		(width 0.15)
		(layer "B.Cu")
		(net 193)
	)
	(segment
		(start 178.246666 130.889666)
		(end 178.246666 131.397666)
		(width 0.15)
		(layer "B.Cu")
		(net 193)
	)
	(segment
		(start 177.03633 109.02167)
		(end 176.042 110.016)
		(width 0.15)
		(layer "B.Cu")
		(net 193)
	)
	(segment
		(start 176.042 128.685)
		(end 178.246666 130.889666)
		(width 0.15)
		(layer "B.Cu")
		(net 193)
	)
	(segment
		(start 176.042 110.016)
		(end 176.042 128.685)
		(width 0.15)
		(layer "B.Cu")
		(net 193)
	)
	(segment
		(start 177.03633 107.497157)
		(end 177.03633 109.02167)
		(width 0.15)
		(layer "B.Cu")
		(net 193)
	)
	(segment
		(start 176.536329 106.497156)
		(end 176.536329 108.497157)
		(width 0.15)
		(layer "F.Cu")
		(net 194)
	)
	(segment
		(start 176.169 130.567)
		(end 176.169 131.352)
		(width 0.15)
		(layer "F.Cu")
		(net 194)
	)
	(via
		(at 176.536329 108.497157)
		(size 0.5)
		(drill 0.2)
		(layers "F.Cu" "B.Cu")
		(net 194)
	)
	(via
		(at 176.169 131.352)
		(size 0.5)
		(drill 0.2)
		(layers "F.Cu" "B.Cu")
		(net 194)
	)
	(segment
		(start 176.536329 108.497157)
		(end 175.741991 109.291495)
		(width 0.15)
		(layer "B.Cu")
		(net 194)
	)
	(segment
		(start 176.046666 132.973218)
		(end 176.046666 131.948218)
		(width 0.15)
		(layer "B.Cu")
		(net 194)
	)
	(segment
		(start 175.741991 129.146991)
		(end 176.169 129.574)
		(width 0.15)
		(layer "B.Cu")
		(net 194)
	)
	(segment
		(start 176.046666 131.948218)
		(end 176.169 131.825884)
		(width 0.15)
		(layer "B.Cu")
		(net 194)
	)
	(segment
		(start 176.169 131.825884)
		(end 176.169 131.352)
		(width 0.15)
		(layer "B.Cu")
		(net 194)
	)
	(segment
		(start 176.169 129.574)
		(end 176.169 131.352)
		(width 0.15)
		(layer "B.Cu")
		(net 194)
	)
	(segment
		(start 175.741991 109.291495)
		(end 175.741991 129.146991)
		(width 0.15)
		(layer "B.Cu")
		(net 194)
	)
	(segment
		(start 177.536328 104.497156)
		(end 178.036328 103.997157)
		(width 0.15)
		(layer "F.Cu")
		(net 195)
	)
	(segment
		(start 173.756 130.567)
		(end 173.756 131.479)
		(width 0.15)
		(layer "F.Cu")
		(net 195)
	)
	(via
		(at 178.036328 103.997157)
		(size 0.5)
		(drill 0.2)
		(layers "F.Cu" "B.Cu")
		(net 195)
	)
	(via
		(at 173.756 131.479)
		(size 0.5)
		(drill 0.2)
		(layers "F.Cu" "B.Cu")
		(net 195)
	)
	(segment
		(start 177.530586 106.241415)
		(end 177.530586 104.502899)
		(width 0.15)
		(layer "B.Cu")
		(net 195)
	)
	(segment
		(start 175.407 129.193)
		(end 175.407 108.365)
		(width 0.15)
		(layer "B.Cu")
		(net 195)
	)
	(segment
		(start 173.756 131.479)
		(end 173.756 130.844)
		(width 0.15)
		(layer "B.Cu")
		(net 195)
	)
	(segment
		(start 177.530586 104.502899)
		(end 178.036328 103.997157)
		(width 0.15)
		(layer "B.Cu")
		(net 195)
	)
	(segment
		(start 173.756 132.882552)
		(end 173.846666 132.973218)
		(width 0.15)
		(layer "B.Cu")
		(net 195)
	)
	(segment
		(start 173.756 130.844)
		(end 175.407 129.193)
		(width 0.15)
		(layer "B.Cu")
		(net 195)
	)
	(segment
		(start 175.407 108.365)
		(end 177.530586 106.241415)
		(width 0.15)
		(layer "B.Cu")
		(net 195)
	)
	(segment
		(start 173.756 131.479)
		(end 173.756 132.882552)
		(width 0.15)
		(layer "B.Cu")
		(net 195)
	)
	(segment
		(start 176.536329 104.497156)
		(end 177.03633 104.997157)
		(width 0.15)
		(layer "F.Cu")
		(net 196)
	)
	(segment
		(start 172.74 131.479)
		(end 172.746666 131.485666)
		(width 0.15)
		(layer "F.Cu")
		(net 196)
	)
	(segment
		(start 172.74 130.567)
		(end 172.74 131.479)
		(width 0.15)
		(layer "F.Cu")
		(net 196)
	)
	(via
		(at 177.03633 104.997157)
		(size 0.5)
		(drill 0.2)
		(layers "F.Cu" "B.Cu")
		(net 196)
	)
	(via
		(at 172.746666 131.485666)
		(size 0.5)
		(drill 0.2)
		(layers "F.Cu" "B.Cu")
		(net 196)
	)
	(segment
		(start 177.03633 104.997157)
		(end 177.03633 106.22767)
		(width 0.15)
		(layer "B.Cu")
		(net 196)
	)
	(segment
		(start 177.03633 106.22767)
		(end 175.10699 108.15701)
		(width 0.15)
		(layer "B.Cu")
		(net 196)
	)
	(segment
		(start 172.994 130.844)
		(end 172.746666 131.091334)
		(width 0.15)
		(layer "B.Cu")
		(net 196)
	)
	(segment
		(start 172.746666 132.973218)
		(end 172.746666 131.485666)
		(width 0.15)
		(layer "B.Cu")
		(net 196)
	)
	(segment
		(start 172.746666 131.091334)
		(end 172.746666 131.485666)
		(width 0.15)
		(layer "B.Cu")
		(net 196)
	)
	(segment
		(start 175.10699 128.98501)
		(end 173.248 130.844)
		(width 0.15)
		(layer "B.Cu")
		(net 196)
	)
	(segment
		(start 173.248 130.844)
		(end 172.994 130.844)
		(width 0.15)
		(layer "B.Cu")
		(net 196)
	)
	(segment
		(start 175.10699 108.15701)
		(end 175.10699 128.98501)
		(width 0.15)
		(layer "B.Cu")
		(net 196)
	)
	(segment
		(start 176.536329 103.497157)
		(end 177.036329 103.997157)
		(width 0.15)
		(layer "F.Cu")
		(net 197)
	)
	(segment
		(start 171.597 130.567)
		(end 171.597 131.479)
		(width 0.15)
		(layer "F.Cu")
		(net 197)
	)
	(via
		(at 177.036329 103.997157)
		(size 0.5)
		(drill 0.2)
		(layers "F.Cu" "B.Cu")
		(net 197)
	)
	(via
		(at 171.597 131.479)
		(size 0.5)
		(drill 0.2)
		(layers "F.Cu" "B.Cu")
		(net 197)
	)
	(segment
		(start 177.036329 103.997157)
		(end 176.536328 104.497158)
		(width 0.15)
		(layer "B.Cu")
		(net 197)
	)
	(segment
		(start 174.80698 108.032742)
		(end 174.80698 128.77702)
		(width 0.15)
		(layer "B.Cu")
		(net 197)
	)
	(segment
		(start 174.80698 128.77702)
		(end 173.04001 130.54399)
		(width 0.15)
		(layer "B.Cu")
		(net 197)
	)
	(segment
		(start 172.27801 130.54399)
		(end 171.597 131.225)
		(width 0.15)
		(layer "B.Cu")
		(net 197)
	)
	(segment
		(start 171.646666 131.528666)
		(end 171.597 131.479)
		(width 0.15)
		(layer "B.Cu")
		(net 197)
	)
	(segment
		(start 173.04001 130.54399)
		(end 172.27801 130.54399)
		(width 0.15)
		(layer "B.Cu")
		(net 197)
	)
	(segment
		(start 171.597 131.225)
		(end 171.597 131.479)
		(width 0.15)
		(layer "B.Cu")
		(net 197)
	)
	(segment
		(start 176.536328 104.497158)
		(end 176.536328 106.303394)
		(width 0.15)
		(layer "B.Cu")
		(net 197)
	)
	(segment
		(start 171.646666 131.556334)
		(end 171.646666 131.528666)
		(width 0.15)
		(layer "B.Cu")
		(net 197)
	)
	(segment
		(start 171.646666 132.973218)
		(end 171.646666 131.556334)
		(width 0.15)
		(layer "B.Cu")
		(net 197)
	)
	(segment
		(start 176.536328 106.303394)
		(end 174.80698 108.032742)
		(width 0.15)
		(layer "B.Cu")
		(net 197)
	)
	(segment
		(start 178.536329 106.497156)
		(end 178.536329 108.497157)
		(width 0.15)
		(layer "F.Cu")
		(net 198)
	)
	(segment
		(start 176.931 124.621)
		(end 177.797 124.621)
		(width 0.15)
		(layer "F.Cu")
		(net 198)
	)
	(segment
		(start 178.836 124.598)
		(end 177.693 124.598)
		(width 0.15)
		(layer "F.Cu")
		(net 198)
	)
	(via
		(at 178.536329 108.497157)
		(size 0.5)
		(drill 0.2)
		(layers "F.Cu" "B.Cu")
		(net 198)
	)
	(via
		(at 176.931 124.621)
		(size 0.5)
		(drill 0.2)
		(layers "F.Cu" "B.Cu")
		(net 198)
	)
	(segment
		(start 178.536329 108.664671)
		(end 176.677 110.524)
		(width 0.15)
		(layer "B.Cu")
		(net 198)
	)
	(segment
		(start 178.536329 108.497157)
		(end 178.536329 108.664671)
		(width 0.15)
		(layer "B.Cu")
		(net 198)
	)
	(segment
		(start 176.677 124.367)
		(end 176.931 124.621)
		(width 0.15)
		(layer "B.Cu")
		(net 198)
	)
	(segment
		(start 176.677 110.524)
		(end 176.677 124.367)
		(width 0.15)
		(layer "B.Cu")
		(net 198)
	)
	(segment
		(start 190.736328 65.663672)
		(end 191.436328 64.963672)
		(width 0.1)
		(layer "F.Cu")
		(net 206)
	)
	(segment
		(start 190.736328 71.212157)
		(end 190.736328 65.663672)
		(width 0.1)
		(layer "F.Cu")
		(net 206)
	)
	(segment
		(start 191.436328 64.963672)
		(end 191.436328 64.220008)
		(width 0.1)
		(layer "F.Cu")
		(net 206)
	)
	(segment
		(start 168.536329 90.497157)
		(end 168.036329 89.997157)
		(width 0.15)
		(layer "F.Cu")
		(net 208)
	)
	(segment
		(start 213.201328 92.435008)
		(end 213.186328 92.420008)
		(width 0.2)
		(layer "F.Cu")
		(net 208)
	)
	(segment
		(start 213.201328 93.220008)
		(end 213.201328 92.435008)
		(width 0.2)
		(layer "F.Cu")
		(net 208)
	)
	(segment
		(start 213.193336 93.22368)
		(end 213.193336 94.72168)
		(width 0.2)
		(layer "F.Cu")
		(net 208)
	)
	(via blind
		(at 168.036329 89.997157)
		(size 0.5)
		(drill 0.2)
		(layers "F.Cu" "In2.Cu")
		(net 208)
	)
	(via
		(at 213.186328 92.420008)
		(size 0.5)
		(drill 0.2)
		(layers "F.Cu" "B.Cu")
		(net 208)
	)
	(via
		(at 190.586328 89.920008)
		(size 0.5)
		(drill 0.2)
		(layers "F.Cu" "B.Cu")
		(net 208)
	)
	(segment
		(start 213.186328 92.420008)
		(end 210.686328 89.920008)
		(width 0.2)
		(layer "B.Cu")
		(net 208)
	)
	(segment
		(start 210.686328 89.920008)
		(end 190.586328 89.920008)
		(width 0.2)
		(layer "B.Cu")
		(net 208)
	)
	(segment
		(start 176.929212 94.497177)
		(end 177.543444 94.497177)
		(width 0.1)
		(layer "In2.Cu")
		(net 208)
	)
	(segment
		(start 189.271317 89.920008)
		(end 190.586328 89.920008)
		(width 0.1)
		(layer "In2.Cu")
		(net 208)
	)
	(segment
		(start 172.043442 93.997135)
		(end 173.450669 93.997135)
		(width 0.1)
		(layer "In2.Cu")
		(net 208)
	)
	(segment
		(start 177.543464 94.497157)
		(end 184.694168 94.497157)
		(width 0.1)
		(layer "In2.Cu")
		(net 208)
	)
	(segment
		(start 168.036329 89.997157)
		(end 168.286328 90.247156)
		(width 0.1)
		(layer "In2.Cu")
		(net 208)
	)
	(segment
		(start 175.555898 94.497157)
		(end 176.929192 94.497157)
		(width 0.1)
		(layer "In2.Cu")
		(net 208)
	)
	(segment
		(start 175.355886 94.697169)
		(end 175.555898 94.497157)
		(width 0.1)
		(layer "In2.Cu")
		(net 208)
	)
	(segment
		(start 168.286328 90.247156)
		(end 168.293463 90.247156)
		(width 0.1)
		(layer "In2.Cu")
		(net 208)
	)
	(segment
		(start 174.150703 94.697169)
		(end 175.355886 94.697169)
		(width 0.1)
		(layer "In2.Cu")
		(net 208)
	)
	(segment
		(start 184.694168 94.497157)
		(end 189.271317 89.920008)
		(width 0.1)
		(layer "In2.Cu")
		(net 208)
	)
	(segment
		(start 176.929192 94.497157)
		(end 176.929212 94.497177)
		(width 0.1)
		(layer "In2.Cu")
		(net 208)
	)
	(segment
		(start 173.450669 93.997135)
		(end 174.150703 94.697169)
		(width 0.1)
		(layer "In2.Cu")
		(net 208)
	)
	(segment
		(start 177.543444 94.497177)
		(end 177.543464 94.497157)
		(width 0.1)
		(layer "In2.Cu")
		(net 208)
	)
	(segment
		(start 168.293463 90.247156)
		(end 172.043442 93.997135)
		(width 0.1)
		(layer "In2.Cu")
		(net 208)
	)
	(segment
		(start 190.736328 73.697157)
		(end 190.736328 72.132157)
		(width 0.1)
		(layer "F.Cu")
		(net 209)
	)
	(segment
		(start 169.536329 91.497157)
		(end 170.036329 90.997156)
		(width 0.15)
		(layer "F.Cu")
		(net 210)
	)
	(segment
		(start 198.571336 86.235008)
		(end 197.486328 86.235008)
		(width 0.1)
		(layer "F.Cu")
		(net 210)
	)
	(segment
		(start 198.736328 86.4)
		(end 198.571336 86.235008)
		(width 0.1)
		(layer "F.Cu")
		(net 210)
	)
	(segment
		(start 194.371328 86.235008)
		(end 194.386328 86.220008)
		(width 0.1)
		(layer "F.Cu")
		(net 210)
	)
	(segment
		(start 194.301328 86.235008)
		(end 197.486328 86.235008)
		(width 0.1)
		(layer "F.Cu")
		(net 210)
	)
	(via blind
		(at 170.036329 90.997156)
		(size 0.5)
		(drill 0.2)
		(layers "F.Cu" "In2.Cu")
		(net 210)
	)
	(via
		(at 194.386328 86.220008)
		(size 0.5)
		(drill 0.2)
		(layers "F.Cu" "B.Cu")
		(net 210)
	)
	(segment
		(start 170.036329 91.636454)
		(end 172.146999 93.747124)
		(width 0.1)
		(layer "In2.Cu")
		(net 210)
	)
	(segment
		(start 189.402038 89.435718)
		(end 191.670618 89.435718)
		(width 0.1)
		(layer "In2.Cu")
		(net 210)
	)
	(segment
		(start 173.586295 93.747124)
		(end 174.286329 94.447158)
		(width 0.1)
		(layer "In2.Cu")
		(net 210)
	)
	(segment
		(start 175.492287 94.2072)
		(end 184.059852 94.2072)
		(width 0.1)
		(layer "In2.Cu")
		(net 210)
	)
	(segment
		(start 184.069896 94.197157)
		(end 184.6406 94.197157)
		(width 0.1)
		(layer "In2.Cu")
		(net 210)
	)
	(segment
		(start 172.146999 93.747124)
		(end 173.586295 93.747124)
		(width 0.1)
		(layer "In2.Cu")
		(net 210)
	)
	(segment
		(start 170.036329 90.997156)
		(end 170.036329 91.636454)
		(width 0.1)
		(layer "In2.Cu")
		(net 210)
	)
	(segment
		(start 184.6406 94.197157)
		(end 189.402038 89.435718)
		(width 0.1)
		(layer "In2.Cu")
		(net 210)
	)
	(segment
		(start 194.386328 86.720008)
		(end 194.386328 86.220008)
		(width 0.1)
		(layer "In2.Cu")
		(net 210)
	)
	(segment
		(start 184.059852 94.2072)
		(end 184.069896 94.197157)
		(width 0.1)
		(layer "In2.Cu")
		(net 210)
	)
	(segment
		(start 174.286329 94.447158)
		(end 175.252329 94.447158)
		(width 0.1)
		(layer "In2.Cu")
		(net 210)
	)
	(segment
		(start 175.252329 94.447158)
		(end 175.492287 94.2072)
		(width 0.1)
		(layer "In2.Cu")
		(net 210)
	)
	(segment
		(start 191.670618 89.435718)
		(end 194.386328 86.720008)
		(width 0.1)
		(layer "In2.Cu")
		(net 210)
	)
	(segment
		(start 198.736328 73.689)
		(end 198.736328 72.182157)
		(width 0.1)
		(layer "F.Cu")
		(net 211)
	)
	(segment
		(start 169.536329 100.497157)
		(end 170.036329 100.997157)
		(width 0.15)
		(layer "F.Cu")
		(net 212)
	)
	(segment
		(start 168.337 115.119)
		(end 168.314 115.096)
		(width 0.1)
		(layer "F.Cu")
		(net 212)
	)
	(segment
		(start 168.337 115.731)
		(end 168.337 115.119)
		(width 0.1)
		(layer "F.Cu")
		(net 212)
	)
	(via blind
		(at 170.036329 100.997157)
		(size 0.5)
		(drill 0.2)
		(layers "F.Cu" "In2.Cu")
		(net 212)
	)
	(via
		(at 168.314 115.096)
		(size 0.5)
		(drill 0.2)
		(layers "F.Cu" "B.Cu")
		(net 212)
	)
	(segment
		(start 168.337 115.731)
		(end 168.337 115.119)
		(width 0.1)
		(layer "B.Cu")
		(net 212)
	)
	(segment
		(start 168.337 115.119)
		(end 168.314 115.096)
		(width 0.1)
		(layer "B.Cu")
		(net 212)
	)
	(segment
		(start 170.083656 115.096)
		(end 170.586328 114.593328)
		(width 0.1)
		(layer "In2.Cu")
		(net 212)
	)
	(segment
		(start 170.586328 101.547156)
		(end 170.586328 114.593328)
		(width 0.1)
		(layer "In2.Cu")
		(net 212)
	)
	(segment
		(start 168.314 115.096)
		(end 170.083656 115.096)
		(width 0.1)
		(layer "In2.Cu")
		(net 212)
	)
	(segment
		(start 170.036329 100.997157)
		(end 170.586328 101.547156)
		(width 0.1)
		(layer "In2.Cu")
		(net 212)
	)
	(segment
		(start 173.536329 91.497157)
		(end 174.036329 91.997157)
		(width 0.15)
		(layer "F.Cu")
		(net 213)
	)
	(segment
		(start 173.536328 91.497157)
		(end 173.536329 91.497157)
		(width 0.15)
		(layer "F.Cu")
		(net 213)
	)
	(segment
		(start 180.6735 118.271)
		(end 181.4585 118.271)
		(width 0.1)
		(layer "F.Cu")
		(net 213)
	)
	(via blind
		(at 174.036329 91.997157)
		(size 0.5)
		(drill 0.2)
		(layers "F.Cu" "In2.Cu")
		(net 213)
	)
	(via
		(at 181.4585 118.271)
		(size 0.5)
		(drill 0.2)
		(layers "F.Cu" "B.Cu")
		(net 213)
	)
	(via
		(at 182.4555 92.49)
		(size 0.5)
		(drill 0.2)
		(layers "F.Cu" "B.Cu")
		(net 213)
	)
	(segment
		(start 182.136328 117.593172)
		(end 181.4585 118.271)
		(width 0.1)
		(layer "B.Cu")
		(net 213)
	)
	(segment
		(start 182.136328 92.809172)
		(end 182.136328 117.593172)
		(width 0.1)
		(layer "B.Cu")
		(net 213)
	)
	(segment
		(start 181.4585 118.271)
		(end 180.6735 118.271)
		(width 0.1)
		(layer "B.Cu")
		(net 213)
	)
	(segment
		(start 182.4555 92.49)
		(end 182.136328 92.809172)
		(width 0.1)
		(layer "B.Cu")
		(net 213)
	)
	(segment
		(start 180.6735 118.271)
		(end 180.6735 119.541)
		(width 0.1)
		(layer "B.Cu")
		(net 213)
	)
	(segment
		(start 180.786328 92.497157)
		(end 181.246317 92.957146)
		(width 0.1)
		(layer "In2.Cu")
		(net 213)
	)
	(segment
		(start 181.246317 92.957146)
		(end 181.988354 92.957146)
		(width 0.1)
		(layer "In2.Cu")
		(net 213)
	)
	(segment
		(start 181.988354 92.957146)
		(end 182.4555 92.49)
		(width 0.1)
		(layer "In2.Cu")
		(net 213)
	)
	(segment
		(start 174.536328 92.497157)
		(end 180.786328 92.497157)
		(width 0.1)
		(layer "In2.Cu")
		(net 213)
	)
	(segment
		(start 174.036329 91.997157)
		(end 174.536328 92.497157)
		(width 0.1)
		(layer "In2.Cu")
		(net 213)
	)
	(segment
		(start 171.536329 103.497157)
		(end 172.036329 103.997157)
		(width 0.15)
		(layer "F.Cu")
		(net 217)
	)
	(segment
		(start 170.6 109.8492)
		(end 171.010828 109.8492)
		(width 0.2)
		(layer "F.Cu")
		(net 217)
	)
	(via
		(at 172.029729 103.997157)
		(size 0.5)
		(drill 0.2)
		(layers "F.Cu" "B.Cu")
		(net 217)
	)
	(via
		(at 171.010828 109.8492)
		(size 0.5)
		(drill 0.2)
		(layers "F.Cu" "B.Cu")
		(net 217)
	)
	(segment
		(start 172.036329 103.989729)
		(end 172.036329 108.823699)
		(width 0.15)
		(layer "B.Cu")
		(net 217)
	)
	(segment
		(start 172.036329 108.823699)
		(end 171.010828 109.8492)
		(width 0.15)
		(layer "B.Cu")
		(net 217)
	)
	(segment
		(start 168.536329 91.497157)
		(end 168.036329 90.997157)
		(width 0.15)
		(layer "F.Cu")
		(net 219)
	)
	(segment
		(start 188.401328 92.720008)
		(end 187.886328 92.720008)
		(width 0.1)
		(layer "F.Cu")
		(net 219)
	)
	(via blind
		(at 168.036329 90.997157)
		(size 0.5)
		(drill 0.2)
		(layers "F.Cu" "In2.Cu")
		(net 219)
	)
	(via
		(at 187.886328 92.720008)
		(size 0.5)
		(drill 0.2)
		(layers "F.Cu" "B.Cu")
		(net 219)
	)
	(segment
		(start 184.101304 95.797157)
		(end 187.178454 92.720008)
		(width 0.1)
		(layer "In2.Cu")
		(net 219)
	)
	(segment
		(start 171.536329 94.497157)
		(end 173.243555 94.497157)
		(width 0.1)
		(layer "In2.Cu")
		(net 219)
	)
	(segment
		(start 174.543555 95.797157)
		(end 184.101304 95.797157)
		(width 0.1)
		(layer "In2.Cu")
		(net 219)
	)
	(segment
		(start 173.243555 94.497157)
		(end 174.543555 95.797157)
		(width 0.1)
		(layer "In2.Cu")
		(net 219)
	)
	(segment
		(start 168.036329 90.997157)
		(end 171.536329 94.497157)
		(width 0.1)
		(layer "In2.Cu")
		(net 219)
	)
	(segment
		(start 187.178454 92.720008)
		(end 187.886328 92.720008)
		(width 0.1)
		(layer "In2.Cu")
		(net 219)
	)
	(segment
		(start 123.425 55.65)
		(end 122.3 55.65)
		(width 0.3)
		(layer "F.Cu")
		(net 224)
	)
	(segment
		(start 109.6 114.6)
		(end 109.03 114.6)
		(width 0.2)
		(layer "F.Cu")
		(net 224)
	)
	(segment
		(start 108.815 114.815)
		(end 108.815 115.7)
		(width 0.2)
		(layer "F.Cu")
		(net 224)
	)
	(segment
		(start 109.03 114.6)
		(end 108.815 114.815)
		(width 0.2)
		(layer "F.Cu")
		(net 224)
	)
	(segment
		(start 123.742672 55.967672)
		(end 123.425 55.65)
		(width 0.3)
		(layer "F.Cu")
		(net 224)
	)
	(segment
		(start 124.997157 55.967672)
		(end 123.742672 55.967672)
		(width 0.3)
		(layer "F.Cu")
		(net 224)
	)
	(via
		(at 109.4 128.2)
		(size 0.5)
		(drill 0.2)
		(layers "F.Cu" "B.Cu")
		(free yes)
		(net 224)
	)
	(via
		(at 120.2 54.9)
		(size 0.5)
		(drill 0.2)
		(layers "F.Cu" "B.Cu")
		(free yes)
		(net 224)
	)
	(via
		(at 108.8 127)
		(size 0.5)
		(drill 0.2)
		(layers "F.Cu" "B.Cu")
		(free yes)
		(net 224)
	)
	(via
		(at 108.8 126.2)
		(size 0.5)
		(drill 0.2)
		(layers "F.Cu" "B.Cu")
		(free yes)
		(net 224)
	)
	(via
		(at 120.8 54.9)
		(size 0.5)
		(drill 0.2)
		(layers "F.Cu" "B.Cu")
		(free yes)
		(net 224)
	)
	(via
		(at 110.3 114.6)
		(size 0.5)
		(drill 0.2)
		(layers "F.Cu" "B.Cu")
		(free yes)
		(net 224)
	)
	(via
		(at 109.4 125)
		(size 0.5)
		(drill 0.2)
		(layers "F.Cu" "B.Cu")
		(free yes)
		(net 224)
	)
	(via
		(at 122.6 54.9)
		(size 0.5)
		(drill 0.2)
		(layers "F.Cu" "B.Cu")
		(free yes)
		(net 224)
	)
	(via
		(at 109.6 114.6)
		(size 0.5)
		(drill 0.2)
		(layers "F.Cu" "B.Cu")
		(free yes)
		(net 224)
	)
	(via
		(at 111 114.6)
		(size 0.5)
		(drill 0.2)
		(layers "F.Cu" "B.Cu")
		(free yes)
		(net 224)
	)
	(via
		(at 110 114)
		(size 0.5)
		(drill 0.2)
		(layers "F.Cu" "B.Cu")
		(free yes)
		(net 224)
	)
	(via
		(at 122 54.9)
		(size 0.5)
		(drill 0.2)
		(layers "F.Cu" "B.Cu")
		(free yes)
		(net 224)
	)
	(via
		(at 121.4 54.9)
		(size 0.5)
		(drill 0.2)
		(layers "F.Cu" "B.Cu")
		(free yes)
		(net 224)
	)
	(via
		(at 110.7 114)
		(size 0.5)
		(drill 0.2)
		(layers "F.Cu" "B.Cu")
		(free yes)
		(net 224)
	)
	(via
		(at 121.4 55.5)
		(size 0.5)
		(drill 0.2)
		(layers "F.Cu" "B.Cu")
		(free yes)
		(net 224)
	)
	(via
		(at 109.4 126.6)
		(size 0.5)
		(drill 0.2)
		(layers "F.Cu" "B.Cu")
		(free yes)
		(net 224)
	)
	(via
		(at 108.8 128.6)
		(size 0.5)
		(drill 0.2)
		(layers "F.Cu" "B.Cu")
		(free yes)
		(net 224)
	)
	(via
		(at 108.8 127.8)
		(size 0.5)
		(drill 0.2)
		(layers "F.Cu" "B.Cu")
		(free yes)
		(net 224)
	)
	(via
		(at 109.4 127.4)
		(size 0.5)
		(drill 0.2)
		(layers "F.Cu" "B.Cu")
		(free yes)
		(net 224)
	)
	(via
		(at 109.4 129)
		(size 0.5)
		(drill 0.2)
		(layers "F.Cu" "B.Cu")
		(free yes)
		(net 224)
	)
	(via
		(at 120.2 55.5)
		(size 0.5)
		(drill 0.2)
		(layers "F.Cu" "B.Cu")
		(free yes)
		(net 224)
	)
	(via
		(at 111.3 114)
		(size 0.5)
		(drill 0.2)
		(layers "F.Cu" "B.Cu")
		(free yes)
		(net 224)
	)
	(via
		(at 108.8 125.4)
		(size 0.5)
		(drill 0.2)
		(layers "F.Cu" "B.Cu")
		(free yes)
		(net 224)
	)
	(via
		(at 120.8 55.5)
		(size 0.5)
		(drill 0.2)
		(layers "F.Cu" "B.Cu")
		(free yes)
		(net 224)
	)
	(via
		(at 109.4 125.8)
		(size 0.5)
		(drill 0.2)
		(layers "F.Cu" "B.Cu")
		(free yes)
		(net 224)
	)
	(via
		(at 108.8 124.6)
		(size 0.5)
		(drill 0.2)
		(layers "F.Cu" "B.Cu")
		(free yes)
		(net 224)
	)
	(segment
		(start 194.736328 73.689)
		(end 194.736328 72.182157)
		(width 0.1)
		(layer "F.Cu")
		(net 228)
	)
	(segment
		(start 191.389171 121.074485)
		(end 191.389171 122.559485)
		(width 0.25)
		(layer "F.Cu")
		(net 229)
	)
	(segment
		(start 191.389171 122.559485)
		(end 191.374171 122.574485)
		(width 0.25)
		(layer "F.Cu")
		(net 229)
	)
	(segment
		(start 202.736328 73.747157)
		(end 202.736328 72.182157)
		(width 0.1)
		(layer "F.Cu")
		(net 230)
	)
	(segment
		(start 206.736328 73.747157)
		(end 206.736328 72.182157)
		(width 0.1)
		(layer "F.Cu")
		(net 231)
	)
	(segment
		(start 201.006336 84.820008)
		(end 200.636328 84.45)
		(width 0.2)
		(layer "F.Cu")
		(net 232)
	)
	(segment
		(start 201.901328 84.820008)
		(end 201.006336 84.820008)
		(width 0.2)
		(layer "F.Cu")
		(net 232)
	)
	(segment
		(start 201.901328 86.620008)
		(end 201.06632 86.620008)
		(width 0.2)
		(layer "F.Cu")
		(net 233)
	)
	(segment
		(start 201.06632 86.620008)
		(end 200.636328 87.05)
		(width 0.2)
		(layer "F.Cu")
		(net 233)
	)
	(segment
		(start 141.7325 89.6)
		(end 140.6675 89.6)
		(width 0.2)
		(layer "F.Cu")
		(net 234)
	)
	(segment
		(start 141.7325 92.1)
		(end 140.6675 92.1)
		(width 0.2)
		(layer "F.Cu")
		(net 235)
	)
	(segment
		(start 141.7325 87.1)
		(end 140.6675 87.1)
		(width 0.2)
		(layer "F.Cu")
		(net 236)
	)
	(segment
		(start 141.7325 84.7)
		(end 140.6675 84.7)
		(width 0.2)
		(layer "F.Cu")
		(net 237)
	)
	(segment
		(start 125.115 67.65)
		(end 123.7 67.65)
		(width 0.15)
		(layer "B.Cu")
		(net 238)
	)
	(segment
		(start 123.65 67.6)
		(end 123.65 68.485)
		(width 0.15)
		(layer "B.Cu")
		(net 238)
	)
	(segment
		(start 123.65 68.485)
		(end 123.185 68.95)
		(width 0.15)
		(layer "B.Cu")
		(net 238)
	)
	(segment
		(start 123.7 67.65)
		(end 123.65 67.6)
		(width 0.15)
		(layer "B.Cu")
		(net 238)
	)
	(segment
		(start 140 113.918485)
		(end 139.776328 114.142157)
		(width 0.15)
		(layer "F.Cu")
		(net 239)
	)
	(segment
		(start 140 111.7875)
		(end 140 113.918485)
		(width 0.15)
		(layer "F.Cu")
		(net 239)
	)
	(segment
		(start 144.384171 113.45)
		(end 145.046328 114.112157)
		(width 0.15)
		(layer "F.Cu")
		(net 240)
	)
	(segment
		(start 142.5 111.7875)
		(end 142.5 112.4)
		(width 0.15)
		(layer "F.Cu")
		(net 240)
	)
	(segment
		(start 143.55 113.45)
		(end 144.384171 113.45)
		(width 0.15)
		(layer "F.Cu")
		(net 240)
	)
	(segment
		(start 142.5 112.4)
		(end 143.55 113.45)
		(width 0.15)
		(layer "F.Cu")
		(net 240)
	)
	(segment
		(start 143.722157 113.122157)
		(end 143 112.4)
		(width 0.15)
		(layer "F.Cu")
		(net 241)
	)
	(segment
		(start 143 112.4)
		(end 143 111.7875)
		(width 0.15)
		(layer "F.Cu")
		(net 241)
	)
	(segment
		(start 147.551328 113.122157)
		(end 143.722157 113.122157)
		(width 0.15)
		(layer "F.Cu")
		(net 241)
	)
	(segment
		(start 143.75 112.55)
		(end 147.003485 112.55)
		(width 0.15)
		(layer "F.Cu")
		(net 242)
	)
	(segment
		(start 143.5 111.7875)
		(end 143.5 112.3)
		(width 0.15)
		(layer "F.Cu")
		(net 242)
	)
	(segment
		(start 147.003485 112.55)
		(end 147.571328 111.982157)
		(width 0.15)
		(layer "F.Cu")
		(net 242)
	)
	(segment
		(start 143.5 112.3)
		(end 143.75 112.55)
		(width 0.15)
		(layer "F.Cu")
		(net 242)
	)
	(segment
		(start 146.690985 111.7875)
		(end 147.571328 110.907157)
		(width 0.15)
		(layer "F.Cu")
		(net 243)
	)
	(segment
		(start 144 111.7875)
		(end 146.690985 111.7875)
		(width 0.15)
		(layer "F.Cu")
		(net 243)
	)
	(segment
		(start 118.518672 118.975)
		(end 117.55 118.975)
		(width 0.2)
		(layer "F.Cu")
		(net 244)
	)
	(segment
		(start 146.35 111.1)
		(end 147.571328 109.878672)
		(width 0.15)
		(layer "F.Cu")
		(net 245)
	)
	(segment
		(start 147.571328 109.878672)
		(end 147.571328 109.832157)
		(width 0.15)
		(layer "F.Cu")
		(net 245)
	)
	(segment
		(start 144.6875 111.1)
		(end 146.35 111.1)
		(width 0.15)
		(layer "F.Cu")
		(net 245)
	)
	(segment
		(start 147.419171 107.6)
		(end 147.566328 107.747157)
		(width 0.15)
		(layer "F.Cu")
		(net 246)
	)
	(segment
		(start 144.6875 107.6)
		(end 147.419171 107.6)
		(width 0.15)
		(layer "F.Cu")
		(net 246)
	)
	(segment
		(start 144.6875 107.1)
		(end 147.073485 107.1)
		(width 0.15)
		(layer "F.Cu")
		(net 247)
	)
	(segment
		(start 147.073485 107.1)
		(end 147.551328 106.622157)
		(width 0.15)
		(layer "F.Cu")
		(net 247)
	)
	(segment
		(start 144.6875 106.6)
		(end 146.448485 106.6)
		(width 0.15)
		(layer "F.Cu")
		(net 248)
	)
	(segment
		(start 146.448485 106.6)
		(end 147.551328 105.497157)
		(width 0.15)
		(layer "F.Cu")
		(net 248)
	)
	(segment
		(start 145.823485 106.1)
		(end 147.551328 104.372157)
		(width 0.15)
		(layer "F.Cu")
		(net 249)
	)
	(segment
		(start 144.6875 106.1)
		(end 145.823485 106.1)
		(width 0.15)
		(layer "F.Cu")
		(net 249)
	)
	(segment
		(start 145.6 105.1)
		(end 144.6875 105.1)
		(width 0.15)
		(layer "F.Cu")
		(net 250)
	)
	(segment
		(start 147.551328 102.122157)
		(end 146.477843 102.122157)
		(width 0.15)
		(layer "F.Cu")
		(net 250)
	)
	(segment
		(start 145.95 102.65)
		(end 145.95 104.75)
		(width 0.15)
		(layer "F.Cu")
		(net 250)
	)
	(segment
		(start 145.95 104.75)
		(end 145.6 105.1)
		(width 0.15)
		(layer "F.Cu")
		(net 250)
	)
	(segment
		(start 146.477843 102.122157)
		(end 145.95 102.65)
		(width 0.15)
		(layer "F.Cu")
		(net 250)
	)
	(segment
		(start 142.5 100.768485)
		(end 142.536328 100.732157)
		(width 0.15)
		(layer "F.Cu")
		(net 251)
	)
	(segment
		(start 142.5 103.9125)
		(end 142.5 100.768485)
		(width 0.15)
		(layer "F.Cu")
		(net 251)
	)
	(segment
		(start 142 103.9125)
		(end 142 101.320829)
		(width 0.15)
		(layer "F.Cu")
		(net 252)
	)
	(segment
		(start 142 101.320829)
		(end 141.411328 100.732157)
		(width 0.15)
		(layer "F.Cu")
		(net 252)
	)
	(segment
		(start 134.396328 102.622157)
		(end 137.272157 102.622157)
		(width 0.15)
		(layer "F.Cu")
		(net 253)
	)
	(segment
		(start 137.272157 102.622157)
		(end 137.5 102.85)
		(width 0.15)
		(layer "F.Cu")
		(net 253)
	)
	(segment
		(start 137.5 102.85)
		(end 137.5 103.9125)
		(width 0.15)
		(layer "F.Cu")
		(net 253)
	)
	(segment
		(start 135.9 106.4)
		(end 134.924171 106.4)
		(width 0.15)
		(layer "F.Cu")
		(net 254)
	)
	(segment
		(start 136.2 106.1)
		(end 135.9 106.4)
		(width 0.15)
		(layer "F.Cu")
		(net 254)
	)
	(segment
		(start 134.924171 106.4)
		(end 134.396328 105.872157)
		(width 0.15)
		(layer "F.Cu")
		(net 254)
	)
	(segment
		(start 136.8125 106.1)
		(end 136.2 106.1)
		(width 0.15)
		(layer "F.Cu")
		(net 254)
	)
	(segment
		(start 169.307 115.731)
		(end 170.6 115.731)
		(width 0.1)
		(layer "F.Cu")
		(net 255)
	)
	(segment
		(start 178.347 118.271)
		(end 179.7035 118.271)
		(width 0.1)
		(layer "F.Cu")
		(net 256)
	)
	(segment
		(start 178.347 117.001)
		(end 179.7035 117.001)
		(width 0.1)
		(layer "F.Cu")
		(net 257)
	)
	(segment
		(start 169.307 118.271)
		(end 170.6 118.271)
		(width 0.1)
		(layer "F.Cu")
		(net 258)
	)
	(segment
		(start 179.6925 119.53)
		(end 178.3485 119.53)
		(width 0.1)
		(layer "F.Cu")
		(net 259)
	)
	(segment
		(start 169.307 117.001)
		(end 170.6 117.001)
		(width 0.1)
		(layer "F.Cu")
		(net 260)
	)
	(segment
		(start 197.009179 105.797157)
		(end 193.778477 105.797157)
		(width 0.15)
		(layer "F.Cu")
		(net 261)
	)
	(segment
		(start 193.778477 105.797157)
		(end 193.586328 105.989306)
		(width 0.15)
		(layer "F.Cu")
		(net 261)
	)
	(segment
		(start 136.015 96.484143)
		(end 136.024143 96.475)
		(width 0.2)
		(layer "F.Cu")
		(net 262)
	)
	(segment
		(start 136.015 98.25)
		(end 136.015 96.484143)
		(width 0.2)
		(layer "F.Cu")
		(net 262)
	)
	(segment
		(start 134.935 78.15)
		(end 134.685 78.4)
		(width 0.2)
		(layer "B.Cu")
		(net 263)
	)
	(segment
		(start 135.725 78.15)
		(end 134.935 78.15)
		(width 0.2)
		(layer "B.Cu")
		(net 263)
	)
	(segment
		(start 133.8 79.7)
		(end 134.685 78.815)
		(width 0.2)
		(layer "B.Cu")
		(net 263)
	)
	(segment
		(start 134.685 78.4)
		(end 134.685 78.815)
		(width 0.2)
		(layer "B.Cu")
		(net 263)
	)
	(segment
		(start 133.715 79.7)
		(end 133.8 79.7)
		(width 0.2)
		(layer "B.Cu")
		(net 263)
	)
	(segment
		(start 134.685 70.415)
		(end 133.8 71.3)
		(width 0.2)
		(layer "B.Cu")
		(net 264)
	)
	(segment
		(start 135.725 69.75)
		(end 134.935 69.75)
		(width 0.2)
		(layer "B.Cu")
		(net 264)
	)
	(segment
		(start 134.935 69.75)
		(end 134.685 70)
		(width 0.2)
		(layer "B.Cu")
		(net 264)
	)
	(segment
		(start 133.8 71.3)
		(end 133.715 71.3)
		(width 0.2)
		(layer "B.Cu")
		(net 264)
	)
	(segment
		(start 134.685 70)
		(end 134.685 70.415)
		(width 0.2)
		(layer "B.Cu")
		(net 264)
	)
	(segment
		(start 144.6875 109.6)
		(end 145.6508 109.6)
		(width 0.15)
		(layer "F.Cu")
		(net 265)
	)
	(segment
		(start 145.6508 109.6)
		(end 146.1 109.1508)
		(width 0.15)
		(layer "F.Cu")
		(net 265)
	)
	(segment
		(start 179.039171 86)
		(end 179.536328 86.497157)
		(width 0.1)
		(layer "F.Cu")
		(net 271)
	)
	(segment
		(start 175.536328 86.497157)
		(end 176.033485 86)
		(width 0.1)
		(layer "F.Cu")
		(net 271)
	)
	(segment
		(start 173.536328 86.497157)
		(end 174.033485 86)
		(width 0.1)
		(layer "F.Cu")
		(net 271)
	)
	(segment
		(start 175.039171 86)
		(end 175.536328 86.497157)
		(width 0.1)
		(layer "F.Cu")
		(net 271)
	)
	(segment
		(start 174.033485 86)
		(end 175.039171 86)
		(width 0.1)
		(layer "F.Cu")
		(net 271)
	)
	(segment
		(start 178.033485 86)
		(end 179.039171 86)
		(width 0.1)
		(layer "F.Cu")
		(net 271)
	)
	(segment
		(start 177.039171 86)
		(end 177.536328 86.497157)
		(width 0.1)
		(layer "F.Cu")
		(net 271)
	)
	(segment
		(start 176.033485 86)
		(end 177.039171 86)
		(width 0.1)
		(layer "F.Cu")
		(net 271)
	)
	(segment
		(start 177.536328 86.497157)
		(end 178.033485 86)
		(width 0.1)
		(layer "F.Cu")
		(net 271)
	)
	(via
		(at 141.5 76.3)
		(size 0.5)
		(drill 0.2)
		(layers "F.Cu" "B.Cu")
		(free yes)
		(net 273)
	)
	(via
		(at 183.4 77.5)
		(size 0.5)
		(drill 0.2)
		(layers "F.Cu" "B.Cu")
		(net 273)
	)
	(via
		(at 142.1 76.7)
		(size 0.5)
		(drill 0.2)
		(layers "F.Cu" "B.Cu")
		(free yes)
		(net 273)
	)
	(via
		(at 182.2 75.9)
		(size 0.5)
		(drill 0.2)
		(layers "F.Cu" "B.Cu")
		(net 273)
	)
	(via
		(at 183.4 76.7)
		(size 0.5)
		(drill 0.2)
		(layers "F.Cu" "B.Cu")
		(net 273)
	)
	(via
		(at 140.3 76.3)
		(size 0.5)
		(drill 0.2)
		(layers "F.Cu" "B.Cu")
		(free yes)
		(net 273)
	)
	(via
		(at 143.3 77.5)
		(size 0.5)
		(drill 0.2)
		(layers "F.Cu" "B.Cu")
		(free yes)
		(net 273)
	)
	(via
		(at 183.4 75.9)
		(size 0.5)
		(drill 0.2)
		(layers "F.Cu" "B.Cu")
		(net 273)
	)
	(via
		(at 181.6 76.3)
		(size 0.5)
		(drill 0.2)
		(layers "F.Cu" "B.Cu")
		(net 273)
	)
	(via
		(at 180.4 77.1)
		(size 0.5)
		(drill 0.2)
		(layers "F.Cu" "B.Cu")
		(net 273)
	)
	(via
		(at 181 75.9)
		(size 0.5)
		(drill 0.2)
		(layers "F.Cu" "B.Cu")
		(net 273)
	)
	(via
		(at 181 76.7)
		(size 0.5)
		(drill 0.2)
		(layers "F.Cu" "B.Cu")
		(net 273)
	)
	(via
		(at 180.4 76.3)
		(size 0.5)
		(drill 0.2)
		(layers "F.Cu" "B.Cu")
		(net 273)
	)
	(via
		(at 182.8 77.1)
		(size 0.5)
		(drill 0.2)
		(layers "F.Cu" "B.Cu")
		(net 273)
	)
	(via
		(at 182.2 76.7)
		(size 0.5)
		(drill 0.2)
		(layers "F.Cu" "B.Cu")
		(net 273)
	)
	(via
		(at 181 77.5)
		(size 0.5)
		(drill 0.2)
		(layers "F.Cu" "B.Cu")
		(net 273)
	)
	(via
		(at 140.9 75.9)
		(size 0.5)
		(drill 0.2)
		(layers "F.Cu" "B.Cu")
		(free yes)
		(net 273)
	)
	(via
		(at 142.7 77.1)
		(size 0.5)
		(drill 0.2)
		(layers "F.Cu" "B.Cu")
		(free yes)
		(net 273)
	)
	(via
		(at 181.6 77.1)
		(size 0.5)
		(drill 0.2)
		(layers "F.Cu" "B.Cu")
		(net 273)
	)
	(via
		(at 182.2 77.5)
		(size 0.5)
		(drill 0.2)
		(layers "F.Cu" "B.Cu")
		(net 273)
	)
	(via
		(at 143.3 75.9)
		(size 0.5)
		(drill 0.2)
		(layers "F.Cu" "B.Cu")
		(free yes)
		(net 273)
	)
	(via
		(at 141.5 77.1)
		(size 0.5)
		(drill 0.2)
		(layers "F.Cu" "B.Cu")
		(free yes)
		(net 273)
	)
	(via
		(at 142.1 75.9)
		(size 0.5)
		(drill 0.2)
		(layers "F.Cu" "B.Cu")
		(free yes)
		(net 273)
	)
	(via
		(at 140.3 77.1)
		(size 0.5)
		(drill 0.2)
		(layers "F.Cu" "B.Cu")
		(free yes)
		(net 273)
	)
	(via
		(at 182.8 76.3)
		(size 0.5)
		(drill 0.2)
		(layers "F.Cu" "B.Cu")
		(net 273)
	)
	(via
		(at 140.9 76.7)
		(size 0.5)
		(drill 0.2)
		(layers "F.Cu" "B.Cu")
		(free yes)
		(net 273)
	)
	(via
		(at 142.1 77.5)
		(size 0.5)
		(drill 0.2)
		(layers "F.Cu" "B.Cu")
		(free yes)
		(net 273)
	)
	(via
		(at 140.9 77.5)
		(size 0.5)
		(drill 0.2)
		(layers "F.Cu" "B.Cu")
		(free yes)
		(net 273)
	)
	(via
		(at 142.7 76.3)
		(size 0.5)
		(drill 0.2)
		(layers "F.Cu" "B.Cu")
		(free yes)
		(net 273)
	)
	(via
		(at 143.3 76.7)
		(size 0.5)
		(drill 0.2)
		(layers "F.Cu" "B.Cu")
		(free yes)
		(net 273)
	)
	(segment
		(start 177.039171 90)
		(end 177.536328 90.497157)
		(width 0.1)
		(layer "F.Cu")
		(net 275)
	)
	(segment
		(start 179.039171 90)
		(end 179.536328 90.497157)
		(width 0.1)
		(layer "F.Cu")
		(net 275)
	)
	(segment
		(start 177.536328 90.497157)
		(end 178.033485 90)
		(width 0.1)
		(layer "F.Cu")
		(net 275)
	)
	(segment
		(start 175.039171 90)
		(end 175.536328 90.497157)
		(width 0.1)
		(layer "F.Cu")
		(net 275)
	)
	(segment
		(start 174.033485 90)
		(end 175.039171 90)
		(width 0.1)
		(layer "F.Cu")
		(net 275)
	)
	(segment
		(start 178.033485 90)
		(end 179.039171 90)
		(width 0.1)
		(layer "F.Cu")
		(net 275)
	)
	(segment
		(start 173.536328 90.497157)
		(end 174.033485 90)
		(width 0.1)
		(layer "F.Cu")
		(net 275)
	)
	(segment
		(start 176.033485 90)
		(end 177.039171 90)
		(width 0.1)
		(layer "F.Cu")
		(net 275)
	)
	(segment
		(start 175.536328 90.497157)
		(end 176.033485 90)
		(width 0.1)
		(layer "F.Cu")
		(net 275)
	)
	(segment
		(start 158.575282 84.302)
		(end 158.834 84.302)
		(width 0.182)
		(layer "F.Cu")
		(net 332)
	)
	(segment
		(start 159 83.472)
		(end 159 80.55)
		(width 0.182)
		(layer "F.Cu")
		(net 332)
	)
	(segment
		(start 158.834 83.97)
		(end 158.575282 83.97)
		(width 0.182)
		(layer "F.Cu")
		(net 332)
	)
	(segment
		(start 159.536328 80.013672)
		(end 159.536328 78.847157)
		(width 0.182)
		(layer "F.Cu")
		(net 332)
	)
	(segment
		(start 159 85.033485)
		(end 159 84.8)
		(width 0.182)
		(layer "F.Cu")
		(net 332)
	)
	(segment
		(start 158.575282 83.638)
		(end 158.834 83.638)
		(width 0.182)
		(layer "F.Cu")
		(net 332)
	)
	(segment
		(start 158.536328 85.497157)
		(end 159 85.033485)
		(width 0.182)
		(layer "F.Cu")
		(net 332)
	)
	(segment
		(start 158.834 84.634)
		(end 158.575282 84.634)
		(width 0.182)
		(layer "F.Cu")
		(net 332)
	)
	(segment
		(start 159 80.55)
		(end 159.536328 80.013672)
		(width 0.182)
		(layer "F.Cu")
		(net 332)
	)
	(arc
		(start 158.575282 83.97)
		(mid 158.457902 83.92138)
		(end 158.409282 83.804)
		(width 0.182)
		(layer "F.Cu")
		(net 332)
	)
	(arc
		(start 159 84.136)
		(mid 158.95138 84.01862)
		(end 158.834 83.97)
		(width 0.182)
		(layer "F.Cu")
		(net 332)
	)
	(arc
		(start 158.834 84.302)
		(mid 158.95138 84.25338)
		(end 159 84.136)
		(width 0.182)
		(layer "F.Cu")
		(net 332)
	)
	(arc
		(start 158.409282 84.468)
		(mid 158.457902 84.35062)
		(end 158.575282 84.302)
		(width 0.182)
		(layer "F.Cu")
		(net 332)
	)
	(arc
		(start 158.575282 84.634)
		(mid 158.457902 84.58538)
		(end 158.409282 84.468)
		(width 0.182)
		(layer "F.Cu")
		(net 332)
	)
	(arc
		(start 158.409282 83.804)
		(mid 158.457902 83.68662)
		(end 158.575282 83.638)
		(width 0.182)
		(layer "F.Cu")
		(net 332)
	)
	(arc
		(start 159 84.8)
		(mid 158.95138 84.68262)
		(end 158.834 84.634)
		(width 0.182)
		(layer "F.Cu")
		(net 332)
	)
	(arc
		(start 158.834 83.638)
		(mid 158.95138 83.58938)
		(end 159 83.472)
		(width 0.182)
		(layer "F.Cu")
		(net 332)
	)
	(segment
		(start 159.616 83.68)
		(end 159.751338 83.68)
		(width 0.182)
		(layer "F.Cu")
		(net 333)
	)
	(segment
		(start 159.751338 83.348)
		(end 159.616 83.348)
		(width 0.182)
		(layer "F.Cu")
		(net 333)
	)
	(segment
		(start 159.751338 84.012)
		(end 159.616 84.012)
		(width 0.182)
		(layer "F.Cu")
		(net 333)
	)
	(segment
		(start 159.616 84.344)
		(end 159.751338 84.344)
		(width 0.182)
		(layer "F.Cu")
		(net 333)
	)
	(segment
		(start 159.45 85.410829)
		(end 159.536328 85.497157)
		(width 0.182)
		(layer "F.Cu")
		(net 333)
	)
	(segment
		(start 159.45 80.636328)
		(end 159.45 82.85)
		(width 0.182)
		(layer "F.Cu")
		(net 333)
	)
	(segment
		(start 159.616 83.016)
		(end 159.751338 83.016)
		(width 0.182)
		(layer "F.Cu")
		(net 333)
	)
	(segment
		(start 159.45 84.892)
		(end 159.45 85.410829)
		(width 0.182)
		(layer "F.Cu")
		(net 333)
	)
	(segment
		(start 160.036328 80.05)
		(end 159.45 80.636328)
		(width 0.182)
		(layer "F.Cu")
		(net 333)
	)
	(segment
		(start 159.45 84.842)
		(end 159.45 84.892)
		(width 0.182)
		(layer "F.Cu")
		(net 333)
	)
	(segment
		(start 159.751338 84.676)
		(end 159.616 84.676)
		(width 0.182)
		(layer "F.Cu")
		(net 333)
	)
	(segment
		(start 160.036328 78.847157)
		(end 160.036328 80.05)
		(width 0.182)
		(layer "F.Cu")
		(net 333)
	)
	(arc
		(start 159.45 84.178)
		(mid 159.49862 84.29538)
		(end 159.616 84.344)
		(width 0.182)
		(layer "F.Cu")
		(net 333)
	)
	(arc
		(start 159.917338 84.51)
		(mid 159.868718 84.62738)
		(end 159.751338 84.676)
		(width 0.182)
		(layer "F.Cu")
		(net 333)
	)
	(arc
		(start 159.616 83.348)
		(mid 159.49862 83.39662)
		(end 159.45 83.514)
		(width 0.182)
		(layer "F.Cu")
		(net 333)
	)
	(arc
		(start 159.45 83.514)
		(mid 159.49862 83.63138)
		(end 159.616 83.68)
		(width 0.182)
		(layer "F.Cu")
		(net 333)
	)
	(arc
		(start 159.616 84.676)
		(mid 159.49862 84.72462)
		(end 159.45 84.842)
		(width 0.182)
		(layer "F.Cu")
		(net 333)
	)
	(arc
		(start 159.751338 83.68)
		(mid 159.868718 83.72862)
		(end 159.917338 83.846)
		(width 0.182)
		(layer "F.Cu")
		(net 333)
	)
	(arc
		(start 159.751338 84.344)
		(mid 159.868718 84.39262)
		(end 159.917338 84.51)
		(width 0.182)
		(layer "F.Cu")
		(net 333)
	)
	(arc
		(start 159.751338 83.016)
		(mid 159.868718 83.06462)
		(end 159.917338 83.182)
		(width 0.182)
		(layer "F.Cu")
		(net 333)
	)
	(arc
		(start 159.45 82.85)
		(mid 159.49862 82.96738)
		(end 159.616 83.016)
		(width 0.182)
		(layer "F.Cu")
		(net 333)
	)
	(arc
		(start 159.616 84.012)
		(mid 159.49862 84.06062)
		(end 159.45 84.178)
		(width 0.182)
		(layer "F.Cu")
		(net 333)
	)
	(arc
		(start 159.917338 83.846)
		(mid 159.868718 83.96338)
		(end 159.751338 84.012)
		(width 0.182)
		(layer "F.Cu")
		(net 333)
	)
	(arc
		(start 159.917338 83.182)
		(mid 159.868718 83.29938)
		(end 159.751338 83.348)
		(width 0.182)
		(layer "F.Cu")
		(net 333)
	)
	(segment
		(start 160.536328 80.35)
		(end 160.25 80.636328)
		(width 0.182)
		(layer "F.Cu")
		(net 334)
	)
	(segment
		(start 160.536328 78.847157)
		(end 160.536328 80.35)
		(width 0.182)
		(layer "F.Cu")
		(net 334)
	)
	(segment
		(start 159.945143 82.462328)
		(end 160.084 82.462328)
		(width 0.182)
		(layer "F.Cu")
		(net 334)
	)
	(segment
		(start 160.25 85.210829)
		(end 160.536328 85.497157)
		(width 0.182)
		(layer "F.Cu")
		(net 334)
	)
	(segment
		(start 160.084 80.802328)
		(end 159.945143 80.802328)
		(width 0.182)
		(layer "F.Cu")
		(net 334)
	)
	(segment
		(start 160.25 82.628328)
		(end 160.25 85.210829)
		(width 0.182)
		(layer "F.Cu")
		(net 334)
	)
	(segment
		(start 159.945143 81.798328)
		(end 160.084 81.798328)
		(width 0.182)
		(layer "F.Cu")
		(net 334)
	)
	(segment
		(start 160.084 82.130328)
		(end 159.945143 82.130328)
		(width 0.182)
		(layer "F.Cu")
		(net 334)
	)
	(segment
		(start 159.945143 81.134328)
		(end 160.084 81.134328)
		(width 0.182)
		(layer "F.Cu")
		(net 334)
	)
	(segment
		(start 160.084 81.466328)
		(end 159.945143 81.466328)
		(width 0.182)
		(layer "F.Cu")
		(net 334)
	)
	(arc
		(start 159.779143 81.632328)
		(mid 159.827763 81.749708)
		(end 159.945143 81.798328)
		(width 0.182)
		(layer "F.Cu")
		(net 334)
	)
	(arc
		(start 160.084 81.134328)
		(mid 160.20138 81.182948)
		(end 160.25 81.300328)
		(width 0.182)
		(layer "F.Cu")
		(net 334)
	)
	(arc
		(start 159.779143 82.296328)
		(mid 159.827763 82.413708)
		(end 159.945143 82.462328)
		(width 0.182)
		(layer "F.Cu")
		(net 334)
	)
	(arc
		(start 160.084 81.798328)
		(mid 160.20138 81.846948)
		(end 160.25 81.964328)
		(width 0.182)
		(layer "F.Cu")
		(net 334)
	)
	(arc
		(start 159.945143 80.802328)
		(mid 159.827763 80.850948)
		(end 159.779143 80.968328)
		(width 0.182)
		(layer "F.Cu")
		(net 334)
	)
	(arc
		(start 159.945143 82.130328)
		(mid 159.827763 82.178948)
		(end 159.779143 82.296328)
		(width 0.182)
		(layer "F.Cu")
		(net 334)
	)
	(arc
		(start 159.779143 80.968328)
		(mid 159.827763 81.085708)
		(end 159.945143 81.134328)
		(width 0.182)
		(layer "F.Cu")
		(net 334)
	)
	(arc
		(start 160.084 82.462328)
		(mid 160.20138 82.510948)
		(end 160.25 82.628328)
		(width 0.182)
		(layer "F.Cu")
		(net 334)
	)
	(arc
		(start 159.945143 81.466328)
		(mid 159.827763 81.514948)
		(end 159.779143 81.632328)
		(width 0.182)
		(layer "F.Cu")
		(net 334)
	)
	(arc
		(start 160.25 80.636328)
		(mid 160.20138 80.753708)
		(end 160.084 80.802328)
		(width 0.182)
		(layer "F.Cu")
		(net 334)
	)
	(arc
		(start 160.25 81.964328)
		(mid 160.20138 82.081708)
		(end 160.084 82.130328)
		(width 0.182)
		(layer "F.Cu")
		(net 334)
	)
	(arc
		(start 160.25 81.300328)
		(mid 160.20138 81.417708)
		(end 160.084 81.466328)
		(width 0.182)
		(layer "F.Cu")
		(net 334)
	)
	(segment
		(start 161.036328 78.847157)
		(end 161.036328 80.813672)
		(width 0.182)
		(layer "F.Cu")
		(net 335)
	)
	(segment
		(start 160.65 81.2)
		(end 160.65 83.1)
		(width 0.182)
		(layer "F.Cu")
		(net 335)
	)
	(segment
		(start 161.036328 85.997157)
		(end 161.536328 86.497157)
		(width 0.182)
		(layer "F.Cu")
		(net 335)
	)
	(segment
		(start 160.65 83.764)
		(end 160.65 84.727344)
		(width 0.182)
		(layer "F.Cu")
		(net 335)
	)
	(segment
		(start 161.036328 85.113672)
		(end 161.036328 85.997157)
		(width 0.182)
		(layer "F.Cu")
		(net 335)
	)
	(segment
		(start 160.65 84.727344)
		(end 161.036328 85.113672)
		(width 0.182)
		(layer "F.Cu")
		(net 335)
	)
	(segment
		(start 160.816 83.266)
		(end 160.966471 83.266)
		(width 0.182)
		(layer "F.Cu")
		(net 335)
	)
	(segment
		(start 160.966471 83.598)
		(end 160.816 83.598)
		(width 0.182)
		(layer "F.Cu")
		(net 335)
	)
	(segment
		(start 161.036328 80.813672)
		(end 160.65 81.2)
		(width 0.182)
		(layer "F.Cu")
		(net 335)
	)
	(arc
		(start 160.816 83.598)
		(mid 160.69862 83.64662)
		(end 160.65 83.764)
		(width 0.182)
		(layer "F.Cu")
		(net 335)
	)
	(arc
		(start 161.132471 83.432)
		(mid 161.083851 83.54938)
		(end 160.966471 83.598)
		(width 0.182)
		(layer "F.Cu")
		(net 335)
	)
	(arc
		(start 160.65 83.1)
		(mid 160.69862 83.21738)
		(end 160.816 83.266)
		(width 0.182)
		(layer "F.Cu")
		(net 335)
	)
	(arc
		(start 160.966471 83.266)
		(mid 161.083851 83.31462)
		(end 161.132471 83.432)
		(width 0.182)
		(layer "F.Cu")
		(net 335)
	)
	(segment
		(start 161.370328 82.770328)
		(end 161.142026 82.770328)
		(width 0.182)
		(layer "F.Cu")
		(net 336)
	)
	(segment
		(start 161.370328 81.442328)
		(end 161.292026 81.442328)
		(width 0.182)
		(layer "F.Cu")
		(net 336)
	)
	(segment
		(start 161.370328 82.106328)
		(end 161.142026 82.106328)
		(width 0.182)
		(layer "F.Cu")
		(net 336)
	)
	(segment
		(start 161.292026 81.110328)
		(end 161.370328 81.110328)
		(width 0.182)
		(layer "F.Cu")
		(net 336)
	)
	(segment
		(start 161.536328 85.497157)
		(end 161.536328 82.936328)
		(width 0.182)
		(layer "F.Cu")
		(net 336)
	)
	(segment
		(start 161.142026 82.438328)
		(end 161.370328 82.438328)
		(width 0.182)
		(layer "F.Cu")
		(net 336)
	)
	(segment
		(start 161.142026 81.774328)
		(end 161.370328 81.774328)
		(width 0.182)
		(layer "F.Cu")
		(net 336)
	)
	(segment
		(start 161.536328 80.894328)
		(end 161.536328 78.847157)
		(width 0.182)
		(layer "F.Cu")
		(net 336)
	)
	(segment
		(start 161.536328 80.944328)
		(end 161.536328 80.894328)
		(width 0.182)
		(layer "F.Cu")
		(net 336)
	)
	(arc
		(start 161.142026 82.106328)
		(mid 161.024646 82.057708)
		(end 160.976026 81.940328)
		(width 0.182)
		(layer "F.Cu")
		(net 336)
	)
	(arc
		(start 160.976026 82.604328)
		(mid 161.024646 82.486948)
		(end 161.142026 82.438328)
		(width 0.182)
		(layer "F.Cu")
		(net 336)
	)
	(arc
		(start 161.370328 81.110328)
		(mid 161.487708 81.061708)
		(end 161.536328 80.944328)
		(width 0.182)
		(layer "F.Cu")
		(net 336)
	)
	(arc
		(start 161.536328 82.272328)
		(mid 161.487708 82.154948)
		(end 161.370328 82.106328)
		(width 0.182)
		(layer "F.Cu")
		(net 336)
	)
	(arc
		(start 161.142026 82.770328)
		(mid 161.024646 82.721708)
		(end 160.976026 82.604328)
		(width 0.182)
		(layer "F.Cu")
		(net 336)
	)
	(arc
		(start 161.536328 81.608328)
		(mid 161.487708 81.490948)
		(end 161.370328 81.442328)
		(width 0.182)
		(layer "F.Cu")
		(net 336)
	)
	(arc
		(start 161.370328 82.438328)
		(mid 161.487708 82.389708)
		(end 161.536328 82.272328)
		(width 0.182)
		(layer "F.Cu")
		(net 336)
	)
	(arc
		(start 161.370328 81.774328)
		(mid 161.487708 81.725708)
		(end 161.536328 81.608328)
		(width 0.182)
		(layer "F.Cu")
		(net 336)
	)
	(arc
		(start 161.292026 81.442328)
		(mid 161.174646 81.393708)
		(end 161.126026 81.276328)
		(width 0.182)
		(layer "F.Cu")
		(net 336)
	)
	(arc
		(start 160.976026 81.940328)
		(mid 161.024646 81.822948)
		(end 161.142026 81.774328)
		(width 0.182)
		(layer "F.Cu")
		(net 336)
	)
	(arc
		(start 161.536328 82.936328)
		(mid 161.487708 82.818948)
		(end 161.370328 82.770328)
		(width 0.182)
		(layer "F.Cu")
		(net 336)
	)
	(arc
		(start 161.126026 81.276328)
		(mid 161.174646 81.158948)
		(end 161.292026 81.110328)
		(width 0.182)
		(layer "F.Cu")
		(net 336)
	)
	(segment
		(start 163.536328 84.913672)
		(end 163.536328 85.497157)
		(width 0.182)
		(layer "F.Cu")
		(net 338)
	)
	(segment
		(start 163.045271 80.748)
		(end 163.484 80.748)
		(width 0.182)
		(layer "F.Cu")
		(net 338)
	)
	(segment
		(start 163.65 81.578)
		(end 163.65 84.8)
		(width 0.182)
		(layer "F.Cu")
		(net 338)
	)
	(segment
		(start 163.65 84.8)
		(end 163.536328 84.913672)
		(width 0.182)
		(layer "F.Cu")
		(net 338)
	)
	(segment
		(start 163.536328 79.886328)
		(end 163.65 80)
		(width 0.182)
		(layer "F.Cu")
		(net 338)
	)
	(segment
		(start 163.484 81.08)
		(end 163.245271 81.08)
		(width 0.182)
		(layer "F.Cu")
		(net 338)
	)
	(segment
		(start 163.65 80)
		(end 163.65 80.25)
		(width 0.182)
		(layer "F.Cu")
		(net 338)
	)
	(segment
		(start 163.484 80.416)
		(end 163.045271 80.416)
		(width 0.182)
		(layer "F.Cu")
		(net 338)
	)
	(segment
		(start 163.245271 81.412)
		(end 163.484 81.412)
		(width 0.182)
		(layer "F.Cu")
		(net 338)
	)
	(segment
		(start 163.536328 78.847157)
		(end 163.536328 79.886328)
		(width 0.182)
		(layer "F.Cu")
		(net 338)
	)
	(arc
		(start 163.045271 80.416)
		(mid 162.927891 80.46462)
		(end 162.879271 80.582)
		(width 0.182)
		(layer "F.Cu")
		(net 338)
	)
	(arc
		(start 163.65 80.914)
		(mid 163.60138 81.03138)
		(end 163.484 81.08)
		(width 0.182)
		(layer "F.Cu")
		(net 338)
	)
	(arc
		(start 163.245271 81.08)
		(mid 163.127891 81.12862)
		(end 163.079271 81.246)
		(width 0.182)
		(layer "F.Cu")
		(net 338)
	)
	(arc
		(start 163.079271 81.246)
		(mid 163.127891 81.36338)
		(end 163.245271 81.412)
		(width 0.182)
		(layer "F.Cu")
		(net 338)
	)
	(arc
		(start 163.484 81.412)
		(mid 163.60138 81.46062)
		(end 163.65 81.578)
		(width 0.182)
		(layer "F.Cu")
		(net 338)
	)
	(arc
		(start 163.484 80.748)
		(mid 163.60138 80.79662)
		(end 163.65 80.914)
		(width 0.182)
		(layer "F.Cu")
		(net 338)
	)
	(arc
		(start 163.65 80.25)
		(mid 163.60138 80.36738)
		(end 163.484 80.416)
		(width 0.182)
		(layer "F.Cu")
		(net 338)
	)
	(arc
		(start 162.879271 80.582)
		(mid 162.927891 80.69938)
		(end 163.045271 80.748)
		(width 0.182)
		(layer "F.Cu")
		(net 338)
	)
	(segment
		(start 164.036328 86.997157)
		(end 164.536328 87.497157)
		(width 0.182)
		(layer "F.Cu")
		(net 339)
	)
	(segment
		(start 164.036328 78.847157)
		(end 164.036328 86.997157)
		(width 0.182)
		(layer "F.Cu")
		(net 339)
	)
	(segment
		(start 164.725524 82.226)
		(end 164.566 82.226)
		(width 0.182)
		(layer "F.Cu")
		(net 340)
	)
	(segment
		(start 164.536328 84.836328)
		(end 164.536328 85.497157)
		(width 0.182)
		(layer "F.Cu")
		(net 340)
	)
	(segment
		(start 164.566 81.894)
		(end 164.725524 81.894)
		(width 0.182)
		(layer "F.Cu")
		(net 340)
	)
	(segment
		(start 164.4 84.7)
		(end 164.536328 84.836328)
		(width 0.182)
		(layer "F.Cu")
		(net 340)
	)
	(segment
		(start 164.725524 81.562)
		(end 164.566 81.562)
		(width 0.182)
		(layer "F.Cu")
		(net 340)
	)
	(segment
		(start 164.566 81.23)
		(end 164.725524 81.23)
		(width 0.182)
		(layer "F.Cu")
		(net 340)
	)
	(segment
		(start 164.4 82.392)
		(end 164.4 84.7)
		(width 0.182)
		(layer "F.Cu")
		(net 340)
	)
	(segment
		(start 164.536328 78.847157)
		(end 164.536328 79.913672)
		(width 0.182)
		(layer "F.Cu")
		(net 340)
	)
	(segment
		(start 164.4 80.05)
		(end 164.4 80.4)
		(width 0.182)
		(layer "F.Cu")
		(net 340)
	)
	(segment
		(start 164.566 80.566)
		(end 164.725524 80.566)
		(width 0.182)
		(layer "F.Cu")
		(net 340)
	)
	(segment
		(start 164.536328 79.913672)
		(end 164.4 80.05)
		(width 0.182)
		(layer "F.Cu")
		(net 340)
	)
	(segment
		(start 164.725524 80.898)
		(end 164.566 80.898)
		(width 0.182)
		(layer "F.Cu")
		(net 340)
	)
	(arc
		(start 164.4 81.728)
		(mid 164.44862 81.84538)
		(end 164.566 81.894)
		(width 0.182)
		(layer "F.Cu")
		(net 340)
	)
	(arc
		(start 164.4 80.4)
		(mid 164.44862 80.51738)
		(end 164.566 80.566)
		(width 0.182)
		(layer "F.Cu")
		(net 340)
	)
	(arc
		(start 164.4 81.064)
		(mid 164.44862 81.18138)
		(end 164.566 81.23)
		(width 0.182)
		(layer "F.Cu")
		(net 340)
	)
	(arc
		(start 164.725524 81.894)
		(mid 164.842904 81.94262)
		(end 164.891524 82.06)
		(width 0.182)
		(layer "F.Cu")
		(net 340)
	)
	(arc
		(start 164.566 80.898)
		(mid 164.44862 80.94662)
		(end 164.4 81.064)
		(width 0.182)
		(layer "F.Cu")
		(net 340)
	)
	(arc
		(start 164.891524 80.732)
		(mid 164.842904 80.84938)
		(end 164.725524 80.898)
		(width 0.182)
		(layer "F.Cu")
		(net 340)
	)
	(arc
		(start 164.566 81.562)
		(mid 164.44862 81.61062)
		(end 164.4 81.728)
		(width 0.182)
		(layer "F.Cu")
		(net 340)
	)
	(arc
		(start 164.891524 82.06)
		(mid 164.842904 82.17738)
		(end 164.725524 82.226)
		(width 0.182)
		(layer "F.Cu")
		(net 340)
	)
	(arc
		(start 164.891524 81.396)
		(mid 164.842904 81.51338)
		(end 164.725524 81.562)
		(width 0.182)
		(layer "F.Cu")
		(net 340)
	)
	(arc
		(start 164.566 82.226)
		(mid 164.44862 82.27462)
		(end 164.4 82.392)
		(width 0.182)
		(layer "F.Cu")
		(net 340)
	)
	(arc
		(start 164.725524 80.566)
		(mid 164.842904 80.61462)
		(end 164.891524 80.732)
		(width 0.182)
		(layer "F.Cu")
		(net 340)
	)
	(arc
		(start 164.725524 81.23)
		(mid 164.842904 81.27862)
		(end 164.891524 81.396)
		(width 0.182)
		(layer "F.Cu")
		(net 340)
	)
	(segment
		(start 165.036328 78.847157)
		(end 165.036328 79.936328)
		(width 0.182)
		(layer "F.Cu")
		(net 341)
	)
	(segment
		(start 165.536328 86.493328)
		(end 165.536328 86.497157)
		(width 0.182)
		(layer "F.Cu")
		(net 341)
	)
	(segment
		(start 165.609252 82.4)
		(end 165.366 82.4)
		(width 0.182)
		(layer "F.Cu")
		(net 341)
	)
	(segment
		(start 165.036328 85.213672)
		(end 165.036328 85.993328)
		(width 0.182)
		(layer "F.Cu")
		(net 341)
	)
	(segment
		(start 165.2 80.1)
		(end 165.2 81.902)
		(width 0.182)
		(layer "F.Cu")
		(net 341)
	)
	(segment
		(start 165.366 82.068)
		(end 165.609252 82.068)
		(width 0.182)
		(layer "F.Cu")
		(net 341)
	)
	(segment
		(start 165.036328 85.993328)
		(end 165.536328 86.493328)
		(width 0.182)
		(layer "F.Cu")
		(net 341)
	)
	(segment
		(start 165.036328 79.936328)
		(end 165.2 80.1)
		(width 0.182)
		(layer "F.Cu")
		(net 341)
	)
	(segment
		(start 165.2 82.566)
		(end 165.2 85.05)
		(width 0.182)
		(layer "F.Cu")
		(net 341)
	)
	(segment
		(start 165.2 85.05)
		(end 165.036328 85.213672)
		(width 0.182)
		(layer "F.Cu")
		(net 341)
	)
	(arc
		(start 165.366 82.4)
		(mid 165.24862 82.44862)
		(end 165.2 82.566)
		(width 0.182)
		(layer "F.Cu")
		(net 341)
	)
	(arc
		(start 165.775252 82.234)
		(mid 165.726632 82.35138)
		(end 165.609252 82.4)
		(width 0.182)
		(layer "F.Cu")
		(net 341)
	)
	(arc
		(start 165.2 81.902)
		(mid 165.24862 82.01938)
		(end 165.366 82.068)
		(width 0.182)
		(layer "F.Cu")
		(net 341)
	)
	(arc
		(start 165.609252 82.068)
		(mid 165.726632 82.11662)
		(end 165.775252 82.234)
		(width 0.182)
		(layer "F.Cu")
		(net 341)
	)
	(segment
		(start 166.35 82.486)
		(end 166.35 81.95)
		(width 0.182)
		(layer "F.Cu")
		(net 343)
	)
	(segment
		(start 165.736328 83.4)
		(end 166.15 83.4)
		(width 0.182)
		(layer "F.Cu")
		(net 343)
	)
	(segment
		(start 165.536328 85.497157)
		(end 165.536328 83.6)
		(width 0.182)
		(layer "F.Cu")
		(net 343)
	)
	(segment
		(start 165.536328 81.55)
		(end 165.536328 78.847157)
		(width 0.182)
		(layer "F.Cu")
		(net 343)
	)
	(segment
		(start 165.91195 82.702)
		(end 166.184 82.702)
		(width 0.182)
		(layer "F.Cu")
		(net 343)
	)
	(segment
		(start 166.15 81.75)
		(end 165.736328 81.75)
		(width 0.182)
		(layer "F.Cu")
		(net 343)
	)
	(segment
		(start 166.184 83.034)
		(end 165.91195 83.034)
		(width 0.182)
		(layer "F.Cu")
		(net 343)
	)
	(segment
		(start 166.35 82.536)
		(end 166.35 82.486)
		(width 0.182)
		(layer "F.Cu")
		(net 343)
	)
	(arc
		(start 165.91195 83.034)
		(mid 165.79457 82.98538)
		(end 165.74595 82.868)
		(width 0.182)
		(layer "F.Cu")
		(net 343)
	)
	(arc
		(start 165.536328 83.6)
		(mid 165.594907 83.458579)
		(end 165.736328 83.4)
		(width 0.182)
		(layer "F.Cu")
		(net 343)
	)
	(arc
		(start 166.15 83.4)
		(mid 166.291421 83.341421)
		(end 166.35 83.2)
		(width 0.182)
		(layer "F.Cu")
		(net 343)
	)
	(arc
		(start 166.35 81.95)
		(mid 166.291421 81.808579)
		(end 166.15 81.75)
		(width 0.182)
		(layer "F.Cu")
		(net 343)
	)
	(arc
		(start 165.736328 81.75)
		(mid 165.594907 81.691421)
		(end 165.536328 81.55)
		(width 0.182)
		(layer "F.Cu")
		(net 343)
	)
	(arc
		(start 166.184 82.702)
		(mid 166.30138 82.65338)
		(end 166.35 82.536)
		(width 0.182)
		(layer "F.Cu")
		(net 343)
	)
	(arc
		(start 165.74595 82.868)
		(mid 165.79457 82.75062)
		(end 165.91195 82.702)
		(width 0.182)
		(layer "F.Cu")
		(net 343)
	)
	(arc
		(start 166.35 83.2)
		(mid 166.30138 83.08262)
		(end 166.184 83.034)
		(width 0.182)
		(layer "F.Cu")
		(net 343)
	)
	(segment
		(start 166.236328 81.4)
		(end 166.52 81.4)
		(width 0.182)
		(layer "F.Cu")
		(net 344)
	)
	(segment
		(start 166.52 83.75)
		(end 166.25 83.75)
		(width 0.182)
		(layer "F.Cu")
		(net 344)
	)
	(segment
		(start 166.536328 86.497157)
		(end 166.05 86.010829)
		(width 0.182)
		(layer "F.Cu")
		(net 344)
	)
	(segment
		(start 166.72 81.6)
		(end 166.72 83.55)
		(width 0.182)
		(layer "F.Cu")
		(net 344)
	)
	(segment
		(start 166.036328 78.847157)
		(end 166.036328 81.2)
		(width 0.182)
		(layer "F.Cu")
		(net 344)
	)
	(segment
		(start 166.05 86.010829)
		(end 166.05 83.95)
		(width 0.182)
		(layer "F.Cu")
		(net 344)
	)
	(arc
		(start 166.72 83.55)
		(mid 166.661421 83.691421)
		(end 166.52 83.75)
		(width 0.182)
		(layer "F.Cu")
		(net 344)
	)
	(arc
		(start 166.036328 81.2)
		(mid 166.094907 81.341421)
		(end 166.236328 81.4)
		(width 0.182)
		(layer "F.Cu")
		(net 344)
	)
	(arc
		(start 166.52 81.4)
		(mid 166.661421 81.458579)
		(end 166.72 81.6)
		(width 0.182)
		(layer "F.Cu")
		(net 344)
	)
	(arc
		(start 166.05 83.95)
		(mid 166.108579 83.808579)
		(end 166.25 83.75)
		(width 0.182)
		(layer "F.Cu")
		(net 344)
	)
	(segment
		(start 167.35 81.214)
		(end 167.35 81.264)
		(width 0.182)
		(layer "F.Cu")
		(net 345)
	)
	(segment
		(start 167.184 80.716)
		(end 166.91195 80.716)
		(width 0.182)
		(layer "F.Cu")
		(net 345)
	)
	(segment
		(start 166.91195 81.048)
		(end 167.184 81.048)
		(width 0.182)
		(layer "F.Cu")
		(net 345)
	)
	(segment
		(start 166.536328 84.3)
		(end 166.536328 85.497157)
		(width 0.182)
		(layer "F.Cu")
		(net 345)
	)
	(segment
		(start 166.536328 78.847157)
		(end 166.536328 80.15)
		(width 0.182)
		(layer "F.Cu")
		(net 345)
	)
	(segment
		(start 167.35 81.264)
		(end 167.35 83.9)
		(width 0.182)
		(layer "F.Cu")
		(net 345)
	)
	(segment
		(start 166.736328 80.35)
		(end 167.15 80.35)
		(width 0.182)
		(layer "F.Cu")
		(net 345)
	)
	(segment
		(start 167.15 84.1)
		(end 166.736328 84.1)
		(width 0.182)
		(layer "F.Cu")
		(net 345)
	)
	(arc
		(start 166.74595 80.882)
		(mid 166.79457 80.99938)
		(end 166.91195 81.048)
		(width 0.182)
		(layer "F.Cu")
		(net 345)
	)
	(arc
		(start 166.536328 80.15)
		(mid 166.594907 80.291421)
		(end 166.736328 80.35)
		(width 0.182)
		(layer "F.Cu")
		(net 345)
	)
	(arc
		(start 167.15 80.35)
		(mid 167.291421 80.408579)
		(end 167.35 80.55)
		(width 0.182)
		(layer "F.Cu")
		(net 345)
	)
	(arc
		(start 166.91195 80.716)
		(mid 166.79457 80.76462)
		(end 166.74595 80.882)
		(width 0.182)
		(layer "F.Cu")
		(net 345)
	)
	(arc
		(start 167.35 80.55)
		(mid 167.30138 80.66738)
		(end 167.184 80.716)
		(width 0.182)
		(layer "F.Cu")
		(net 345)
	)
	(arc
		(start 167.35 83.9)
		(mid 167.291421 84.041421)
		(end 167.15 84.1)
		(width 0.182)
		(layer "F.Cu")
		(net 345)
	)
	(arc
		(start 167.184 81.048)
		(mid 167.30138 81.09662)
		(end 167.35 81.214)
		(width 0.182)
		(layer "F.Cu")
		(net 345)
	)
	(arc
		(start 166.736328 84.1)
		(mid 166.594907 84.158579)
		(end 166.536328 84.3)
		(width 0.182)
		(layer "F.Cu")
		(net 345)
	)
	(segment
		(start 167.5 84.425)
		(end 167.225 84.425)
		(width 0.182)
		(layer "F.Cu")
		(net 346)
	)
	(segment
		(start 167.036328 78.847157)
		(end 167.036328 79.8)
		(width 0.182)
		(layer "F.Cu")
		(net 346)
	)
	(segment
		(start 167.7 80.2)
		(end 167.7 84.225)
		(width 0.182)
		(layer "F.Cu")
		(net 346)
	)
	(segment
		(start 167.025 85.985829)
		(end 167.536328 86.497157)
		(width 0.182)
		(layer "F.Cu")
		(net 346)
	)
	(segment
		(start 167.236328 80)
		(end 167.5 80)
		(width 0.182)
		(layer "F.Cu")
		(net 346)
	)
	(segment
		(start 167.025 84.625)
		(end 167.025 85.985829)
		(width 0.182)
		(layer "F.Cu")
		(net 346)
	)
	(arc
		(start 167.036328 79.8)
		(mid 167.094907 79.941421)
		(end 167.236328 80)
		(width 0.182)
		(layer "F.Cu")
		(net 346)
	)
	(arc
		(start 167.5 80)
		(mid 167.641421 80.058579)
		(end 167.7 80.2)
		(width 0.182)
		(layer "F.Cu")
		(net 346)
	)
	(arc
		(start 167.7 84.225)
		(mid 167.641421 84.366421)
		(end 167.5 84.425)
		(width 0.182)
		(layer "F.Cu")
		(net 346)
	)
	(arc
		(start 167.025 84.625)
		(mid 167.083579 84.483579)
		(end 167.225 84.425)
		(width 0.182)
		(layer "F.Cu")
		(net 346)
	)
	(segment
		(start 168.036328 86.997157)
		(end 168.536328 87.497157)
		(width 0.15)
		(layer "F.Cu")
		(net 347)
	)
	(segment
		(start 168.036328 78.847157)
		(end 168.036328 86.997157)
		(width 0.15)
		(layer "F.Cu")
		(net 347)
	)
	(segment
		(start 170.536328 87.497157)
		(end 171.036328 86.997157)
		(width 0.182)
		(layer "F.Cu")
		(net 348)
	)
	(segment
		(start 171.036328 86.997157)
		(end 171.036328 78.847157)
		(width 0.182)
		(layer "F.Cu")
		(net 348)
	)
	(segment
		(start 170.543236 83.481172)
		(end 170.575828 83.481172)
		(width 0.182)
		(layer "F.Cu")
		(net 349)
	)
	(segment
		(start 170.536328 79.884164)
		(end 170.729328 80.077164)
		(width 0.182)
		(layer "F.Cu")
		(net 349)
	)
	(segment
		(start 170.729328 84.912672)
		(end 170.729328 85.304157)
		(width 0.182)
		(layer "F.Cu")
		(net 349)
	)
	(segment
		(start 170.343236 84.709172)
		(end 170.575828 84.709172)
		(width 0.182)
		(layer "F.Cu")
		(net 349)
	)
	(segment
		(start 170.729328 84.862672)
		(end 170.729328 84.912672)
		(width 0.182)
		(layer "F.Cu")
		(net 349)
	)
	(segment
		(start 170.729328 80.077164)
		(end 170.729328 83.020672)
		(width 0.182)
		(layer "F.Cu")
		(net 349)
	)
	(segment
		(start 170.575828 83.788172)
		(end 170.343236 83.788172)
		(width 0.182)
		(layer "F.Cu")
		(net 349)
	)
	(segment
		(start 170.575828 83.174172)
		(end 170.543236 83.174172)
		(width 0.182)
		(layer "F.Cu")
		(net 349)
	)
	(segment
		(start 170.575828 84.402172)
		(end 170.343236 84.402172)
		(width 0.182)
		(layer "F.Cu")
		(net 349)
	)
	(segment
		(start 170.536328 78.847157)
		(end 170.536328 79.884164)
		(width 0.182)
		(layer "F.Cu")
		(net 349)
	)
	(segment
		(start 170.729328 85.304157)
		(end 170.536328 85.497157)
		(width 0.182)
		(layer "F.Cu")
		(net 349)
	)
	(segment
		(start 170.343236 84.095172)
		(end 170.575828 84.095172)
		(width 0.182)
		(layer "F.Cu")
		(net 349)
	)
	(arc
		(start 170.343236 84.402172)
		(mid 170.234695 84.447131)
		(end 170.189736 84.555672)
		(width 0.182)
		(layer "F.Cu")
		(net 349)
	)
	(arc
		(start 170.729328 83.020672)
		(mid 170.684369 83.129213)
		(end 170.575828 83.174172)
		(width 0.182)
		(layer "F.Cu")
		(net 349)
	)
	(arc
		(start 170.543236 83.174172)
		(mid 170.434695 83.219131)
		(end 170.389736 83.327672)
		(width 0.182)
		(layer "F.Cu")
		(net 349)
	)
	(arc
		(start 170.189736 84.555672)
		(mid 170.234695 84.664213)
		(end 170.343236 84.709172)
		(width 0.182)
		(layer "F.Cu")
		(net 349)
	)
	(arc
		(start 170.343236 83.788172)
		(mid 170.234695 83.833131)
		(end 170.189736 83.941672)
		(width 0.182)
		(layer "F.Cu")
		(net 349)
	)
	(arc
		(start 170.389736 83.327672)
		(mid 170.434695 83.436213)
		(end 170.543236 83.481172)
		(width 0.182)
		(layer "F.Cu")
		(net 349)
	)
	(arc
		(start 170.575828 84.095172)
		(mid 170.684369 84.140131)
		(end 170.729328 84.248672)
		(width 0.182)
		(layer "F.Cu")
		(net 349)
	)
	(arc
		(start 170.575828 84.709172)
		(mid 170.684369 84.754131)
		(end 170.729328 84.862672)
		(width 0.182)
		(layer "F.Cu")
		(net 349)
	)
	(arc
		(start 170.729328 83.634672)
		(mid 170.684369 83.743213)
		(end 170.575828 83.788172)
		(width 0.182)
		(layer "F.Cu")
		(net 349)
	)
	(arc
		(start 170.189736 83.941672)
		(mid 170.234695 84.050213)
		(end 170.343236 84.095172)
		(width 0.182)
		(layer "F.Cu")
		(net 349)
	)
	(arc
		(start 170.575828 83.481172)
		(mid 170.684369 83.526131)
		(end 170.729328 83.634672)
		(width 0.182)
		(layer "F.Cu")
		(net 349)
	)
	(arc
		(start 170.729328 84.248672)
		(mid 170.684369 84.357213)
		(end 170.575828 84.402172)
		(width 0.182)
		(layer "F.Cu")
		(net 349)
	)
	(segment
		(start 170.41 81.054)
		(end 170.41 81.104)
		(width 0.182)
		(layer "F.Cu")
		(net 350)
	)
	(segment
		(start 170.036328 85.997157)
		(end 170.536328 86.497157)
		(width 0.182)
		(layer "F.Cu")
		(net 350)
	)
	(segment
		(start 169.85 84.95)
		(end 170.036328 85.136328)
		(width 0.182)
		(layer "F.Cu")
		(net 350)
	)
	(segment
		(start 170.41 82.776)
		(end 169.85 83.336)
		(width 0.182)
		(layer "F.Cu")
		(net 350)
	)
	(segment
		(start 170.036328 78.847157)
		(end 170.036328 79.818328)
		(width 0.182)
		(layer "F.Cu")
		(net 350)
	)
	(segment
		(start 170.165466 80.888)
		(end 170.244 80.888)
		(width 0.182)
		(layer "F.Cu")
		(net 350)
	)
	(segment
		(start 170.036328 79.818328)
		(end 170.41 80.192)
		(width 0.182)
		(layer "F.Cu")
		(net 350)
	)
	(segment
		(start 170.036328 85.136328)
		(end 170.036328 85.997157)
		(width 0.182)
		(layer "F.Cu")
		(net 350)
	)
	(segment
		(start 170.41 81.104)
		(end 170.41 82.776)
		(width 0.182)
		(layer "F.Cu")
		(net 350)
	)
	(segment
		(start 169.85 83.336)
		(end 169.85 84.95)
		(width 0.182)
		(layer "F.Cu")
		(net 350)
	)
	(segment
		(start 170.244 80.556)
		(end 170.165466 80.556)
		(width 0.182)
		(layer "F.Cu")
		(net 350)
	)
	(segment
		(start 170.41 80.192)
		(end 170.41 80.39)
		(width 0.182)
		(layer "F.Cu")
		(net 350)
	)
	(arc
		(start 170.41 80.39)
		(mid 170.36138 80.50738)
		(end 170.244 80.556)
		(width 0.182)
		(layer "F.Cu")
		(net 350)
	)
	(arc
		(start 170.244 80.888)
		(mid 170.36138 80.93662)
		(end 170.41 81.054)
		(width 0.182)
		(layer "F.Cu")
		(net 350)
	)
	(arc
		(start 169.999466 80.722)
		(mid 170.048086 80.83938)
		(end 170.165466 80.888)
		(width 0.182)
		(layer "F.Cu")
		(net 350)
	)
	(arc
		(start 170.165466 80.556)
		(mid 170.048086 80.60462)
		(end 169.999466 80.722)
		(width 0.182)
		(layer "F.Cu")
		(net 350)
	)
	(segment
		(start 169.1 83.55)
		(end 170.05 82.6)
		(width 0.182)
		(layer "F.Cu")
		(net 351)
	)
	(segment
		(start 169.1 83.572)
		(end 169.1 83.55)
		(width 0.182)
		(layer "F.Cu")
		(net 351)
	)
	(segment
		(start 169.332741 84.402)
		(end 169.266 84.402)
		(width 0.182)
		(layer "F.Cu")
		(net 351)
	)
	(segment
		(start 169.536328 80.122328)
		(end 169.536328 80.072328)
		(width 0.182)
		(layer "F.Cu")
		(net 351)
	)
	(segment
		(start 169.266 84.734)
		(end 169.332741 84.734)
		(width 0.182)
		(layer "F.Cu")
		(net 351)
	)
	(segment
		(start 169.352328 80.288328)
		(end 169.370328 80.288328)
		(width 0.182)
		(layer "F.Cu")
		(net 351)
	)
	(segment
		(start 170.05 81.3)
		(end 169.536328 80.786328)
		(width 0.182)
		(layer "F.Cu")
		(net 351)
	)
	(segment
		(start 170.05 82.6)
		(end 170.05 81.3)
		(width 0.182)
		(layer "F.Cu")
		(net 351)
	)
	(segment
		(start 169.536328 80.072328)
		(end 169.536328 78.847157)
		(width 0.182)
		(layer "F.Cu")
		(net 351)
	)
	(segment
		(start 169.332741 83.738)
		(end 169.266 83.738)
		(width 0.182)
		(layer "F.Cu")
		(net 351)
	)
	(segment
		(start 169.266 84.07)
		(end 169.332741 84.07)
		(width 0.182)
		(layer "F.Cu")
		(net 351)
	)
	(segment
		(start 169.370328 80.620328)
		(end 169.352328 80.620328)
		(width 0.182)
		(layer "F.Cu")
		(net 351)
	)
	(segment
		(start 169.536328 85.497157)
		(end 169.536328 85.336328)
		(width 0.182)
		(layer "F.Cu")
		(net 351)
	)
	(segment
		(start 169.536328 85.336328)
		(end 169.1 84.9)
		(width 0.182)
		(layer "F.Cu")
		(net 351)
	)
	(arc
		(start 169.498741 84.568)
		(mid 169.450121 84.45062)
		(end 169.332741 84.402)
		(width 0.182)
		(layer "F.Cu")
		(net 351)
	)
	(arc
		(start 169.186328 80.454328)
		(mid 169.234948 80.336948)
		(end 169.352328 80.288328)
		(width 0.182)
		(layer "F.Cu")
		(net 351)
	)
	(arc
		(start 169.370328 80.288328)
		(mid 169.487708 80.239708)
		(end 169.536328 80.122328)
		(width 0.182)
		(layer "F.Cu")
		(net 351)
	)
	(arc
		(start 169.332741 84.734)
		(mid 169.450121 84.68538)
		(end 169.498741 84.568)
		(width 0.182)
		(layer "F.Cu")
		(net 351)
	)
	(arc
		(start 169.332741 84.07)
		(mid 169.450121 84.02138)
		(end 169.498741 83.904)
		(width 0.182)
		(layer "F.Cu")
		(net 351)
	)
	(arc
		(start 169.352328 80.620328)
		(mid 169.234948 80.571708)
		(end 169.186328 80.454328)
		(width 0.182)
		(layer "F.Cu")
		(net 351)
	)
	(arc
		(start 169.266 84.402)
		(mid 169.14862 84.35338)
		(end 169.1 84.236)
		(width 0.182)
		(layer "F.Cu")
		(net 351)
	)
	(arc
		(start 169.1 84.9)
		(mid 169.14862 84.78262)
		(end 169.266 84.734)
		(width 0.182)
		(layer "F.Cu")
		(net 351)
	)
	(arc
		(start 169.266 83.738)
		(mid 169.14862 83.68938)
		(end 169.1 83.572)
		(width 0.182)
		(layer "F.Cu")
		(net 351)
	)
	(arc
		(start 169.536328 80.786328)
		(mid 169.487708 80.668948)
		(end 169.370328 80.620328)
		(width 0.182)
		(layer "F.Cu")
		(net 351)
	)
	(arc
		(start 169.498741 83.904)
		(mid 169.450121 83.78662)
		(end 169.332741 83.738)
		(width 0.182)
		(layer "F.Cu")
		(net 351)
	)
	(arc
		(start 169.1 84.236)
		(mid 169.14862 84.11862)
		(end 169.266 84.07)
		(width 0.182)
		(layer "F.Cu")
		(net 351)
	)
	(segment
		(start 160.536328 86.497156)
		(end 160.036328 85.997156)
		(width 0.15)
		(layer "F.Cu")
		(net 352)
	)
	(segment
		(start 159.786328 70.647157)
		(end 159.786328 71.997157)
		(width 0.1)
		(layer "F.Cu")
		(net 352)
	)
	(via blind
		(at 159.786328 71.997157)
		(size 0.5)
		(drill 0.2)
		(layers "F.Cu" "In2.Cu")
		(net 352)
	)
	(via blind
		(at 160.036328 85.997156)
		(size 0.5)
		(drill 0.2)
		(layers "F.Cu" "In2.Cu")
		(net 352)
	)
	(segment
		(start 160.036328 85.196384)
		(end 160.036328 85.997156)
		(width 0.182)
		(layer "In2.Cu")
		(net 352)
	)
	(segment
		(start 160.461 84.617)
		(end 160.461 84.667)
		(width 0.182)
		(layer "In2.Cu")
		(net 352)
	)
	(segment
		(start 160.461 84.771712)
		(end 160.036328 85.196384)
		(width 0.182)
		(layer "In2.Cu")
		(net 352)
	)
	(segment
		(start 159.811 79.871712)
		(end 159.811 80.678288)
		(width 0.182)
		(layer "In2.Cu")
		(net 352)
	)
	(segment
		(start 160.244045 79.438667)
		(end 159.811 79.871712)
		(width 0.182)
		(layer "In2.Cu")
		(net 352)
	)
	(segment
		(start 159.786328 71.997157)
		(end 159.786328 78.353616)
		(width 0.182)
		(layer "In2.Cu")
		(net 352)
	)
	(segment
		(start 160.461 82.893946)
		(end 160.461 82.953)
		(width 0.182)
		(layer "In2.Cu")
		(net 352)
	)
	(segment
		(start 160.166272 83.7245)
		(end 160.2825 83.7245)
		(width 0.182)
		(layer "In2.Cu")
		(net 352)
	)
	(segment
		(start 160.2825 84.0815)
		(end 160.166272 84.0815)
		(width 0.182)
		(layer "In2.Cu")
		(net 352)
	)
	(segment
		(start 159.624054 82.186946)
		(end 159.624054 82.246)
		(width 0.182)
		(layer "In2.Cu")
		(net 352)
	)
	(segment
		(start 160.166272 84.4385)
		(end 160.2825 84.4385)
		(width 0.182)
		(layer "In2.Cu")
		(net 352)
	)
	(segment
		(start 160.461 84.667)
		(end 160.461 84.771712)
		(width 0.182)
		(layer "In2.Cu")
		(net 352)
	)
	(segment
		(start 160.244045 78.811333)
		(end 160.244045 79.438667)
		(width 0.182)
		(layer "In2.Cu")
		(net 352)
	)
	(segment
		(start 160.461 81.328288)
		(end 160.461 81.539)
		(width 0.182)
		(layer "In2.Cu")
		(net 352)
	)
	(segment
		(start 159.811 80.678288)
		(end 160.461 81.328288)
		(width 0.182)
		(layer "In2.Cu")
		(net 352)
	)
	(segment
		(start 160.326027 81.673973)
		(end 160.137027 81.673973)
		(width 0.182)
		(layer "In2.Cu")
		(net 352)
	)
	(segment
		(start 159.786328 78.353616)
		(end 160.244045 78.811333)
		(width 0.182)
		(layer "In2.Cu")
		(net 352)
	)
	(segment
		(start 160.461 82.953)
		(end 160.461 83.189)
		(width 0.182)
		(layer "In2.Cu")
		(net 352)
	)
	(segment
		(start 160.2825 83.3675)
		(end 160.166272 83.3675)
		(width 0.182)
		(layer "In2.Cu")
		(net 352)
	)
	(segment
		(start 160.137027 82.758973)
		(end 160.326027 82.758973)
		(width 0.182)
		(layer "In2.Cu")
		(net 352)
	)
	(arc
		(start 160.2825 83.7245)
		(mid 160.408719 83.776781)
		(end 160.461 83.903)
		(width 0.182)
		(layer "In2.Cu")
		(net 352)
	)
	(arc
		(start 159.987772 83.546)
		(mid 160.040053 83.672219)
		(end 160.166272 83.7245)
		(width 0.182)
		(layer "In2.Cu")
		(net 352)
	)
	(arc
		(start 160.461 83.903)
		(mid 160.408719 84.029219)
		(end 160.2825 84.0815)
		(width 0.182)
		(layer "In2.Cu")
		(net 352)
	)
	(arc
		(start 160.461 81.539)
		(mid 160.421467 81.63444)
		(end 160.326027 81.673973)
		(width 0.182)
		(layer "In2.Cu")
		(net 352)
	)
	(arc
		(start 160.2825 84.4385)
		(mid 160.408719 84.490781)
		(end 160.461 84.617)
		(width 0.182)
		(layer "In2.Cu")
		(net 352)
	)
	(arc
		(start 160.166272 83.3675)
		(mid 160.040053 83.419781)
		(end 159.987772 83.546)
		(width 0.182)
		(layer "In2.Cu")
		(net 352)
	)
	(arc
		(start 159.987772 84.26)
		(mid 160.040053 84.386219)
		(end 160.166272 84.4385)
		(width 0.182)
		(layer "In2.Cu")
		(net 352)
	)
	(arc
		(start 160.166272 84.0815)
		(mid 160.040053 84.133781)
		(end 159.987772 84.26)
		(width 0.182)
		(layer "In2.Cu")
		(net 352)
	)
	(arc
		(start 160.461 83.189)
		(mid 160.408719 83.315219)
		(end 160.2825 83.3675)
		(width 0.182)
		(layer "In2.Cu")
		(net 352)
	)
	(arc
		(start 159.624054 82.246)
		(mid 159.7743 82.608727)
		(end 160.137027 82.758973)
		(width 0.182)
		(layer "In2.Cu")
		(net 352)
	)
	(arc
		(start 160.326027 82.758973)
		(mid 160.421467 82.798506)
		(end 160.461 82.893946)
		(width 0.182)
		(layer "In2.Cu")
		(net 352)
	)
	(arc
		(start 160.137027 81.673973)
		(mid 159.7743 81.824219)
		(end 159.624054 82.186946)
		(width 0.182)
		(layer "In2.Cu")
		(net 352)
	)
	(segment
		(start 160.286328 70.647157)
		(end 160.286328 72.5)
		(width 0.1)
		(layer "F.Cu")
		(net 353)
	)
	(segment
		(start 160.536328 87.497156)
		(end 160.036328 86.997156)
		(width 0.15)
		(layer "F.Cu")
		(net 353)
	)
	(via blind
		(at 160.036328 86.997156)
		(size 0.5)
		(drill 0.2)
		(layers "F.Cu" "In2.Cu")
		(net 353)
	)
	(via blind
		(at 160.286328 72.5)
		(size 0.5)
		(drill 0.2)
		(layers "F.Cu" "In2.Cu")
		(net 353)
	)
	(segment
		(start 160.839 81.171712)
		(end 160.839 81.539)
		(width 0.182)
		(layer "In2.Cu")
		(net 353)
	)
	(segment
		(start 160.002054 82.186946)
		(end 160.002054 82.246)
		(width 0.182)
		(layer "In2.Cu")
		(net 353)
	)
	(segment
		(start 160.137027 82.380973)
		(end 160.326027 82.380973)
		(width 0.182)
		(layer "In2.Cu")
		(net 353)
	)
	(segment
		(start 160.414328 86.27818)
		(end 160.414328 86.619156)
		(width 0.182)
		(layer "In2.Cu")
		(net 353)
	)
	(segment
		(start 160.839 82.953)
		(end 160.839 84.928288)
		(width 0.182)
		(layer "In2.Cu")
		(net 353)
	)
	(segment
		(start 160.164328 72.622)
		(end 160.164328 78.19704)
		(width 0.182)
		(layer "In2.Cu")
		(net 353)
	)
	(segment
		(start 160.414328 85.716132)
		(end 160.502328 85.804132)
		(width 0.182)
		(layer "In2.Cu")
		(net 353)
	)
	(segment
		(start 160.286328 72.5)
		(end 160.164328 72.622)
		(width 0.182)
		(layer "In2.Cu")
		(net 353)
	)
	(segment
		(start 160.326027 82.051973)
		(end 160.137027 82.051973)
		(width 0.182)
		(layer "In2.Cu")
		(net 353)
	)
	(segment
		(start 160.189 80.521712)
		(end 160.839 81.171712)
		(width 0.182)
		(layer "In2.Cu")
		(net 353)
	)
	(segment
		(start 160.622045 78.654757)
		(end 160.622045 79.595243)
		(width 0.182)
		(layer "In2.Cu")
		(net 353)
	)
	(segment
		(start 160.622045 79.595243)
		(end 160.189 80.028288)
		(width 0.182)
		(layer "In2.Cu")
		(net 353)
	)
	(segment
		(start 160.164328 78.19704)
		(end 160.622045 78.654757)
		(width 0.182)
		(layer "In2.Cu")
		(net 353)
	)
	(segment
		(start 160.502328 86.19018)
		(end 160.414328 86.27818)
		(width 0.182)
		(layer "In2.Cu")
		(net 353)
	)
	(segment
		(start 160.414328 86.619156)
		(end 160.036328 86.997156)
		(width 0.182)
		(layer "In2.Cu")
		(net 353)
	)
	(segment
		(start 160.189 80.028288)
		(end 160.189 80.521712)
		(width 0.182)
		(layer "In2.Cu")
		(net 353)
	)
	(segment
		(start 160.414328 85.35296)
		(end 160.414328 85.716132)
		(width 0.182)
		(layer "In2.Cu")
		(net 353)
	)
	(segment
		(start 160.502328 85.804132)
		(end 160.502328 86.19018)
		(width 0.182)
		(layer "In2.Cu")
		(net 353)
	)
	(segment
		(start 160.839 84.928288)
		(end 160.414328 85.35296)
		(width 0.182)
		(layer "In2.Cu")
		(net 353)
	)
	(segment
		(start 160.839 82.893946)
		(end 160.839 82.953)
		(width 0.182)
		(layer "In2.Cu")
		(net 353)
	)
	(arc
		(start 160.002054 82.246)
		(mid 160.041587 82.34144)
		(end 160.137027 82.380973)
		(width 0.182)
		(layer "In2.Cu")
		(net 353)
	)
	(arc
		(start 160.326027 82.380973)
		(mid 160.688754 82.531219)
		(end 160.839 82.893946)
		(width 0.182)
		(layer "In2.Cu")
		(net 353)
	)
	(arc
		(start 160.137027 82.051973)
		(mid 160.041587 82.091506)
		(end 160.002054 82.186946)
		(width 0.182)
		(layer "In2.Cu")
		(net 353)
	)
	(arc
		(start 160.839 81.539)
		(mid 160.688754 81.901727)
		(end 160.326027 82.051973)
		(width 0.182)
		(layer "In2.Cu")
		(net 353)
	)
	(segment
		(start 175.536329 92.497157)
		(end 176.036329 91.997157)
		(width 0.15)
		(layer "F.Cu")
		(net 390)
	)
	(segment
		(start 192.736328 70.597157)
		(end 192.136328 69.997157)
		(width 0.1)
		(layer "F.Cu")
		(net 390)
	)
	(segment
		(start 192.736328 71.197157)
		(end 192.736328 70.597157)
		(width 0.1)
		(layer "F.Cu")
		(net 390)
	)
	(segment
		(start 192.136328 69.997157)
		(end 192.136328 69.647157)
		(width 0.1)
		(layer "F.Cu")
		(net 390)
	)
	(segment
		(start 192.736328 71.212157)
		(end 192.694179 71.212157)
		(width 0.1)
		(layer "F.Cu")
		(net 390)
	)
	(segment
		(start 192.694179 71.212157)
		(end 191.92 71.986336)
		(width 0.1)
		(layer "F.Cu")
		(net 390)
	)
	(segment
		(start 191.92 71.986336)
		(end 191.92 82.886336)
		(width 0.1)
		(layer "F.Cu")
		(net 390)
	)
	(segment
		(start 191.92 82.886336)
		(end 189.986328 84.820008)
		(width 0.1)
		(layer "F.Cu")
		(net 390)
	)
	(via blind
		(at 176.036329 91.997157)
		(size 0.5)
		(drill 0.2)
		(layers "F.Cu" "In2.Cu")
		(net 390)
	)
	(via
		(at 189.986328 84.820008)
		(size 0.5)
		(drill 0.2)
		(layers "F.Cu" "B.Cu")
		(net 390)
	)
	(segment
		(start 184.301341 91.137168)
		(end 189.986328 85.45218)
		(width 0.1)
		(layer "In2.Cu")
		(net 390)
	)
	(segment
		(start 189.986328 85.45218)
		(end 189.986328 84.820008)
		(width 0.1)
		(layer "In2.Cu")
		(net 390)
	)
	(segment
		(start 176.036329 91.997157)
		(end 176.896318 91.137168)
		(width 0.1)
		(layer "In2.Cu")
		(net 390)
	)
	(segment
		(start 176.896318 91.137168)
		(end 184.301341 91.137168)
		(width 0.1)
		(layer "In2.Cu")
		(net 390)
	)
	(segment
		(start 178.536329 92.497157)
		(end 179.036329 91.997157)
		(width 0.15)
		(layer "F.Cu")
		(net 391)
	)
	(segment
		(start 179.036329 91.997157)
		(end 180.536328 91.997157)
		(width 0.15)
		(layer "F.Cu")
		(net 391)
	)
	(segment
		(start 196.736328 71.212157)
		(end 196.736328 69.847157)
		(width 0.1)
		(layer "F.Cu")
		(net 391)
	)
	(segment
		(start 196.736328 69.847157)
		(end 196.536328 69.647157)
		(width 0.1)
		(layer "F.Cu")
		(net 391)
	)
	(segment
		(start 196.416328 71.212157)
		(end 196.186328 71.442157)
		(width 0.1)
		(layer "F.Cu")
		(net 391)
	)
	(segment
		(start 196.186328 71.442157)
		(end 196.186328 76.720008)
		(width 0.1)
		(layer "F.Cu")
		(net 391)
	)
	(segment
		(start 196.736328 71.212157)
		(end 196.416328 71.212157)
		(width 0.1)
		(layer "F.Cu")
		(net 391)
	)
	(segment
		(start 194.886328 78.020008)
		(end 194.886328 80.120008)
		(width 0.1)
		(layer "F.Cu")
		(net 391)
	)
	(segment
		(start 196.186328 76.720008)
		(end 194.886328 78.020008)
		(width 0.1)
		(layer "F.Cu")
		(net 391)
	)
	(via blind
		(at 180.536328 91.997157)
		(size 0.5)
		(drill 0.2)
		(layers "F.Cu" "In2.Cu")
		(net 391)
	)
	(via
		(at 194.886328 80.120008)
		(size 0.5)
		(drill 0.2)
		(layers "F.Cu" "B.Cu")
		(net 391)
	)
	(segment
		(start 180.536328 91.997157)
		(end 180.896295 91.63719)
		(width 0.1)
		(layer "In2.Cu")
		(net 391)
	)
	(segment
		(start 194.886328 81.220008)
		(end 194.886328 80.120008)
		(width 0.1)
		(layer "In2.Cu")
		(net 391)
	)
	(segment
		(start 180.896295 91.63719)
		(end 184.508455 91.63719)
		(width 0.1)
		(layer "In2.Cu")
		(net 391)
	)
	(segment
		(start 184.508455 91.63719)
		(end 194.886328 81.259317)
		(width 0.1)
		(layer "In2.Cu")
		(net 391)
	)
	(segment
		(start 194.886328 81.259317)
		(end 194.886328 81.220008)
		(width 0.1)
		(layer "In2.Cu")
		(net 391)
	)
	(segment
		(start 177.536329 93.497156)
		(end 178.036329 92.997156)
		(width 0.15)
		(layer "F.Cu")
		(net 392)
	)
	(segment
		(start 200.736328 71.212157)
		(end 200.736328 69.847157)
		(width 0.1)
		(layer "F.Cu")
		(net 392)
	)
	(segment
		(start 198.686328 74.820008)
		(end 198.686328 78.820008)
		(width 0.1)
		(layer "F.Cu")
		(net 392)
	)
	(segment
		(start 199.986328 73.520008)
		(end 198.686328 74.820008)
		(width 0.1)
		(layer "F.Cu")
		(net 392)
	)
	(segment
		(start 199.986328 71.962157)
		(end 199.986328 73.520008)
		(width 0.1)
		(layer "F.Cu")
		(net 392)
	)
	(segment
		(start 199.986328 71.962157)
		(end 200.736328 71.212157)
		(width 0.1)
		(layer "F.Cu")
		(net 392)
	)
	(via blind
		(at 178.036329 92.997156)
		(size 0.5)
		(drill 0.2)
		(layers "F.Cu" "In2.Cu")
		(net 392)
	)
	(via
		(at 198.686328 78.820008)
		(size 0.5)
		(drill 0.2)
		(layers "F.Cu" "B.Cu")
		(net 392)
	)
	(segment
		(start 195.232773 81.620008)
		(end 196.886328 81.620008)
		(width 0.1)
		(layer "In2.Cu")
		(net 392)
	)
	(segment
		(start 178.036329 92.997156)
		(end 178.24633 93.207157)
		(width 0.1)
		(layer "In2.Cu")
		(net 392)
	)
	(segment
		(start 178.24633 93.207157)
		(end 183.645624 93.207157)
		(width 0.1)
		(layer "In2.Cu")
		(net 392)
	)
	(segment
		(start 183.645624 93.207157)
		(end 195.232773 81.620008)
		(width 0.1)
		(layer "In2.Cu")
		(net 392)
	)
	(segment
		(start 198.686328 79.820008)
		(end 198.686328 78.820008)
		(width 0.1)
		(layer "In2.Cu")
		(net 392)
	)
	(segment
		(start 196.886328 81.620008)
		(end 198.686328 79.820008)
		(width 0.1)
		(layer "In2.Cu")
		(net 392)
	)
	(segment
		(start 170.286328 70.772157)
		(end 170.286328 72.625)
		(width 0.1)
		(layer "F.Cu")
		(net 393)
	)
	(segment
		(start 169.536329 89.494683)
		(end 170.036338 88.994674)
		(width 0.15)
		(layer "F.Cu")
		(net 393)
	)
	(segment
		(start 169.536329 89.497157)
		(end 169.536329 89.494683)
		(width 0.15)
		(layer "F.Cu")
		(net 393)
	)
	(via blind
		(at 170.286328 72.625)
		(size 0.5)
		(drill 0.2)
		(layers "F.Cu" "In2.Cu")
		(net 393)
	)
	(via blind
		(at 170.036338 88.994674)
		(size 0.5)
		(drill 0.2)
		(layers "F.Cu" "In2.Cu")
		(net 393)
	)
	(segment
		(start 170.286328 86.47467)
		(end 170.55 86.738342)
		(width 0.182)
		(layer "In2.Cu")
		(net 393)
	)
	(segment
		(start 170.55 88.481012)
		(end 170.036338 88.994674)
		(width 0.182)
		(layer "In2.Cu")
		(net 393)
	)
	(segment
		(start 170.55 86.738342)
		(end 170.55 88.481012)
		(width 0.182)
		(layer "In2.Cu")
		(net 393)
	)
	(segment
		(start 170.286328 72.625)
		(end 170.286328 86.47467)
		(width 0.182)
		(layer "In2.Cu")
		(net 393)
	)
	(segment
		(start 169.536329 87.481156)
		(end 170.036329 86.981157)
		(width 0.15)
		(layer "F.Cu")
		(net 394)
	)
	(segment
		(start 169.786328 70.772157)
		(end 169.786328 72.122157)
		(width 0.1)
		(layer "F.Cu")
		(net 394)
	)
	(via blind
		(at 170.036329 86.981157)
		(size 0.5)
		(drill 0.2)
		(layers "F.Cu" "In2.Cu")
		(net 394)
	)
	(via blind
		(at 169.786328 72.122157)
		(size 0.5)
		(drill 0.2)
		(layers "F.Cu" "In2.Cu")
		(net 394)
	)
	(segment
		(start 169.786328 74.547672)
		(end 169.786328 86.731156)
		(width 0.182)
		(layer "In2.Cu")
		(net 394)
	)
	(segment
		(start 169.629328 72.820672)
		(end 169.43402 72.820672)
		(width 0.182)
		(layer "In2.Cu")
		(net 394)
	)
	(segment
		(start 169.629328 74.076672)
		(end 169.43402 74.076672)
		(width 0.182)
		(layer "In2.Cu")
		(net 394)
	)
	(segment
		(start 169.629328 73.448672)
		(end 169.43402 73.448672)
		(width 0.182)
		(layer "In2.Cu")
		(net 394)
	)
	(segment
		(start 169.43402 73.134672)
		(end 169.629328 73.134672)
		(width 0.182)
		(layer "In2.Cu")
		(net 394)
	)
	(segment
		(start 169.43402 74.390672)
		(end 169.629328 74.390672)
		(width 0.182)
		(layer "In2.Cu")
		(net 394)
	)
	(segment
		(start 169.786328 86.731156)
		(end 170.036329 86.981157)
		(width 0.182)
		(layer "In2.Cu")
		(net 394)
	)
	(segment
		(start 169.786328 72.122157)
		(end 169.786328 72.663672)
		(width 0.182)
		(layer "In2.Cu")
		(net 394)
	)
	(segment
		(start 169.43402 73.762672)
		(end 169.629328 73.762672)
		(width 0.182)
		(layer "In2.Cu")
		(net 394)
	)
	(arc
		(start 169.27702 73.605672)
		(mid 169.323004 73.716688)
		(end 169.43402 73.762672)
		(width 0.182)
		(layer "In2.Cu")
		(net 394)
	)
	(arc
		(start 169.786328 73.291672)
		(mid 169.740344 73.402688)
		(end 169.629328 73.448672)
		(width 0.182)
		(layer "In2.Cu")
		(net 394)
	)
	(arc
		(start 169.43402 72.820672)
		(mid 169.323004 72.866656)
		(end 169.27702 72.977672)
		(width 0.182)
		(layer "In2.Cu")
		(net 394)
	)
	(arc
		(start 169.27702 74.233672)
		(mid 169.323004 74.344688)
		(end 169.43402 74.390672)
		(width 0.182)
		(layer "In2.Cu")
		(net 394)
	)
	(arc
		(start 169.786328 73.919672)
		(mid 169.740344 74.030688)
		(end 169.629328 74.076672)
		(width 0.182)
		(layer "In2.Cu")
		(net 394)
	)
	(arc
		(start 169.27702 72.977672)
		(mid 169.323004 73.088688)
		(end 169.43402 73.134672)
		(width 0.182)
		(layer "In2.Cu")
		(net 394)
	)
	(arc
		(start 169.629328 74.390672)
		(mid 169.740344 74.436656)
		(end 169.786328 74.547672)
		(width 0.182)
		(layer "In2.Cu")
		(net 394)
	)
	(arc
		(start 169.629328 73.762672)
		(mid 169.740344 73.808656)
		(end 169.786328 73.919672)
		(width 0.182)
		(layer "In2.Cu")
		(net 394)
	)
	(arc
		(start 169.43402 74.076672)
		(mid 169.323004 74.122656)
		(end 169.27702 74.233672)
		(width 0.182)
		(layer "In2.Cu")
		(net 394)
	)
	(arc
		(start 169.786328 72.663672)
		(mid 169.740344 72.774688)
		(end 169.629328 72.820672)
		(width 0.182)
		(layer "In2.Cu")
		(net 394)
	)
	(arc
		(start 169.629328 73.134672)
		(mid 169.740344 73.180656)
		(end 169.786328 73.291672)
		(width 0.182)
		(layer "In2.Cu")
		(net 394)
	)
	(arc
		(start 169.43402 73.448672)
		(mid 169.323004 73.494656)
		(end 169.27702 73.605672)
		(width 0.182)
		(layer "In2.Cu")
		(net 394)
	)
	(segment
		(start 167.536329 87.497157)
		(end 167.036329 86.997157)
		(width 0.15)
		(layer "F.Cu")
		(net 395)
	)
	(segment
		(start 167.286328 70.772157)
		(end 167.286328 72.122157)
		(width 0.1)
		(layer "F.Cu")
		(net 395)
	)
	(via blind
		(at 167.036329 86.997157)
		(size 0.5)
		(drill 0.2)
		(layers "F.Cu" "In2.Cu")
		(net 395)
	)
	(via blind
		(at 167.286328 72.122157)
		(size 0.5)
		(drill 0.2)
		(layers "F.Cu" "In2.Cu")
		(net 395)
	)
	(segment
		(start 167.193329 74.648671)
		(end 167.385969 74.648671)
		(width 0.182)
		(layer "In2.Cu")
		(net 395)
	)
	(segment
		(start 167.385969 74.334671)
		(end 167.193329 74.334671)
		(width 0.182)
		(layer "In2.Cu")
		(net 395)
	)
	(segment
		(start 167.385969 75.590671)
		(end 167.193329 75.590671)
		(width 0.182)
		(layer "In2.Cu")
		(net 395)
	)
	(segment
		(start 167.385969 74.962671)
		(end 167.193329 74.962671)
		(width 0.182)
		(layer "In2.Cu")
		(net 395)
	)
	(segment
		(start 167.286328 72.122157)
		(end 167.286328 72.788974)
		(width 0.182)
		(layer "In2.Cu")
		(net 395)
	)
	(segment
		(start 167.036329 75.747671)
		(end 167.036329 86.997157)
		(width 0.182)
		(layer "In2.Cu")
		(net 395)
	)
	(segment
		(start 167.286328 72.788974)
		(end 167.036329 73.038973)
		(width 0.182)
		(layer "In2.Cu")
		(net 395)
	)
	(segment
		(start 167.036329 73.038973)
		(end 167.036329 73.863671)
		(width 0.182)
		(layer "In2.Cu")
		(net 395)
	)
	(segment
		(start 167.193329 74.020671)
		(end 167.385969 74.020671)
		(width 0.182)
		(layer "In2.Cu")
		(net 395)
	)
	(segment
		(start 167.193329 75.276671)
		(end 167.385969 75.276671)
		(width 0.182)
		(layer "In2.Cu")
		(net 395)
	)
	(arc
		(start 167.542969 74.805671)
		(mid 167.496985 74.916687)
		(end 167.385969 74.962671)
		(width 0.182)
		(layer "In2.Cu")
		(net 395)
	)
	(arc
		(start 167.036329 75.119671)
		(mid 167.082313 75.230687)
		(end 167.193329 75.276671)
		(width 0.182)
		(layer "In2.Cu")
		(net 395)
	)
	(arc
		(start 167.542969 74.177671)
		(mid 167.496985 74.288687)
		(end 167.385969 74.334671)
		(width 0.182)
		(layer "In2.Cu")
		(net 395)
	)
	(arc
		(start 167.036329 74.491671)
		(mid 167.082313 74.602687)
		(end 167.193329 74.648671)
		(width 0.182)
		(layer "In2.Cu")
		(net 395)
	)
	(arc
		(start 167.542969 75.433671)
		(mid 167.496985 75.544687)
		(end 167.385969 75.590671)
		(width 0.182)
		(layer "In2.Cu")
		(net 395)
	)
	(arc
		(start 167.193329 74.962671)
		(mid 167.082313 75.008655)
		(end 167.036329 75.119671)
		(width 0.182)
		(layer "In2.Cu")
		(net 395)
	)
	(arc
		(start 167.193329 75.590671)
		(mid 167.082313 75.636655)
		(end 167.036329 75.747671)
		(width 0.182)
		(layer "In2.Cu")
		(net 395)
	)
	(arc
		(start 167.385969 74.020671)
		(mid 167.496985 74.066655)
		(end 167.542969 74.177671)
		(width 0.182)
		(layer "In2.Cu")
		(net 395)
	)
	(arc
		(start 167.385969 75.276671)
		(mid 167.496985 75.322655)
		(end 167.542969 75.433671)
		(width 0.182)
		(layer "In2.Cu")
		(net 395)
	)
	(arc
		(start 167.036329 73.863671)
		(mid 167.082313 73.974687)
		(end 167.193329 74.020671)
		(width 0.182)
		(layer "In2.Cu")
		(net 395)
	)
	(arc
		(start 167.193329 74.334671)
		(mid 167.082313 74.380655)
		(end 167.036329 74.491671)
		(width 0.182)
		(layer "In2.Cu")
		(net 395)
	)
	(arc
		(start 167.385969 74.648671)
		(mid 167.496985 74.694655)
		(end 167.542969 74.805671)
		(width 0.182)
		(layer "In2.Cu")
		(net 395)
	)
	(segment
		(start 167.536329 88.497156)
		(end 167.036329 87.997157)
		(width 0.15)
		(layer "F.Cu")
		(net 396)
	)
	(segment
		(start 167.786328 70.772157)
		(end 167.786328 72.625)
		(width 0.1)
		(layer "F.Cu")
		(net 396)
	)
	(via blind
		(at 167.036329 87.997157)
		(size 0.5)
		(drill 0.2)
		(layers "F.Cu" "In2.Cu")
		(net 396)
	)
	(via blind
		(at 167.786328 72.625)
		(size 0.5)
		(drill 0.2)
		(layers "F.Cu" "In2.Cu")
		(net 396)
	)
	(segment
		(start 168.005828 73.672172)
		(end 168.005828 87.027658)
		(width 0.182)
		(layer "In2.Cu")
		(net 396)
	)
	(segment
		(start 168.005828 72.8445)
		(end 168.005828 73.044172)
		(width 0.182)
		(layer "In2.Cu")
		(net 396)
	)
	(segment
		(start 167.606831 73.515172)
		(end 167.848828 73.515172)
		(width 0.182)
		(layer "In2.Cu")
		(net 396)
	)
	(segment
		(start 167.848828 73.201172)
		(end 167.606831 73.201172)
		(width 0.182)
		(layer "In2.Cu")
		(net 396)
	)
	(segment
		(start 168.005828 87.027658)
		(end 167.036329 87.997157)
		(width 0.182)
		(layer "In2.Cu")
		(net 396)
	)
	(segment
		(start 167.786328 72.625)
		(end 168.005828 72.8445)
		(width 0.182)
		(layer "In2.Cu")
		(net 396)
	)
	(arc
		(start 168.005828 73.044172)
		(mid 167.959844 73.155188)
		(end 167.848828 73.201172)
		(width 0.182)
		(layer "In2.Cu")
		(net 396)
	)
	(arc
		(start 167.848828 73.515172)
		(mid 167.959844 73.561156)
		(end 168.005828 73.672172)
		(width 0.182)
		(layer "In2.Cu")
		(net 396)
	)
	(arc
		(start 167.606831 73.201172)
		(mid 167.495815 73.247156)
		(end 167.449831 73.358172)
		(width 0.182)
		(layer "In2.Cu")
		(net 396)
	)
	(arc
		(start 167.449831 73.358172)
		(mid 167.495815 73.469188)
		(end 167.606831 73.515172)
		(width 0.182)
		(layer "In2.Cu")
		(net 396)
	)
	(segment
		(start 168.536329 89.497157)
		(end 168.036329 88.997157)
		(width 0.15)
		(layer "F.Cu")
		(net 397)
	)
	(segment
		(start 168.286328 70.772157)
		(end 168.286328 72.122157)
		(width 0.1)
		(layer "F.Cu")
		(net 397)
	)
	(via blind
		(at 168.036329 88.997157)
		(size 0.5)
		(drill 0.2)
		(layers "F.Cu" "In2.Cu")
		(net 397)
	)
	(via blind
		(at 168.286328 72.122157)
		(size 0.5)
		(drill 0.2)
		(layers "F.Cu" "In2.Cu")
		(net 397)
	)
	(segment
		(start 168.566828 88.466658)
		(end 168.036329 88.997157)
		(width 0.182)
		(layer "In2.Cu")
		(net 397)
	)
	(segment
		(start 168.566828 72.402657)
		(end 168.566828 88.466658)
		(width 0.182)
		(layer "In2.Cu")
		(net 397)
	)
	(segment
		(start 168.286328 72.122157)
		(end 168.566828 72.402657)
		(width 0.182)
		(layer "In2.Cu")
		(net 397)
	)
	(segment
		(start 161.536329 88.497157)
		(end 161.036329 87.997157)
		(width 0.15)
		(layer "F.Cu")
		(net 398)
	)
	(segment
		(start 161.286328 70.772157)
		(end 161.286328 72.122157)
		(width 0.1)
		(layer "F.Cu")
		(net 398)
	)
	(via blind
		(at 161.286328 72.122157)
		(size 0.5)
		(drill 0.2)
		(layers "F.Cu" "In2.Cu")
		(net 398)
	)
	(via blind
		(at 161.036329 87.997157)
		(size 0.5)
		(drill 0.2)
		(layers "F.Cu" "In2.Cu")
		(net 398)
	)
	(segment
		(start 161.505829 86.705829)
		(end 161.35 86.55)
		(width 0.182)
		(layer "In2.Cu")
		(net 398)
	)
	(segment
		(start 161.15 78.1)
		(end 161.043 78.1)
		(width 0.182)
		(layer "In2.Cu")
		(net 398)
	)
	(segment
		(start 161.2805 72.127985)
		(end 161.286328 72.122157)
		(width 0.182)
		(layer "In2.Cu")
		(net 398)
	)
	(segment
		(start 161.35 85.922)
		(end 161.35 85.872)
		(width 0.182)
		(layer "In2.Cu")
		(net 398)
	)
	(segment
		(start 161.154451 86.079)
		(end 161.193 86.079)
		(width 0.182)
		(layer "In2.Cu")
		(net 398)
	)
	(segment
		(start 161.193 86.393)
		(end 161.154451 86.393)
		(width 0.182)
		(layer "In2.Cu")
		(net 398)
	)
	(segment
		(start 161.35 85.872)
		(end 161.35 78.3)
		(width 0.182)
		(layer "In2.Cu")
		(net 398)
	)
	(segment
		(start 161.036329 87.997157)
		(end 161.505829 87.527657)
		(width 0.182)
		(layer "In2.Cu")
		(net 398)
	)
	(segment
		(start 161 73.0265)
		(end 161.1235 73.0265)
		(width 0.182)
		(layer "In2.Cu")
		(net 398)
	)
	(segment
		(start 161.2805 72.8695)
		(end 161.2805 72.127985)
		(width 0.182)
		(layer "In2.Cu")
		(net 398)
	)
	(segment
		(start 161.505829 87.527657)
		(end 161.505829 86.705829)
		(width 0.182)
		(layer "In2.Cu")
		(net 398)
	)
	(segment
		(start 160.843 77.9)
		(end 160.843 73.1835)
		(width 0.182)
		(layer "In2.Cu")
		(net 398)
	)
	(arc
		(start 160.997451 86.236)
		(mid 161.043435 86.124984)
		(end 161.154451 86.079)
		(width 0.182)
		(layer "In2.Cu")
		(net 398)
	)
	(arc
		(start 161.1235 73.0265)
		(mid 161.234516 72.980516)
		(end 161.2805 72.8695)
		(width 0.182)
		(layer "In2.Cu")
		(net 398)
	)
	(arc
		(start 161.154451 86.393)
		(mid 161.043435 86.347016)
		(end 160.997451 86.236)
		(width 0.182)
		(layer "In2.Cu")
		(net 398)
	)
	(arc
		(start 160.843 73.1835)
		(mid 160.888984 73.072484)
		(end 161 73.0265)
		(width 0.182)
		(layer "In2.Cu")
		(net 398)
	)
	(arc
		(start 161.193 86.079)
		(mid 161.304016 86.033016)
		(end 161.35 85.922)
		(width 0.182)
		(layer "In2.Cu")
		(net 398)
	)
	(arc
		(start 161.043 78.1)
		(mid 160.901579 78.041421)
		(end 160.843 77.9)
		(width 0.182)
		(layer "In2.Cu")
		(net 398)
	)
	(arc
		(start 161.35 78.3)
		(mid 161.291421 78.158579)
		(end 161.15 78.1)
		(width 0.182)
		(layer "In2.Cu")
		(net 398)
	)
	(arc
		(start 161.35 86.55)
		(mid 161.304016 86.438984)
		(end 161.193 86.393)
		(width 0.182)
		(layer "In2.Cu")
		(net 398)
	)
	(segment
		(start 162.536329 88.497156)
		(end 162.036329 87.997157)
		(width 0.15)
		(layer "F.Cu")
		(net 399)
	)
	(segment
		(start 162.286328 70.772157)
		(end 162.286328 72.122157)
		(width 0.1)
		(layer "F.Cu")
		(net 399)
	)
	(via blind
		(at 162.036329 87.997157)
		(size 0.5)
		(drill 0.2)
		(layers "F.Cu" "In2.Cu")
		(net 399)
	)
	(via blind
		(at 162.286328 72.122157)
		(size 0.5)
		(drill 0.2)
		(layers "F.Cu" "In2.Cu")
		(net 399)
	)
	(segment
		(start 162.286328 75.958958)
		(end 162.286328 86.086328)
		(width 0.182)
		(layer "In2.Cu")
		(net 399)
	)
	(segment
		(start 162.12737 75.8)
		(end 161.807 75.8)
		(width 0.182)
		(layer "In2.Cu")
		(net 399)
	)
	(segment
		(start 162.286328 86.086328)
		(end 162.566829 86.366829)
		(width 0.182)
		(layer "In2.Cu")
		(net 399)
	)
	(segment
		(start 161.808958 73.943328)
		(end 162.129328 73.943328)
		(width 0.182)
		(layer "In2.Cu")
		(net 399)
	)
	(segment
		(start 162.566829 87.466657)
		(end 162.566829 86.366829)
		(width 0.182)
		(layer "In2.Cu")
		(net 399)
	)
	(segment
		(start 161.65 75.643)
		(end 161.65 74.102286)
		(width 0.182)
		(layer "In2.Cu")
		(net 399)
	)
	(segment
		(start 161.65 74.102286)
		(end 161.651958 74.100328)
		(width 0.182)
		(layer "In2.Cu")
		(net 399)
	)
	(segment
		(start 162.286328 75.958958)
		(end 162.28437 75.957)
		(width 0.182)
		(layer "In2.Cu")
		(net 399)
	)
	(segment
		(start 162.036329 87.997157)
		(end 162.566829 87.466657)
		(width 0.182)
		(layer "In2.Cu")
		(net 399)
	)
	(segment
		(start 162.286328 73.786328)
		(end 162.286328 72.122157)
		(width 0.182)
		(layer "In2.Cu")
		(net 399)
	)
	(arc
		(start 161.651958 74.100328)
		(mid 161.697942 73.989312)
		(end 161.808958 73.943328)
		(width 0.182)
		(layer "In2.Cu")
		(net 399)
	)
	(arc
		(start 161.807 75.8)
		(mid 161.695984 75.754016)
		(end 161.65 75.643)
		(width 0.182)
		(layer "In2.Cu")
		(net 399)
	)
	(arc
		(start 162.129328 73.943328)
		(mid 162.240344 73.897344)
		(end 162.286328 73.786328)
		(width 0.182)
		(layer "In2.Cu")
		(net 399)
	)
	(arc
		(start 162.28437 75.957)
		(mid 162.238386 75.845984)
		(end 162.12737 75.8)
		(width 0.182)
		(layer "In2.Cu")
		(net 399)
	)
	(segment
		(start 163.786328 70.772157)
		(end 163.786328 72.625)
		(width 0.1)
		(layer "F.Cu")
		(net 400)
	)
	(segment
		(start 164.536328 88.497155)
		(end 164.036329 87.997156)
		(width 0.1)
		(layer "F.Cu")
		(net 400)
	)
	(segment
		(start 164.536328 88.497157)
		(end 164.536328 88.497155)
		(width 0.1)
		(layer "F.Cu")
		(net 400)
	)
	(via blind
		(at 163.786328 72.625)
		(size 0.5)
		(drill 0.2)
		(layers "F.Cu" "In2.Cu")
		(net 400)
	)
	(via blind
		(at 164.036329 87.997156)
		(size 0.5)
		(drill 0.2)
		(layers "F.Cu" "In2.Cu")
		(net 400)
	)
	(segment
		(start 164.072014 74.385328)
		(end 163.943328 74.385328)
		(width 0.182)
		(layer "In2.Cu")
		(net 400)
	)
	(segment
		(start 163.786328 72.625)
		(end 163.786328 73.286328)
		(width 0.182)
		(layer "In2.Cu")
		(net 400)
	)
	(segment
		(start 163.943328 73.443328)
		(end 164.072014 73.443328)
		(width 0.182)
		(layer "In2.Cu")
		(net 400)
	)
	(segment
		(start 163.786328 74.542328)
		(end 163.786328 84.736583)
		(width 0.182)
		(layer "In2.Cu")
		(net 400)
	)
	(segment
		(start 164.036329 84.986584)
		(end 164.036329 87.997156)
		(width 0.182)
		(layer "In2.Cu")
		(net 400)
	)
	(segment
		(start 164.072014 73.757328)
		(end 163.943328 73.757328)
		(width 0.182)
		(layer "In2.Cu")
		(net 400)
	)
	(segment
		(start 163.943328 74.071328)
		(end 164.072014 74.071328)
		(width 0.182)
		(layer "In2.Cu")
		(net 400)
	)
	(segment
		(start 163.786328 84.736583)
		(end 164.036329 84.986584)
		(width 0.182)
		(layer "In2.Cu")
		(net 400)
	)
	(arc
		(start 163.943328 73.757328)
		(mid 163.832312 73.803312)
		(end 163.786328 73.914328)
		(width 0.182)
		(layer "In2.Cu")
		(net 400)
	)
	(arc
		(start 163.786328 73.286328)
		(mid 163.832312 73.397344)
		(end 163.943328 73.443328)
		(width 0.182)
		(layer "In2.Cu")
		(net 400)
	)
	(arc
		(start 164.072014 73.443328)
		(mid 164.18303 73.489312)
		(end 164.229014 73.600328)
		(width 0.182)
		(layer "In2.Cu")
		(net 400)
	)
	(arc
		(start 164.229014 74.228328)
		(mid 164.18303 74.339344)
		(end 164.072014 74.385328)
		(width 0.182)
		(layer "In2.Cu")
		(net 400)
	)
	(arc
		(start 163.786328 73.914328)
		(mid 163.832312 74.025344)
		(end 163.943328 74.071328)
		(width 0.182)
		(layer "In2.Cu")
		(net 400)
	)
	(arc
		(start 164.072014 74.071328)
		(mid 164.18303 74.117312)
		(end 164.229014 74.228328)
		(width 0.182)
		(layer "In2.Cu")
		(net 400)
	)
	(arc
		(start 164.229014 73.600328)
		(mid 164.18303 73.711344)
		(end 164.072014 73.757328)
		(width 0.182)
		(layer "In2.Cu")
		(net 400)
	)
	(arc
		(start 163.943328 74.385328)
		(mid 163.832312 74.431312)
		(end 163.786328 74.542328)
		(width 0.182)
		(layer "In2.Cu")
		(net 400)
	)
	(segment
		(start 165.536329 88.497157)
		(end 165.036329 87.997157)
		(width 0.15)
		(layer "F.Cu")
		(net 401)
	)
	(segment
		(start 164.286328 70.772157)
		(end 164.286328 72.122157)
		(width 0.1)
		(layer "F.Cu")
		(net 401)
	)
	(via blind
		(at 165.036329 87.997157)
		(size 0.5)
		(drill 0.2)
		(layers "F.Cu" "In2.Cu")
		(net 401)
	)
	(via blind
		(at 164.286328 72.122157)
		(size 0.5)
		(drill 0.2)
		(layers "F.Cu" "In2.Cu")
		(net 401)
	)
	(segment
		(start 164.566828 87.527656)
		(end 165.036329 87.997157)
		(width 0.182)
		(layer "In2.Cu")
		(net 401)
	)
	(segment
		(start 164.566828 76.422828)
		(end 164.566828 87.527656)
		(width 0.182)
		(layer "In2.Cu")
		(net 401)
	)
	(segment
		(start 164.384828 75.148828)
		(end 164.336457 75.148828)
		(width 0.182)
		(layer "In2.Cu")
		(net 401)
	)
	(segment
		(start 164.336457 75.512828)
		(end 164.384828 75.512828)
		(width 0.182)
		(layer "In2.Cu")
		(net 401)
	)
	(segment
		(start 164.286328 72.9)
		(end 164.566828 73.1805)
		(width 0.182)
		(layer "In2.Cu")
		(net 401)
	)
	(segment
		(start 164.384828 75.876828)
		(end 164.336457 75.876828)
		(width 0.182)
		(layer "In2.Cu")
		(net 401)
	)
	(segment
		(start 164.286328 72.122157)
		(end 164.286328 72.9)
		(width 0.182)
		(layer "In2.Cu")
		(net 401)
	)
	(segment
		(start 164.566828 73.1805)
		(end 164.566828 74.966828)
		(width 0.182)
		(layer "In2.Cu")
		(net 401)
	)
	(segment
		(start 164.336457 76.240828)
		(end 164.384828 76.240828)
		(width 0.182)
		(layer "In2.Cu")
		(net 401)
	)
	(arc
		(start 164.566828 75.694828)
		(mid 164.513521 75.823521)
		(end 164.384828 75.876828)
		(width 0.182)
		(layer "In2.Cu")
		(net 401)
	)
	(arc
		(start 164.566828 74.966828)
		(mid 164.513521 75.095521)
		(end 164.384828 75.148828)
		(width 0.182)
		(layer "In2.Cu")
		(net 401)
	)
	(arc
		(start 164.154457 75.330828)
		(mid 164.207764 75.459521)
		(end 164.336457 75.512828)
		(width 0.182)
		(layer "In2.Cu")
		(net 401)
	)
	(arc
		(start 164.336457 75.876828)
		(mid 164.207764 75.930135)
		(end 164.154457 76.058828)
		(width 0.182)
		(layer "In2.Cu")
		(net 401)
	)
	(arc
		(start 164.336457 75.148828)
		(mid 164.207764 75.202135)
		(end 164.154457 75.330828)
		(width 0.182)
		(layer "In2.Cu")
		(net 401)
	)
	(arc
		(start 164.384828 75.512828)
		(mid 164.513521 75.566135)
		(end 164.566828 75.694828)
		(width 0.182)
		(layer "In2.Cu")
		(net 401)
	)
	(arc
		(start 164.384828 76.240828)
		(mid 164.513521 76.294135)
		(end 164.566828 76.422828)
		(width 0.182)
		(layer "In2.Cu")
		(net 401)
	)
	(arc
		(start 164.154457 76.058828)
		(mid 164.207764 76.187521)
		(end 164.336457 76.240828)
		(width 0.182)
		(layer "In2.Cu")
		(net 401)
	)
	(segment
		(start 166.536329 88.497157)
		(end 166.036329 87.997157)
		(width 0.15)
		(layer "F.Cu")
		(net 402)
	)
	(segment
		(start 165.286328 70.772157)
		(end 165.286328 72.122157)
		(width 0.1)
		(layer "F.Cu")
		(net 402)
	)
	(via blind
		(at 166.036329 87.997157)
		(size 0.5)
		(drill 0.2)
		(layers "F.Cu" "In2.Cu")
		(net 402)
	)
	(via blind
		(at 165.286328 72.122157)
		(size 0.5)
		(drill 0.2)
		(layers "F.Cu" "In2.Cu")
		(net 402)
	)
	(segment
		(start 165.286328 73.842328)
		(end 165.286328 86.286328)
		(width 0.182)
		(layer "In2.Cu")
		(net 402)
	)
	(segment
		(start 165.443328 72.693328)
		(end 165.520237 72.693328)
		(width 0.182)
		(layer "In2.Cu")
		(net 402)
	)
	(segment
		(start 165.286328 73.792328)
		(end 165.286328 73.842328)
		(width 0.182)
		(layer "In2.Cu")
		(net 402)
	)
	(segment
		(start 165.286328 72.122157)
		(end 165.286328 72.536328)
		(width 0.182)
		(layer "In2.Cu")
		(net 402)
	)
	(segment
		(start 165.286328 86.286328)
		(end 165.505828 86.505828)
		(width 0.182)
		(layer "In2.Cu")
		(net 402)
	)
	(segment
		(start 165.505828 87.466656)
		(end 166.036329 87.997157)
		(width 0.182)
		(layer "In2.Cu")
		(net 402)
	)
	(segment
		(start 165.505828 86.505828)
		(end 165.505828 87.466656)
		(width 0.182)
		(layer "In2.Cu")
		(net 402)
	)
	(segment
		(start 165.520237 73.635328)
		(end 165.443328 73.635328)
		(width 0.182)
		(layer "In2.Cu")
		(net 402)
	)
	(segment
		(start 165.520237 73.007328)
		(end 165.443328 73.007328)
		(width 0.182)
		(layer "In2.Cu")
		(net 402)
	)
	(segment
		(start 165.443328 73.321328)
		(end 165.520237 73.321328)
		(width 0.182)
		(layer "In2.Cu")
		(net 402)
	)
	(arc
		(start 165.443328 73.007328)
		(mid 165.332312 73.053312)
		(end 165.286328 73.164328)
		(width 0.182)
		(layer "In2.Cu")
		(net 402)
	)
	(arc
		(start 165.443328 73.635328)
		(mid 165.332312 73.681312)
		(end 165.286328 73.792328)
		(width 0.182)
		(layer "In2.Cu")
		(net 402)
	)
	(arc
		(start 165.677237 72.850328)
		(mid 165.631253 72.961344)
		(end 165.520237 73.007328)
		(width 0.182)
		(layer "In2.Cu")
		(net 402)
	)
	(arc
		(start 165.286328 73.164328)
		(mid 165.332312 73.275344)
		(end 165.443328 73.321328)
		(width 0.182)
		(layer "In2.Cu")
		(net 402)
	)
	(arc
		(start 165.520237 73.321328)
		(mid 165.631253 73.367312)
		(end 165.677237 73.478328)
		(width 0.182)
		(layer "In2.Cu")
		(net 402)
	)
	(arc
		(start 165.520237 72.693328)
		(mid 165.631253 72.739312)
		(end 165.677237 72.850328)
		(width 0.182)
		(layer "In2.Cu")
		(net 402)
	)
	(arc
		(start 165.677237 73.478328)
		(mid 165.631253 73.589344)
		(end 165.520237 73.635328)
		(width 0.182)
		(layer "In2.Cu")
		(net 402)
	)
	(arc
		(start 165.286328 72.536328)
		(mid 165.332312 72.647344)
		(end 165.443328 72.693328)
		(width 0.182)
		(layer "In2.Cu")
		(net 402)
	)
	(segment
		(start 162.536329 87.497157)
		(end 162.036329 86.997157)
		(width 0.15)
		(layer "F.Cu")
		(net 403)
	)
	(segment
		(start 161.786328 70.772157)
		(end 161.786328 72.588672)
		(width 0.1)
		(layer "F.Cu")
		(net 403)
	)
	(segment
		(start 161.786328 72.588672)
		(end 161.75 72.625)
		(width 0.1)
		(layer "F.Cu")
		(net 403)
	)
	(via blind
		(at 162.036329 86.997157)
		(size 0.5)
		(drill 0.2)
		(layers "F.Cu" "In2.Cu")
		(net 403)
	)
	(via blind
		(at 161.75 72.625)
		(size 0.5)
		(drill 0.2)
		(layers "F.Cu" "In2.Cu")
		(net 403)
	)
	(segment
		(start 161.382 76.282)
		(end 161.516965 76.282)
		(width 0.182)
		(layer "In2.Cu")
		(net 403)
	)
	(segment
		(start 161.75 77.882)
		(end 161.75 86.15)
		(width 0.182)
		(layer "In2.Cu")
		(net 403)
	)
	(segment
		(start 161.382 77.01)
		(end 161.516965 77.01)
		(width 0.182)
		(layer "In2.Cu")
		(net 403)
	)
	(segment
		(start 161.357 77.725)
		(end 161.593 77.725)
		(width 0.182)
		(layer "In2.Cu")
		(net 403)
	)
	(segment
		(start 162.036329 86.436329)
		(end 162.036329 86.997157)
		(width 0.182)
		(layer "In2.Cu")
		(net 403)
	)
	(segment
		(start 161.2 77.556)
		(end 161.2 77.568)
		(width 0.182)
		(layer "In2.Cu")
		(net 403)
	)
	(segment
		(start 161.75 72.625)
		(end 161.75 73.3)
		(width 0.182)
		(layer "In2.Cu")
		(net 403)
	)
	(segment
		(start 161.593 73.457)
		(end 161.357 73.457)
		(width 0.182)
		(layer "In2.Cu")
		(net 403)
	)
	(segment
		(start 161.2 73.614)
		(end 161.2 76.1)
		(width 0.182)
		(layer "In2.Cu")
		(net 403)
	)
	(segment
		(start 161.516965 77.374)
		(end 161.382 77.374)
		(width 0.182)
		(layer "In2.Cu")
		(net 403)
	)
	(segment
		(start 161.75 86.15)
		(end 162.036329 86.436329)
		(width 0.182)
		(layer "In2.Cu")
		(net 403)
	)
	(segment
		(start 161.516965 76.646)
		(end 161.382 76.646)
		(width 0.182)
		(layer "In2.Cu")
		(net 403)
	)
	(arc
		(start 161.357 73.457)
		(mid 161.245984 73.502984)
		(end 161.2 73.614)
		(width 0.182)
		(layer "In2.Cu")
		(net 403)
	)
	(arc
		(start 161.382 76.646)
		(mid 161.253307 76.699307)
		(end 161.2 76.828)
		(width 0.182)
		(layer "In2.Cu")
		(net 403)
	)
	(arc
		(start 161.593 77.725)
		(mid 161.704016 77.770984)
		(end 161.75 77.882)
		(width 0.182)
		(layer "In2.Cu")
		(net 403)
	)
	(arc
		(start 161.2 77.568)
		(mid 161.245984 77.679016)
		(end 161.357 77.725)
		(width 0.182)
		(layer "In2.Cu")
		(net 403)
	)
	(arc
		(start 161.75 73.3)
		(mid 161.704016 73.411016)
		(end 161.593 73.457)
		(width 0.182)
		(layer "In2.Cu")
		(net 403)
	)
	(arc
		(start 161.698965 77.192)
		(mid 161.645658 77.320693)
		(end 161.516965 77.374)
		(width 0.182)
		(layer "In2.Cu")
		(net 403)
	)
	(arc
		(start 161.2 76.828)
		(mid 161.253307 76.956693)
		(end 161.382 77.01)
		(width 0.182)
		(layer "In2.Cu")
		(net 403)
	)
	(arc
		(start 161.698965 76.464)
		(mid 161.645658 76.592693)
		(end 161.516965 76.646)
		(width 0.182)
		(layer "In2.Cu")
		(net 403)
	)
	(arc
		(start 161.382 77.374)
		(mid 161.253307 77.427307)
		(end 161.2 77.556)
		(width 0.182)
		(layer "In2.Cu")
		(net 403)
	)
	(arc
		(start 161.516965 76.282)
		(mid 161.645658 76.335307)
		(end 161.698965 76.464)
		(width 0.182)
		(layer "In2.Cu")
		(net 403)
	)
	(arc
		(start 161.516965 77.01)
		(mid 161.645658 77.063307)
		(end 161.698965 77.192)
		(width 0.182)
		(layer "In2.Cu")
		(net 403)
	)
	(arc
		(start 161.2 76.1)
		(mid 161.253307 76.228693)
		(end 161.382 76.282)
		(width 0.182)
		(layer "In2.Cu")
		(net 403)
	)
	(segment
		(start 163.536329 87.497156)
		(end 163.036329 86.997157)
		(width 0.15)
		(layer "F.Cu")
		(net 404)
	)
	(segment
		(start 162.786328 70.772157)
		(end 162.786328 72.625)
		(width 0.1)
		(layer "F.Cu")
		(net 404)
	)
	(via blind
		(at 163.036329 86.997157)
		(size 0.5)
		(drill 0.2)
		(layers "F.Cu" "In2.Cu")
		(net 404)
	)
	(via blind
		(at 162.786328 72.625)
		(size 0.5)
		(drill 0.2)
		(layers "F.Cu" "In2.Cu")
		(net 404)
	)
	(segment
		(start 162.786328 85.786328)
		(end 163.036329 86.036329)
		(width 0.182)
		(layer "In2.Cu")
		(net 404)
	)
	(segment
		(start 162.604328 74.318328)
		(end 162.25418 74.318328)
		(width 0.182)
		(layer "In2.Cu")
		(net 404)
	)
	(segment
		(start 162.786328 75.642328)
		(end 162.786328 85.786328)
		(width 0.182)
		(layer "In2.Cu")
		(net 404)
	)
	(segment
		(start 163.036329 86.036329)
		(end 163.036329 86.997157)
		(width 0.182)
		(layer "In2.Cu")
		(net 404)
	)
	(segment
		(start 162.25418 74.682328)
		(end 162.604328 74.682328)
		(width 0.182)
		(layer "In2.Cu")
		(net 404)
	)
	(segment
		(start 162.786328 75.592328)
		(end 162.786328 75.642328)
		(width 0.182)
		(layer "In2.Cu")
		(net 404)
	)
	(segment
		(start 162.786328 72.625)
		(end 162.786328 74.136328)
		(width 0.182)
		(layer "In2.Cu")
		(net 404)
	)
	(segment
		(start 162.25418 75.410328)
		(end 162.604328 75.410328)
		(width 0.182)
		(layer "In2.Cu")
		(net 404)
	)
	(segment
		(start 162.604328 75.046328)
		(end 162.25418 75.046328)
		(width 0.182)
		(layer "In2.Cu")
		(net 404)
	)
	(arc
		(start 162.604328 75.410328)
		(mid 162.733021 75.463635)
		(end 162.786328 75.592328)
		(width 0.182)
		(layer "In2.Cu")
		(net 404)
	)
	(arc
		(start 162.786328 74.136328)
		(mid 162.733021 74.265021)
		(end 162.604328 74.318328)
		(width 0.182)
		(layer "In2.Cu")
		(net 404)
	)
	(arc
		(start 162.604328 74.682328)
		(mid 162.733021 74.735635)
		(end 162.786328 74.864328)
		(width 0.182)
		(layer "In2.Cu")
		(net 404)
	)
	(arc
		(start 162.25418 75.046328)
		(mid 162.125487 75.099635)
		(end 162.07218 75.228328)
		(width 0.182)
		(layer "In2.Cu")
		(net 404)
	)
	(arc
		(start 162.786328 74.864328)
		(mid 162.733021 74.993021)
		(end 162.604328 75.046328)
		(width 0.182)
		(layer "In2.Cu")
		(net 404)
	)
	(arc
		(start 162.07218 75.228328)
		(mid 162.125487 75.357021)
		(end 162.25418 75.410328)
		(width 0.182)
		(layer "In2.Cu")
		(net 404)
	)
	(arc
		(start 162.25418 74.318328)
		(mid 162.125487 74.371635)
		(end 162.07218 74.500328)
		(width 0.182)
		(layer "In2.Cu")
		(net 404)
	)
	(arc
		(start 162.07218 74.500328)
		(mid 162.125487 74.629021)
		(end 162.25418 74.682328)
		(width 0.182)
		(layer "In2.Cu")
		(net 404)
	)
	(segment
		(start 163.536329 89.497157)
		(end 163.036329 88.997157)
		(width 0.15)
		(layer "F.Cu")
		(net 405)
	)
	(segment
		(start 163.286328 70.772157)
		(end 163.286328 72.122157)
		(width 0.1)
		(layer "F.Cu")
		(net 405)
	)
	(via blind
		(at 163.036329 88.997157)
		(size 0.5)
		(drill 0.2)
		(layers "F.Cu" "In2.Cu")
		(net 405)
	)
	(via blind
		(at 163.286328 72.122157)
		(size 0.5)
		(drill 0.2)
		(layers "F.Cu" "In2.Cu")
		(net 405)
	)
	(segment
		(start 163.566829 88.466657)
		(end 163.566829 85.766829)
		(width 0.182)
		(layer "In2.Cu")
		(net 405)
	)
	(segment
		(start 163.036329 88.997157)
		(end 163.566829 88.466657)
		(width 0.182)
		(layer "In2.Cu")
		(net 405)
	)
	(segment
		(start 163.566829 85.766829)
		(end 163.286328 85.486328)
		(width 0.182)
		(layer "In2.Cu")
		(net 405)
	)
	(segment
		(start 163.286328 85.486328)
		(end 163.286328 72.122157)
		(width 0.182)
		(layer "In2.Cu")
		(net 405)
	)
	(segment
		(start 167.536329 89.497157)
		(end 167.036329 88.997157)
		(width 0.15)
		(layer "F.Cu")
		(net 406)
	)
	(segment
		(start 166.786328 70.772157)
		(end 166.786328 72.625)
		(width 0.1)
		(layer "F.Cu")
		(net 406)
	)
	(via blind
		(at 167.036329 88.997157)
		(size 0.5)
		(drill 0.2)
		(layers "F.Cu" "In2.Cu")
		(net 406)
	)
	(via blind
		(at 166.786328 72.625)
		(size 0.5)
		(drill 0.2)
		(layers "F.Cu" "In2.Cu")
		(net 406)
	)
	(segment
		(start 166.505829 88.466657)
		(end 166.505829 72.905499)
		(width 0.182)
		(layer "In2.Cu")
		(net 406)
	)
	(segment
		(start 167.036329 88.997157)
		(end 166.505829 88.466657)
		(width 0.182)
		(layer "In2.Cu")
		(net 406)
	)
	(segment
		(start 166.505829 72.905499)
		(end 166.786328 72.625)
		(width 0.182)
		(layer "In2.Cu")
		(net 406)
	)
	(segment
		(start 175.536329 93.497157)
		(end 176.036329 92.997157)
		(width 0.15)
		(layer "F.Cu")
		(net 436)
	)
	(segment
		(start 204.736328 70.797157)
		(end 205.336328 70.197157)
		(width 0.1)
		(layer "F.Cu")
		(net 436)
	)
	(segment
		(start 204.736328 71.212157)
		(end 204.736328 70.797157)
		(width 0.1)
		(layer "F.Cu")
		(net 436)
	)
	(segment
		(start 205.336328 70.197157)
		(end 205.336328 69.697157)
		(width 0.1)
		(layer "F.Cu")
		(net 436)
	)
	(segment
		(start 203.886328 72.020008)
		(end 204.694179 71.212157)
		(width 0.1)
		(layer "F.Cu")
		(net 436)
	)
	(segment
		(start 202.636328 76.163672)
		(end 202.636328 74.870008)
		(width 0.1)
		(layer "F.Cu")
		(net 436)
	)
	(segment
		(start 204.694179 71.212157)
		(end 204.736328 71.212157)
		(width 0.1)
		(layer "F.Cu")
		(net 436)
	)
	(segment
		(start 201.086328 77.713672)
		(end 202.636328 76.163672)
		(width 0.1)
		(layer "F.Cu")
		(net 436)
	)
	(segment
		(start 202.636328 74.870008)
		(end 203.886328 73.620008)
		(width 0.1)
		(layer "F.Cu")
		(net 436)
	)
	(segment
		(start 201.086328 78.820008)
		(end 201.086328 77.713672)
		(width 0.1)
		(layer "F.Cu")
		(net 436)
	)
	(segment
		(start 203.886328 73.620008)
		(end 203.886328 72.020008)
		(width 0.1)
		(layer "F.Cu")
		(net 436)
	)
	(via blind
		(at 176.036329 92.997157)
		(size 0.5)
		(drill 0.2)
		(layers "F.Cu" "In2.Cu")
		(net 436)
	)
	(via
		(at 201.086328 78.820008)
		(size 0.5)
		(drill 0.2)
		(layers "F.Cu" "B.Cu")
		(net 436)
	)
	(segment
		(start 198.36186 82.444476)
		(end 201.086328 79.720008)
		(width 0.1)
		(layer "In2.Cu")
		(net 436)
	)
	(segment
		(start 183.852738 93.707178)
		(end 195.115441 82.444476)
		(width 0.1)
		(layer "In2.Cu")
		(net 436)
	)
	(segment
		(start 176.036329 92.997157)
		(end 176.74635 93.707178)
		(width 0.1)
		(layer "In2.Cu")
		(net 436)
	)
	(segment
		(start 195.115441 82.444476)
		(end 198.36186 82.444476)
		(width 0.1)
		(layer "In2.Cu")
		(net 436)
	)
	(segment
		(start 201.086328 79.720008)
		(end 201.086328 78.820008)
		(width 0.1)
		(layer "In2.Cu")
		(net 436)
	)
	(segment
		(start 176.74635 93.707178)
		(end 183.852738 93.707178)
		(width 0.1)
		(layer "In2.Cu")
		(net 436)
	)
	(segment
		(start 148.521328 107.747157)
		(end 149.161328 107.747157)
		(width 0.1)
		(layer "F.Cu")
		(net 442)
	)
	(segment
		(start 161.536327 106.497157)
		(end 162.036326 105.997157)
		(width 0.15)
		(layer "F.Cu")
		(net 442)
	)
	(via blind
		(at 149.161328 107.747157)
		(size 0.5)
		(drill 0.2)
		(layers "F.Cu" "In2.Cu")
		(net 442)
	)
	(via
		(at 162.036326 105.997157)
		(size 0.5)
		(drill 0.2)
		(layers "F.Cu" "B.Cu")
		(net 442)
	)
	(segment
		(start 149.161328 107.747157)
		(end 149.536328 107.747157)
		(width 0.15)
		(layer "In2.Cu")
		(net 442)
	)
	(segment
		(start 150.861319 106.422166)
		(end 161.035595 106.422166)
		(width 0.15)
		(layer "In2.Cu")
		(net 442)
	)
	(segment
		(start 161.035595 106.422166)
		(end 161.460604 105.997157)
		(width 0.15)
		(layer "In2.Cu")
		(net 442)
	)
	(segment
		(start 161.460604 105.997157)
		(end 162.036326 105.997157)
		(width 0.15)
		(layer "In2.Cu")
		(net 442)
	)
	(segment
		(start 149.536328 107.747157)
		(end 150.861319 106.422166)
		(width 0.15)
		(layer "In2.Cu")
		(net 442)
	)
	(segment
		(start 161.536328 104.497156)
		(end 162.036328 104.997155)
		(width 0.15)
		(layer "F.Cu")
		(net 444)
	)
	(segment
		(start 148.521328 106.622157)
		(end 149.161328 106.622157)
		(width 0.1)
		(layer "F.Cu")
		(net 444)
	)
	(via
		(at 162.036328 104.997155)
		(size 0.5)
		(drill 0.2)
		(layers "F.Cu" "B.Cu")
		(net 444)
	)
	(via blind
		(at 149.161328 106.622157)
		(size 0.5)
		(drill 0.2)
		(layers "F.Cu" "In2.Cu")
		(net 444)
	)
	(segment
		(start 150.661328 106.122157)
		(end 160.911326 106.122157)
		(width 0.15)
		(layer "In2.Cu")
		(net 444)
	)
	(segment
		(start 149.161328 106.622157)
		(end 150.161328 106.622157)
		(width 0.15)
		(layer "In2.Cu")
		(net 444)
	)
	(segment
		(start 150.161328 106.622157)
		(end 150.661328 106.122157)
		(width 0.15)
		(layer "In2.Cu")
		(net 444)
	)
	(segment
		(start 160.911326 106.122157)
		(end 162.036328 104.997155)
		(width 0.15)
		(layer "In2.Cu")
		(net 444)
	)
	(segment
		(start 160.536328 105.497158)
		(end 160.036328 104.997159)
		(width 0.15)
		(layer "F.Cu")
		(net 447)
	)
	(segment
		(start 148.521328 104.372157)
		(end 148.521328 104.692157)
		(width 0.1)
		(layer "F.Cu")
		(net 447)
	)
	(segment
		(start 148.521328 104.692157)
		(end 148.601349 104.772178)
		(width 0.1)
		(layer "F.Cu")
		(net 447)
	)
	(segment
		(start 148.601349 104.772178)
		(end 149.161302 104.772178)
		(width 0.1)
		(layer "F.Cu")
		(net 447)
	)
	(via
		(at 160.036328 104.997159)
		(size 0.5)
		(drill 0.2)
		(layers "F.Cu" "B.Cu")
		(net 447)
	)
	(via blind
		(at 149.161302 104.772178)
		(size 0.5)
		(drill 0.2)
		(layers "F.Cu" "In2.Cu")
		(net 447)
	)
	(segment
		(start 149.186323 104.747157)
		(end 149.161302 104.772178)
		(width 0.15)
		(layer "In2.Cu")
		(net 447)
	)
	(segment
		(start 159.561329 105.472158)
		(end 150.886329 105.472158)
		(width 0.15)
		(layer "In2.Cu")
		(net 447)
	)
	(segment
		(start 150.161328 104.747157)
		(end 149.186323 104.747157)
		(width 0.15)
		(layer "In2.Cu")
		(net 447)
	)
	(segment
		(start 160.036328 104.997159)
		(end 159.561329 105.472158)
		(width 0.15)
		(layer "In2.Cu")
		(net 447)
	)
	(segment
		(start 150.886329 105.472158)
		(end 150.161328 104.747157)
		(width 0.15)
		(layer "In2.Cu")
		(net 447)
	)
	(segment
		(start 148.521328 102.122157)
		(end 148.521328 101.512157)
		(width 0.1)
		(layer "F.Cu")
		(net 449)
	)
	(segment
		(start 158.536328 101.497157)
		(end 157.557443 101.497157)
		(width 0.15)
		(layer "F.Cu")
		(net 449)
	)
	(segment
		(start 157.557443 101.497157)
		(end 156.9847 102.0699)
		(width 0.15)
		(layer "F.Cu")
		(net 449)
	)
	(segment
		(start 148.521328 101.512157)
		(end 148.536328 101.497157)
		(width 0.1)
		(layer "F.Cu")
		(net 449)
	)
	(via
		(at 156.9847 102.0699)
		(size 0.5)
		(drill 0.2)
		(layers "F.Cu" "B.Cu")
		(net 449)
	)
	(via blind
		(at 148.536328 101.497157)
		(size 0.5)
		(drill 0.2)
		(layers "F.Cu" "In2.Cu")
		(net 449)
	)
	(segment
		(start 149.109071 102.0699)
		(end 156.9847 102.0699)
		(width 0.15)
		(layer "In2.Cu")
		(net 449)
	)
	(segment
		(start 148.536328 101.497157)
		(end 149.109071 102.0699)
		(width 0.15)
		(layer "In2.Cu")
		(net 449)
	)
	(segment
		(start 142.536328 99.762157)
		(end 142.536328 99.122157)
		(width 0.1)
		(layer "F.Cu")
		(net 451)
	)
	(segment
		(start 159.536328 102.497158)
		(end 159.036328 101.997159)
		(width 0.15)
		(layer "F.Cu")
		(net 451)
	)
	(via blind
		(at 142.536328 99.122157)
		(size 0.5)
		(drill 0.2)
		(layers "F.Cu" "In2.Cu")
		(net 451)
	)
	(via
		(at 159.036328 101.997159)
		(size 0.5)
		(drill 0.2)
		(layers "F.Cu" "B.Cu")
		(net 451)
	)
	(segment
		(start 145.786328 102.372157)
		(end 142.536328 99.122157)
		(width 0.15)
		(layer "In2.Cu")
		(net 451)
	)
	(segment
		(start 156.329955 102.372157)
		(end 156.573798 102.616)
		(width 0.15)
		(layer "In2.Cu")
		(net 451)
	)
	(segment
		(start 158.036326 101.997159)
		(end 159.036328 101.997159)
		(width 0.15)
		(layer "In2.Cu")
		(net 451)
	)
	(segment
		(start 156.573798 102.616)
		(end 157.417485 102.616)
		(width 0.15)
		(layer "In2.Cu")
		(net 451)
	)
	(segment
		(start 157.417485 102.616)
		(end 158.036326 101.997159)
		(width 0.15)
		(layer "In2.Cu")
		(net 451)
	)
	(segment
		(start 156.329955 102.372157)
		(end 145.786328 102.372157)
		(width 0.15)
		(layer "In2.Cu")
		(net 451)
	)
	(segment
		(start 158.536329 102.497157)
		(end 158.03633 102.997157)
		(width 0.15)
		(layer "F.Cu")
		(net 453)
	)
	(segment
		(start 141.411328 99.762157)
		(end 141.411328 99.122157)
		(width 0.1)
		(layer "F.Cu")
		(net 453)
	)
	(via
		(at 158.03633 102.997157)
		(size 0.5)
		(drill 0.2)
		(layers "F.Cu" "B.Cu")
		(net 453)
	)
	(via blind
		(at 141.411328 99.122157)
		(size 0.5)
		(drill 0.2)
		(layers "F.Cu" "In2.Cu")
		(net 453)
	)
	(segment
		(start 155.986768 102.672168)
		(end 145.672168 102.672168)
		(width 0.15)
		(layer "In2.Cu")
		(net 453)
	)
	(segment
		(start 156.337 103.0224)
		(end 155.986768 102.672168)
		(width 0.15)
		(layer "In2.Cu")
		(net 453)
	)
	(segment
		(start 142.7 99.7)
		(end 141.989171 99.7)
		(width 0.15)
		(layer "In2.Cu")
		(net 453)
	)
	(segment
		(start 141.989171 99.7)
		(end 141.411328 99.122157)
		(width 0.15)
		(layer "In2.Cu")
		(net 453)
	)
	(segment
		(start 158.03633 102.997157)
		(end 158.011087 103.0224)
		(width 0.15)
		(layer "In2.Cu")
		(net 453)
	)
	(segment
		(start 145.672168 102.672168)
		(end 142.7 99.7)
		(width 0.15)
		(layer "In2.Cu")
		(net 453)
	)
	(segment
		(start 158.011087 103.0224)
		(end 156.337 103.0224)
		(width 0.15)
		(layer "In2.Cu")
		(net 453)
	)
	(segment
		(start 133.426328 102.622157)
		(end 132.786328 102.622157)
		(width 0.1)
		(layer "F.Cu")
		(net 455)
	)
	(segment
		(start 158.536328 104.497158)
		(end 158.036328 103.997159)
		(width 0.15)
		(layer "F.Cu")
		(net 455)
	)
	(via blind
		(at 132.786328 102.622157)
		(size 0.5)
		(drill 0.2)
		(layers "F.Cu" "In2.Cu")
		(net 455)
	)
	(via
		(at 158.036328 103.997159)
		(size 0.5)
		(drill 0.2)
		(layers "F.Cu" "B.Cu")
		(net 455)
	)
	(segment
		(start 133.897156 102.997156)
		(end 133.161327 102.997156)
		(width 0.15)
		(layer "In2.Cu")
		(net 455)
	)
	(segment
		(start 158.036326 103.997157)
		(end 134.897157 103.997157)
		(width 0.15)
		(layer "In2.Cu")
		(net 455)
	)
	(segment
		(start 158.036328 103.997159)
		(end 158.036326 103.997157)
		(width 0.15)
		(layer "In2.Cu")
		(net 455)
	)
	(segment
		(start 133.161327 102.997156)
		(end 132.786328 102.622157)
		(width 0.15)
		(layer "In2.Cu")
		(net 455)
	)
	(segment
		(start 134.897157 103.997157)
		(end 133.897156 102.997156)
		(width 0.15)
		(layer "In2.Cu")
		(net 455)
	)
	(segment
		(start 133.426328 105.872157)
		(end 132.786328 105.872157)
		(width 0.1)
		(layer "F.Cu")
		(net 457)
	)
	(segment
		(start 159.536329 104.497157)
		(end 159.03633 104.997157)
		(width 0.15)
		(layer "F.Cu")
		(net 457)
	)
	(via blind
		(at 132.786328 105.872157)
		(size 0.5)
		(drill 0.2)
		(layers "F.Cu" "In2.Cu")
		(net 457)
	)
	(via
		(at 159.03633 104.997157)
		(size 0.5)
		(drill 0.2)
		(layers "F.Cu" "B.Cu")
		(net 457)
	)
	(segment
		(start 133.102832 104.297168)
		(end 132.786328 104.613672)
		(width 0.15)
		(layer "In2.Cu")
		(net 457)
	)
	(segment
		(start 159.03633 104.997157)
		(end 158.786331 104.747158)
		(width 0.15)
		(layer "In2.Cu")
		(net 457)
	)
	(segment
		(start 158.786331 104.747158)
		(end 158.036329 104.747158)
		(width 0.15)
		(layer "In2.Cu")
		(net 457)
	)
	(segment
		(start 157.586339 104.297168)
		(end 133.102832 104.297168)
		(width 0.15)
		(layer "In2.Cu")
		(net 457)
	)
	(segment
		(start 132.786328 104.613672)
		(end 132.786328 105.872157)
		(width 0.15)
		(layer "In2.Cu")
		(net 457)
	)
	(segment
		(start 158.036329 104.747158)
		(end 157.586339 104.297168)
		(width 0.15)
		(layer "In2.Cu")
		(net 457)
	)
	(segment
		(start 155.36 120.505)
		(end 155.36 121.709)
		(width 0.2)
		(layer "F.Cu")
		(net 459)
	)
	(segment
		(start 164.536329 106.497158)
		(end 164.036328 105.997158)
		(width 0.15)
		(layer "F.Cu")
		(net 459)
	)
	(segment
		(start 166.536328 102.497156)
		(end 167.036328 102.997156)
		(width 0.15)
		(layer "F.Cu")
		(net 459)
	)
	(segment
		(start 162.536328 100.497158)
		(end 162.036328 99.997158)
		(width 0.15)
		(layer "F.Cu")
		(net 459)
	)
	(segment
		(start 163.536327 103.497157)
		(end 164.036327 102.997157)
		(width 0.15)
		(layer "F.Cu")
		(net 459)
	)
	(segment
		(start 160.502844 104.536329)
		(end 160.002843 104.036328)
		(width 0.15)
		(layer "F.Cu")
		(net 459)
	)
	(segment
		(start 173.536329 103.497157)
		(end 174.036329 103.997157)
		(width 0.15)
		(layer "F.Cu")
		(net 459)
	)
	(segment
		(start 169.536329 101.497157)
		(end 170.036329 101.997157)
		(width 0.15)
		(layer "F.Cu")
		(net 459)
	)
	(segment
		(start 170.536329 104.497158)
		(end 170.036328 104.997158)
		(width 0.15)
		(layer "F.Cu")
		(net 459)
	)
	(segment
		(start 171.536329 91.497157)
		(end 172.036329 90.997156)
		(width 0.15)
		(layer "F.Cu")
		(net 459)
	)
	(segment
		(start 167.536329 91.497157)
		(end 167.036329 90.997156)
		(width 0.15)
		(layer "F.Cu")
		(net 459)
	)
	(segment
		(start 176.536329 92.497157)
		(end 177.03633 91.997157)
		(width 0.15)
		(layer "F.Cu")
		(net 459)
	)
	(segment
		(start 173.536329 93.497156)
		(end 174.036329 92.997156)
		(width 0.15)
		(layer "F.Cu")
		(net 459)
	)
	(segment
		(start 174.536329 96.497157)
		(end 175.036329 96.997157)
		(width 0.15)
		(layer "F.Cu")
		(net 459)
	)
	(segment
		(start 175.536327 99.497158)
		(end 175.036327 98.997158)
		(width 0.15)
		(layer "F.Cu")
		(net 459)
	)
	(segment
		(start 172.53633 100.497157)
		(end 173.036329 100.997156)
		(width 0.15)
		(layer "F.Cu")
		(net 459)
	)
	(segment
		(start 176.536329 102.497156)
		(end 177.036329 102.997157)
		(width 0.15)
		(layer "F.Cu")
		(net 459)
	)
	(segment
		(start 149.680801 96.296001)
		(end 150.1808 95.796001)
		(width 0.15)
		(layer "F.Cu")
		(net 459)
	)
	(segment
		(start 198.686328 99.620008)
		(end 198.686328 98.720008)
		(width 0.15)
		(layer "F.Cu")
		(net 459)
	)
	(segment
		(start 192.736328 72.182157)
		(end 192.736328 72.947157)
		(width 0.1)
		(layer "F.Cu")
		(net 459)
	)
	(segment
		(start 196.736328 72.182157)
		(end 196.736328 72.947157)
		(width 0.1)
		(layer "F.Cu")
		(net 459)
	)
	(segment
		(start 200.736328 72.182157)
		(end 200.736328 72.947157)
		(width 0.1)
		(layer "F.Cu")
		(net 459)
	)
	(segment
		(start 204.736328 72.182157)
		(end 204.736328 72.947157)
		(width 0.1)
		(layer "F.Cu")
		(net 459)
	)
	(segment
		(start 205.636328 64.020008)
		(end 206.386328 64.020008)
		(width 0.2)
		(layer "F.Cu")
		(net 459)
	)
	(segment
		(start 175.026 134.241332)
		(end 174.946666 134.320666)
		(width 0.2)
		(layer "F.Cu")
		(net 459)
	)
	(segment
		(start 214.171328 93.220008)
		(end 214.886328 93.220008)
		(width 0.2)
		(layer "F.Cu")
		(net 459)
	)
	(segment
		(start 204.186328 79.805008)
		(end 204.186328 80.520008)
		(width 0.1)
		(layer "F.Cu")
		(net 459)
	)
	(segment
		(start 206.036328 86.620008)
		(end 206.036328 87.470008)
		(width 0.2)
		(layer "F.Cu")
		(net 459)
	)
	(segment
		(start 177.536329 105.497156)
		(end 178.036329 105.997157)
		(width 0.15)
		(layer "F.Cu")
		(net 459)
	)
	(segment
		(start 151.720442 99.282127)
		(end 151.220443 99.782127)
		(width 0.15)
		(layer "F.Cu")
		(net 459)
	)
	(segment
		(start 180.995 112.914)
		(end 180.995 113.572)
		(width 0.2)
		(layer "F.Cu")
		(net 459)
	)
	(segment
		(start 177.536327 95.497156)
		(end 178.036327 94.997156)
		(width 0.15)
		(layer "F.Cu")
		(net 459)
	)
	(segment
		(start 145.046328 115.082157)
		(end 145.046328 115.717157)
		(width 0.15)
		(layer "F.Cu")
		(net 459)
	)
	(segment
		(start 180.307781 101.497156)
		(end 180.661334 101.497156)
		(width 0.15)
		(layer "F.Cu")
		(net 459)
	)
	(segment
		(start 135.585 105.485)
		(end 135.585 104.8)
		(width 0.2)
		(layer "F.Cu")
		(net 459)
	)
	(segment
		(start 179.536329 101.497157)
		(end 180.307781 101.497156)
		(width 0.15)
		(layer "F.Cu")
		(net 459)
	)
	(segment
		(start 209.236328 64.020008)
		(end 209.236328 64.670008)
		(width 0.2)
		(layer "F.Cu")
		(net 459)
	)
	(segment
		(start 201.336328 64.020008)
		(end 202.086328 64.020008)
		(width 0.2)
		(layer "F.Cu")
		(net 459)
	)
	(segment
		(start 179.7035 115.0035)
		(end 179.7 115)
		(width 0.2)
		(layer "F.Cu")
		(net 459)
	)
	(segment
		(start 173.756 129.597)
		(end 172.74 129.597)
		(width 0.2)
		(layer "F.Cu")
		(net 459)
	)
	(segment
		(start 140.5 103.9125)
		(end 140.5 102.685)
		(width 0.2)
		(layer "F.Cu")
		(net 459)
	)
	(segment
		(start 136 104.8)
		(end 136.3 105.1)
		(width 0.2)
		(layer "F.Cu")
		(net 459)
	)
	(segment
		(start 150.0632 91.7194)
		(end 148.0058 91.7194)
		(width 0.15)
		(layer "F.Cu")
		(net 459)
	)
	(segment
		(start 147.411328 108.747157)
		(end 146.9 109.258485)
		(width 0.15)
		(layer "F.Cu")
		(net 459)
	)
	(segment
		(start 174.536327 106.497158)
		(end 174.036327 105.997157)
		(width 0.15)
		(layer "F.Cu")
		(net 459)
	)
	(segment
		(start 209.236328 64.670008)
		(end 209.186328 64.720008)
		(width 0.2)
		(layer "F.Cu")
		(net 459)
	)
	(segment
		(start 178.756328 112.220008)
		(end 178.756328 110.670008)
		(width 0.2)
		(layer "F.Cu")
		(net 459)
	)
	(segment
		(start 173.375 112.152)
		(end 173.375 112.81)
		(width 0.2)
		(layer "F.Cu")
		(net 459)
	)
	(segment
		(start 206.036328 87.470008)
		(end 206.086328 87.520008)
		(width 0.2)
		(layer "F.Cu")
		(net 459)
	)
	(segment
		(start 147.446328 108.782157)
		(end 147.411328 108.747157)
		(width 0.1)
		(layer "F.Cu")
		(net 459)
	)
	(segment
		(start 148.176328 108.782157)
		(end 147.446328 108.782157)
		(width 0.1)
		(layer "F.Cu")
		(net 459)
	)
	(segment
		(start 150.3172 91.9734)
		(end 150.0632 91.7194)
		(width 0.15)
		(layer "F.Cu")
		(net 459)
	)
	(segment
		(start 153.481047 96.277157)
		(end 153.924 95.834204)
		(width 0.15)
		(layer "F.Cu")
		(net 459)
	)
	(segment
		(start 177.693 123.628)
		(end 177.628 123.628)
		(width 0.15)
		(layer "F.Cu")
		(net 459)
	)
	(segment
		(start 197.136328 64.020008)
		(end 197.886328 64.020008)
		(width 0.2)
		(layer "F.Cu")
		(net 459)
	)
	(segment
		(start 167.536329 105.497158)
		(end 167.036328 104.997158)
		(width 0.15)
		(layer "F.Cu")
		(net 459)
	)
	(segment
		(start 180.661333 101.497157)
		(end 180.661334 101.497156)
		(width 0.15)
		(layer "F.Cu")
		(net 459)
	)
	(segment
		(start 207.425626 104.259306)
		(end 207.486328 104.320008)
		(width 0.2)
		(layer "F.Cu")
		(net 459)
	)
	(segment
		(start 157.777728 99.156157)
		(end 158.487528 98.497157)
		(width 0.15)
		(layer "F.Cu")
		(net 459)
	)
	(segment
		(start 139.875 102.685)
		(end 139.855 102.705)
		(width 0.15)
		(layer "F.Cu")
		(net 459)
	)
	(segment
		(start 178.347 115.731)
		(end 178.8788 115.731)
		(width 0.1)
		(layer "F.Cu")
		(net 459)
	)
	(segment
		(start 196.901328 85.205008)
		(end 196.886328 85.220008)
		(width 0.2)
		(layer "F.Cu")
		(net 459)
	)
	(segment
		(start 159.536328 101.497156)
		(end 160.036328 101.997155)
		(width 0.15)
		(layer "F.Cu")
		(net 459)
	)
	(segment
		(start 150.3172 93.599)
		(end 150.3172 91.9734)
		(width 0.15)
		(layer "F.Cu")
		(net 459)
	)
	(segment
		(start 189.371328 92.720008)
		(end 189.986328 92.720008)
		(width 0.1)
		(layer "F.Cu")
		(net 459)
	)
	(segment
		(start 135.9492 101.0742)
		(end 136 101.125)
		(width 0.2)
		(layer "F.Cu")
		(net 459)
	)
	(segment
		(start 178.3485 115.72)
		(end 179.6925 115.72)
		(width 0.2)
		(layer "F.Cu")
		(net 459)
	)
	(segment
		(start 139.561328 118.222157)
		(end 139.661328 118.122157)
		(width 0.2)
		(layer "F.Cu")
		(net 459)
	)
	(segment
		(start 197.009179 101.797157)
		(end 195.909179 101.797157)
		(width 0.2)
		(layer "F.Cu")
		(net 459)
	)
	(segment
		(start 205.448477 104.297157)
		(end 205.486328 104.259306)
		(width 0.2)
		(layer "F.Cu")
		(net 459)
	)
	(segment
		(start 197.486328 87.205008)
		(end 196.801328 87.205008)
		(width 0.2)
		(layer "F.Cu")
		(net 459)
	)
	(segment
		(start 171.597 129.597)
		(end 172.74 129.597)
		(width 0.2)
		(layer "F.Cu")
		(net 459)
	)
	(segment
		(start 178.756328 112.970008)
		(end 180.938992 112.970008)
		(width 0.2)
		(layer "F.Cu")
		(net 459)
	)
	(segment
		(start 203.863477 104.297157)
		(end 205.448477 104.297157)
		(width 0.2)
		(layer "F.Cu")
		(net 459)
	)
	(segment
		(start 206.586328 104.259306)
		(end 207.425626 104.259306)
		(width 0.2)
		(layer "F.Cu")
		(net 459)
	)
	(segment
		(start 171.597 129.597)
		(end 171.597 128.812)
		(width 0.2)
		(layer "F.Cu")
		(net 459)
	)
	(segment
		(start 137.0325 84.7)
		(end 137.0325 83.9)
		(width 0.2)
		(layer "F.Cu")
		(net 459)
	)
	(segment
		(start 177.628 123.628)
		(end 177.2 123.2)
		(width 0.15)
		(layer "F.Cu")
		(net 459)
	)
	(segment
		(start 179.6925 115.72)
		(end 179.7035 115.731)
		(width 0.2)
		(layer "F.Cu")
		(net 459)
	)
	(segment
		(start 140.5 102.685)
		(end 139.875 102.685)
		(width 0.15)
		(layer "F.Cu")
		(net 459)
	)
	(segment
		(start 135.585 108.785)
		(end 135.6 108.8)
		(width 0.2)
		(layer "F.Cu")
		(net 459)
	)
	(segment
		(start 158.36 121.734)
		(end 158.359 121.735)
		(width 0.2)
		(layer "F.Cu")
		(net 459)
	)
	(segment
		(start 143.786328 116.517157)
		(end 143.370328 116.517157)
		(width 0.2)
		(layer "F.Cu")
		(net 459)
	)
	(segment
		(start 195.909179 101.797157)
		(end 195.686328 102.020008)
		(width 0.2)
		(layer "F.Cu")
		(net 459)
	)
	(segment
		(start 146.9 109.258485)
		(end 146.9 109.7)
		(width 0.15)
		(layer "F.Cu")
		(net 459)
	)
	(segment
		(start 158.487528 98.497157)
		(end 158.536328 98.497157)
		(width 0.15)
		(layer "F.Cu")
		(net 459)
	)
	(segment
		(start 146 110.6)
		(end 146.9 109.7)
		(width 0.15)
		(layer "F.Cu")
		(net 459)
	)
	(segment
		(start 135.6 105.4)
		(end 135.585 105.485)
		(width 0.2)
		(layer "F.Cu")
		(net 459)
	)
	(segment
		(start 135.65 108.1)
		(end 136.8125 108.1)
		(width 0.15)
		(layer "F.Cu")
		(net 459)
	)
	(segment
		(start 176.169 129.597)
		(end 179.344 129.597)
		(width 0.2)
		(layer "F.Cu")
		(net 459)
	)
	(segment
		(start 178.536327 98.497158)
		(end 178.036327 97.997158)
		(width 0.15)
		(layer "F.Cu")
		(net 459)
	)
	(segment
		(start 135.585 108.1)
		(end 135.585 108.785)
		(width 0.2)
		(layer "F.Cu")
		(net 459)
	)
	(segment
		(start 136.3 105.1)
		(end 136.8125 105.1)
		(width 0.2)
		(layer "F.Cu")
		(net 459)
	)
	(segment
		(start 137.0325 92.1)
		(end 137.0325 91.3)
		(width 0.2)
		(layer "F.Cu")
		(net 459)
	)
	(segment
		(start 196.801328 87.205008)
		(end 196.786328 87.220008)
		(width 0.2)
		(layer "F.Cu")
		(net 459)
	)
	(segment
		(start 137.0325 87.1)
		(end 137.0325 86.3)
		(width 0.2)
		(layer "F.Cu")
		(net 459)
	)
	(segment
		(start 158.36 120.53)
		(end 158.36 121.734)
		(width 0.2)
		(layer "F.Cu")
		(net 459)
	)
	(segment
		(start 137.0325 89.6)
		(end 137.0325 88.8)
		(width 0.2)
		(layer "F.Cu")
		(net 459)
	)
	(segment
		(start 206.036328 83.970008)
		(end 206.086328 83.920008)
		(width 0.2)
		(layer "F.Cu")
		(net 459)
	)
	(segment
		(start 135.585 104.8)
		(end 136 104.8)
		(width 0.2)
		(layer "F.Cu")
		(net 459)
	)
	(segment
		(start 178.756328 112.970008)
		(end 178.756328 112.220008)
		(width 0.2)
		(layer "F.Cu")
		(net 459)
	)
	(segment
		(start 189.889171 118.283485)
		(end 189.864171 118.258485)
		(width 0.2)
		(layer "F.Cu")
		(net 459)
	)
	(segment
		(start 180.938992 112.970008)
		(end 180.995 112.914)
		(width 0.2)
		(layer "F.Cu")
		(net 459)
	)
	(segment
		(start 138.911328 118.222157)
		(end 139.561328 118.222157)
		(width 0.2)
		(layer "F.Cu")
		(net 459)
	)
	(segment
		(start 189.889171 121.074485)
		(end 189.889171 118.283485)
		(width 0.2)
		(layer "F.Cu")
		(net 459)
	)
	(segment
		(start 179.7035 115.731)
		(end 179.7035 115.0035)
		(width 0.2)
		(layer "F.Cu")
		(net 459)
	)
	(segment
		(start 135 101.0742)
		(end 135.9492 101.0742)
		(width 0.2)
		(layer "F.Cu")
		(net 459)
	)
	(segment
		(start 197.486328 85.205008)
		(end 196.901328 85.205008)
		(width 0.2)
		(layer "F.Cu")
		(net 459)
	)
	(segment
		(start 144.6875 110.6)
		(end 146 110.6)
		(width 0.15)
		(layer "F.Cu")
		(net 459)
	)
	(segment
		(start 143.370328 116.517157)
		(end 143.360328 116.527157)
		(width 0.2)
		(layer "F.Cu")
		(net 459)
	)
	(segment
		(start 175.026 133.068)
		(end 175.026 134.241332)
		(width 0.2)
		(layer "F.Cu")
		(net 459)
	)
	(segment
		(start 152.696328 96.277157)
		(end 153.481047 96.277157)
		(width 0.15)
		(layer "F.Cu")
		(net 459)
	)
	(segment
		(start 178.201 129.597)
		(end 178.201 128.685)
		(width 0.2)
		(layer "F.Cu")
		(net 459)
	)
	(segment
		(start 178.8788 115.731)
		(end 179.7035 115.731)
		(width 0.1)
		(layer "F.Cu")
		(net 459)
	)
	(segment
		(start 205.286328 79.805008)
		(end 205.286328 80.520008)
		(width 0.1)
		(layer "F.Cu")
		(net 459)
	)
	(segment
		(start 179.536328 101.497157)
		(end 180.661333 101.497157)
		(width 0.15)
		(layer "F.Cu")
		(net 459)
	)
	(segment
		(start 192.936328 64.020008)
		(end 193.686328 64.020008)
		(width 0.2)
		(layer "F.Cu")
		(net 459)
	)
	(segment
		(start 205.486328 104.259306)
		(end 206.586328 104.259306)
		(width 0.2)
		(layer "F.Cu")
		(net 459)
	)
	(segment
		(start 206.036328 84.820008)
		(end 206.036328 83.970008)
		(width 0.2)
		(layer "F.Cu")
		(net 459)
	)
	(via
		(at 155.359 121.71)
		(size 0.5)
		(drill 0.2)
		(layers "F.Cu" "B.Cu")
		(net 459)
	)
	(via
		(at 164.036328 105.997158)
		(size 0.5)
		(drill 0.2)
		(layers "F.Cu" "B.Cu")
		(net 459)
	)
	(via
		(at 167.036328 102.997156)
		(size 0.5)
		(drill 0.2)
		(layers "F.Cu" "B.Cu")
		(net 459)
	)
	(via
		(at 164.036327 102.997157)
		(size 0.5)
		(drill 0.2)
		(layers "F.Cu" "B.Cu")
		(net 459)
	)
	(via
		(at 162.036328 99.997158)
		(size 0.5)
		(drill 0.2)
		(layers "F.Cu" "B.Cu")
		(net 459)
	)
	(via
		(at 160.002843 104.036328)
		(size 0.5)
		(drill 0.2)
		(layers "F.Cu" "B.Cu")
		(net 459)
	)
	(via
		(at 170.036328 104.997158)
		(size 0.5)
		(drill 0.2)
		(layers "F.Cu" "B.Cu")
		(net 459)
	)
	(via
		(at 174.036329 103.997157)
		(size 0.5)
		(drill 0.2)
		(layers "F.Cu" "B.Cu")
		(net 459)
	)
	(via
		(at 170.036329 101.997157)
		(size 0.5)
		(drill 0.2)
		(layers "F.Cu" "B.Cu")
		(net 459)
	)
	(via
		(at 172.036329 90.997156)
		(size 0.5)
		(drill 0.2)
		(layers "F.Cu" "B.Cu")
		(net 459)
	)
	(via
		(at 167.036329 90.997156)
		(size 0.5)
		(drill 0.2)
		(layers "F.Cu" "B.Cu")
		(net 459)
	)
	(via
		(at 177.03633 91.997157)
		(size 0.5)
		(drill 0.2)
		(layers "F.Cu" "B.Cu")
		(net 459)
	)
	(via
		(at 174.036329 92.997156)
		(size 0.5)
		(drill 0.2)
		(layers "F.Cu" "B.Cu")
		(net 459)
	)
	(via
		(at 175.036329 96.997157)
		(size 0.5)
		(drill 0.2)
		(layers "F.Cu" "B.Cu")
		(net 459)
	)
	(via
		(at 175.036327 98.997158)
		(size 0.5)
		(drill 0.2)
		(layers "F.Cu" "B.Cu")
		(net 459)
	)
	(via
		(at 173.036329 100.997156)
		(size 0.5)
		(drill 0.2)
		(layers "F.Cu" "B.Cu")
		(net 459)
	)
	(via
		(at 177.036329 102.997157)
		(size 0.5)
		(drill 0.2)
		(layers "F.Cu" "B.Cu")
		(net 459)
	)
	(via
		(at 150.183928 95.787358)
		(size 0.5)
		(drill 0.2)
		(layers "F.Cu" "B.Cu")
		(net 459)
	)
	(via
		(at 198.686328 98.720008)
		(size 0.5)
		(drill 0.2)
		(layers "F.Cu" "B.Cu")
		(net 459)
	)
	(via
		(at 192.736328 72.947157)
		(size 0.5)
		(drill 0.2)
		(layers "F.Cu" "B.Cu")
		(net 459)
	)
	(via
		(at 196.736328 72.947157)
		(size 0.5)
		(drill 0.2)
		(layers "F.Cu" "B.Cu")
		(net 459)
	)
	(via
		(at 200.736328 72.947157)
		(size 0.5)
		(drill 0.2)
		(layers "F.Cu" "B.Cu")
		(net 459)
	)
	(via
		(at 204.736328 72.947157)
		(size 0.5)
		(drill 0.2)
		(layers "F.Cu" "B.Cu")
		(net 459)
	)
	(via
		(at 206.386328 64.020008)
		(size 0.5)
		(drill 0.2)
		(layers "F.Cu" "B.Cu")
		(net 459)
	)
	(via
		(at 157.777728 99.156157)
		(size 0.5)
		(drill 0.2)
		(layers "F.Cu" "B.Cu")
		(net 459)
	)
	(via
		(at 178.036327 97.997158)
		(size 0.5)
		(drill 0.2)
		(layers "F.Cu" "B.Cu")
		(net 459)
	)
	(via
		(at 202.086328 64.020008)
		(size 0.5)
		(drill 0.2)
		(layers "F.Cu" "B.Cu")
		(net 459)
	)
	(via
		(at 116.475 93.35)
		(size 0.5)
		(drill 0.2)
		(layers "F.Cu" "B.Cu")
		(free yes)
		(net 459)
	)
	(via
		(at 137.0325 83.9)
		(size 0.5)
		(drill 0.2)
		(layers "F.Cu" "B.Cu")
		(net 459)
	)
	(via
		(at 198.786328 93.120008)
		(size 0.5)
		(drill 0.2)
		(layers "F.Cu" "B.Cu")
		(net 459)
	)
	(via
		(at 196.386328 98.920008)
		(size 0.5)
		(drill 0.2)
		(layers "F.Cu" "B.Cu")
		(net 459)
	)
	(via
		(at 189.986328 92.720008)
		(size 0.5)
		(drill 0.2)
		(layers "F.Cu" "B.Cu")
		(net 459)
	)
	(via
		(at 117.675 93.35)
		(size 0.5)
		(drill 0.2)
		(layers "F.Cu" "B.Cu")
		(free yes)
		(net 459)
	)
	(via
		(at 190.586328 129.020008)
		(size 0.5)
		(drill 0.2)
		(layers "F.Cu" "B.Cu")
		(net 459)
	)
	(via
		(at 193.686328 64.020008)
		(size 0.5)
		(drill 0.2)
		(layers "F.Cu" "B.Cu")
		(net 459)
	)
	(via
		(at 196.886328 85.220008)
		(size 0.5)
		(drill 0.2)
		(layers "F.Cu" "B.Cu")
		(net 459)
	)
	(via
		(at 214.886328 93.220008)
		(size 0.5)
		(drill 0.2)
		(layers "F.Cu" "B.Cu")
		(net 459)
	)
	(via
		(at 135.6 108.8)
		(size 0.5)
		(drill 0.2)
		(layers "F.Cu" "B.Cu")
		(net 459)
	)
	(via
		(at 173.375 112.81)
		(size 0.5)
		(drill 0.2)
		(layers "F.Cu" "B.Cu")
		(net 459)
	)
	(via
		(at 147.411328 108.747157)
		(size 0.5)
		(drill 0.2)
		(layers "F.Cu" "B.Cu")
		(net 459)
	)
	(via
		(at 195.686328 102.020008)
		(size 0.5)
		(drill 0.2)
		(layers "F.Cu" "B.Cu")
		(net 459)
	)
	(via
		(at 180.995 113.572)
		(size 0.5)
		(drill 0.2)
		(layers "F.Cu" "B.Cu")
		(net 459)
	)
	(via
		(at 179.7 115)
		(size 0.5)
		(drill 0.2)
		(layers "F.Cu" "B.Cu")
		(net 459)
	)
	(via
		(at 178.036327 94.997156)
		(size 0.5)
		(drill 0.2)
		(layers "F.Cu" "B.Cu")
		(net 459)
	)
	(via
		(at 135.6 105.4)
		(size 0.5)
		(drill 0.2)
		(layers "F.Cu" "B.Cu")
		(net 459)
	)
	(via
		(at 135.8 72)
		(size 0.5)
		(drill 0.2)
		(layers "F.Cu" "B.Cu")
		(net 459)
	)
	(via
		(at 137.0325 86.3)
		(size 0.5)
		(drill 0.2)
		(layers "F.Cu" "B.Cu")
		(net 459)
	)
	(via
		(at 116.475 94.15)
		(size 0.5)
		(drill 0.2)
		(layers "F.Cu" "B.Cu")
		(free yes)
		(net 459)
	)
	(via
		(at 196.786328 87.220008)
		(size 0.5)
		(drill 0.2)
		(layers "F.Cu" "B.Cu")
		(net 459)
	)
	(via
		(at 195.686328 93.120008)
		(size 0.5)
		(drill 0.2)
		(layers "F.Cu" "B.Cu")
		(net 459)
	)
	(via
		(at 201.286328 128.920008)
		(size 0.5)
		(drill 0.2)
		(layers "F.Cu" "B.Cu")
		(net 459)
	)
	(via
		(at 178.201 128.685)
		(size 0.5)
		(drill 0.2)
		(layers "F.Cu" "B.Cu")
		(net 459)
	)
	(via
		(at 206.086328 87.520008)
		(size 0.5)
		(drill 0.2)
		(layers "F.Cu" "B.Cu")
		(net 459)
	)
	(via
		(at 139.661328 118.122157)
		(size 0.5)
		(drill 0.2)
		(layers "F.Cu" "B.Cu")
		(net 459)
	)
	(via
		(at 169.3 114.6)
		(size 0.5)
		(drill 0.2)
		(layers "F.Cu" "B.Cu")
		(net 459)
	)
	(via
		(at 160.036328 101.997155)
		(size 0.5)
		(drill 0.2)
		(layers "F.Cu" "B.Cu")
		(net 459)
	)
	(via
		(at 205.286328 80.520008)
		(size 0.5)
		(drill 0.2)
		(layers "F.Cu" "B.Cu")
		(net 459)
	)
	(via
		(at 194.686328 93.120008)
		(size 0.5)
		(drill 0.2)
		(layers "F.Cu" "B.Cu")
		(net 459)
	)
	(via
		(at 137.0325 88.8)
		(size 0.5)
		(drill 0.2)
		(layers "F.Cu" "B.Cu")
		(net 459)
	)
	(via
		(at 178.036329 105.997157)
		(size 0.5)
		(drill 0.2)
		(layers "F.Cu" "B.Cu")
		(net 459)
	)
	(via
		(at 174.036327 105.997157)
		(size 0.5)
		(drill 0.2)
		(layers "F.Cu" "B.Cu")
		(net 459)
	)
	(via
		(at 135.8 80.4)
		(size 0.5)
		(drill 0.2)
		(layers "F.Cu" "B.Cu")
		(net 459)
	)
	(via
		(at 206.086328 83.920008)
		(size 0.5)
		(drill 0.2)
		(layers "F.Cu" "B.Cu")
		(net 459)
	)
	(via
		(at 153.924 95.834204)
		(size 0.5)
		(drill 0.2)
		(layers "F.Cu" "B.Cu")
		(net 459)
	)
	(via
		(at 117.675 94.15)
		(size 0.5)
		(drill 0.2)
		(layers "F.Cu" "B.Cu")
		(free yes)
		(net 459)
	)
	(via
		(at 189.864171 118.258485)
		(size 0.5)
		(drill 0.2)
		(layers "F.Cu" "B.Cu")
		(net 459)
	)
	(via
		(at 210.086328 105.020008)
		(size 0.5)
		(drill 0.2)
		(layers "F.Cu" "B.Cu")
		(net 459)
	)
	(via
		(at 204.186328 80.520008)
		(size 0.5)
		(drill 0.2)
		(layers "F.Cu" "B.Cu")
		(net 459)
	)
	(via
		(at 139.855 102.705)
		(size 0.5)
		(drill 0.2)
		(layers "F.Cu" "B.Cu")
		(net 459)
	)
	(via
		(at 171.597 128.812)
		(size 0.5)
		(drill 0.2)
		(layers "F.Cu" "B.Cu")
		(net 459)
	)
	(via
		(at 199.786328 92.120008)
		(size 0.5)
		(drill 0.2)
		(layers "F.Cu" "B.Cu")
		(net 459)
	)
	(via
		(at 117.075 93.75)
		(size 0.5)
		(drill 0.2)
		(layers "F.Cu" "B.Cu")
		(free yes)
		(net 459)
	)
	(via
		(at 150.3172 93.599)
		(size 0.5)
		(drill 0.2)
		(layers "F.Cu" "B.Cu")
		(net 459)
	)
	(via
		(at 180.661334 101.497156)
		(size 0.5)
		(drill 0.2)
		(layers "F.Cu" "B.Cu")
		(net 459)
	)
	(via
		(at 209.186328 64.720008)
		(size 0.5)
		(drill 0.2)
		(layers "F.Cu" "B.Cu")
		(net 459)
	)
	(via
		(at 145.046328 115.717157)
		(size 0.5)
		(drill 0.2)
		(layers "F.Cu" "B.Cu")
		(net 459)
	)
	(via
		(at 158.359 121.735)
		(size 0.5)
		(drill 0.2)
		(layers "F.Cu" "B.Cu")
		(net 459)
	)
	(via
		(at 210.086328 103.520008)
		(size 0.5)
		(drill 0.2)
		(layers "F.Cu" "B.Cu")
		(net 459)
	)
	(via
		(at 136 101.125)
		(size 0.5)
		(drill 0.2)
		(layers "F.Cu" "B.Cu")
		(net 459)
	)
	(via
		(at 195.086328 109.020008)
		(size 0.5)
		(drill 0.2)
		(layers "F.Cu" "B.Cu")
		(net 459)
	)
	(via
		(at 174.946666 134.320666)
		(size 0.5)
		(drill 0.2)
		(layers "F.Cu" "B.Cu")
		(net 459)
	)
	(via
		(at 197.686328 92.820008)
		(size 0.5)
		(drill 0.2)
		(layers "F.Cu" "B.Cu")
		(net 459)
	)
	(via
		(at 197.886328 64.020008)
		(size 0.5)
		(drill 0.2)
		(layers "F.Cu" "B.Cu")
		(net 459)
	)
	(via
		(at 196.686328 93.020008)
		(size 0.5)
		(drill 0.2)
		(layers "F.Cu" "B.Cu")
		(net 459)
	)
	(via
		(at 177.2 123.2)
		(size 0.5)
		(drill 0.2)
		(layers "F.Cu" "B.Cu")
		(net 459)
	)
	(via
		(at 207.486328 104.320008)
		(size 0.5)
		(drill 0.2)
		(layers "F.Cu" "B.Cu")
		(net 459)
	)
	(via
		(at 143.786328 116.517157)
		(size 0.5)
		(drill 0.2)
		(layers "F.Cu" "B.Cu")
		(net 459)
	)
	(via
		(at 137.0325 91.3)
		(size 0.5)
		(drill 0.2)
		(layers "F.Cu" "B.Cu")
		(net 459)
	)
	(via
		(at 151.202242 99.790328)
		(size 0.5)
		(drill 0.2)
		(layers "F.Cu" "B.Cu")
		(net 459)
	)
	(via
		(at 167.036328 104.997158)
		(size 0.5)
		(drill 0.2)
		(layers "F.Cu" "B.Cu")
		(net 459)
	)
	(segment
		(start 173.015 101.75)
		(end 173.015 101.018485)
		(width 0.2)
		(layer "B.Cu")
		(net 459)
	)
	(segment
		(start 197.796328 103.320008)
		(end 198.586328 104.110008)
		(width 0.2)
		(layer "B.Cu")
		(net 459)
	)
	(segment
		(start 177.036328 102.482157)
		(end 177.036328 102.997156)
		(width 0.15)
		(layer "B.Cu")
		(net 459)
	)
	(segment
		(start 169.036328 104.797157)
		(end 169.836327 104.797157)
		(width 0.2)
		(layer "B.Cu")
		(net 459)
	)
	(segment
		(start 190.63203 128.974306)
		(end 190.586328 129.020008)
		(width 0.2)
		(layer "B.Cu")
		(net 459)
	)
	(segment
		(start 177.036328 102.997156)
		(end 177.036329 102.997157)
		(width 0.15)
		(layer "B.Cu")
		(net 459)
	)
	(segment
		(start 173.985 105.94583)
		(end 174.036327 105.997157)
		(width 0.2)
		(layer "B.Cu")
		(net 459)
	)
	(segment
		(start 167.836328 90.982157)
		(end 167.051328 90.982157)
		(width 0.15)
		(layer "B.Cu")
		(net 459)
	)
	(segment
		(start 159.985 103.125)
		(end 159.985 104.018485)
		(width 0.2)
		(layer "B.Cu")
		(net 459)
	)
	(segment
		(start 151.202242 99.790328)
		(end 150.310928 99.790328)
		(width 0.15)
		(layer "B.Cu")
		(net 459)
	)
	(segment
		(start 179.7035 115.0035)
		(end 179.7 115)
		(width 0.2)
		(layer "B.Cu")
		(net 459)
	)
	(segment
		(start 198.586328 104.110008)
		(end 198.586328 104.120008)
		(width 0.2)
		(layer "B.Cu")
		(net 459)
	)
	(segment
		(start 135.775 70.25)
		(end 135.775 71.26)
		(width 0.2)
		(layer "B.Cu")
		(net 459)
	)
	(segment
		(start 177.36 94.75)
		(end 177.789171 94.75)
		(width 0.2)
		(layer "B.Cu")
		(net 459)
	)
	(segment
		(start 162.111328 99.922158)
		(end 162.036328 99.997158)
		(width 0.15)
		(layer "B.Cu")
		(net 459)
	)
	(segment
		(start 197.686328 93.535008)
		(end 197.686328 92.820008)
		(width 0.2)
		(layer "B.Cu")
		(net 459)
	)
	(segment
		(start 194.686328 95.235008)
		(end 194.686328 93.120008)
		(width 0.2)
		(layer "B.Cu")
		(net 459)
	)
	(segment
		(start 167.015 102.975828)
		(end 167.036328 102.997156)
		(width 0.2)
		(layer "B.Cu")
		(net 459)
	)
	(segment
		(start 170.015 102.018486)
		(end 170.036329 101.997157)
		(width 0.2)
		(layer "B.Cu")
		(net 459)
	)
	(segment
		(start 157.777728 99.156157)
		(end 158.668357 99.156157)
		(width 0.15)
		(layer "B.Cu")
		(net 459)
	)
	(segment
		(start 163.985 105.94583)
		(end 164.036328 105.997158)
		(width 0.2)
		(layer "B.Cu")
		(net 459)
	)
	(segment
		(start 170.015 102.75)
		(end 170.015 102.018486)
		(width 0.2)
		(layer "B.Cu")
		(net 459)
	)
	(segment
		(start 198.686328 98.720008)
		(end 198.686328 99.335008)
		(width 0.2)
		(layer "B.Cu")
		(net 459)
	)
	(segment
		(start 175.036329 96.197158)
		(end 175.036328 96.197157)
		(width 0.2)
		(layer "B.Cu")
		(net 459)
	)
	(segment
		(start 195.686328 95.735008)
		(end 195.686328 93.120008)
		(width 0.2)
		(layer "B.Cu")
		(net 459)
	)
	(segment
		(start 173.015 101.018485)
		(end 173.036329 100.997156)
		(width 0.2)
		(layer "B.Cu")
		(net 459)
	)
	(segment
		(start 163.985 105.125)
		(end 163.985 105.94583)
		(width 0.2)
		(layer "B.Cu")
		(net 459)
	)
	(segment
		(start 135.815 79.7)
		(end 135.815 78.69)
		(width 0.2)
		(layer "B.Cu")
		(net 459)
	)
	(segment
		(start 194.786328 102.035008)
		(end 195.671328 102.035008)
		(width 0.2)
		(layer "B.Cu")
		(net 459)
	)
	(segment
		(start 164.036327 102.997157)
		(end 164.862843 102.997157)
		(width 0.2)
		(layer "B.Cu")
		(net 459)
	)
	(segment
		(start 173.985 105.125)
		(end 173.985 105.94583)
		(width 0.2)
		(layer "B.Cu")
		(net 459)
	)
	(segment
		(start 176.485 91.5)
		(end 176.539173 91.5)
		(width 0.2)
		(layer "B.Cu")
		(net 459)
	)
	(segment
		(start 134.685 79.7)
		(end 135.815 79.7)
		(width 0.2)
		(layer "B.Cu")
		(net 459)
	)
	(segment
		(start 169.307 118.271)
		(end 169.307 115.731)
		(width 0.2)
		(layer "B.Cu")
		(net 459)
	)
	(segment
		(start 195.086328 108.274306)
		(end 195.086328 109.020008)
		(width 0.2)
		(layer "B.Cu")
		(net 459)
	)
	(segment
		(start 180.611333 101.547157)
		(end 180.661334 101.497156)
		(width 0.15)
		(layer "B.Cu")
		(net 459)
	)
	(segment
		(start 177.985 99.125)
		(end 177.985 98.048485)
		(width 0.2)
		(layer "B.Cu")
		(net 459)
	)
	(segment
		(start 175.036329 96.997157)
		(end 175.036329 96.197158)
		(width 0.2)
		(layer "B.Cu")
		(net 459)
	)
	(segment
		(start 176.539173 91.5)
		(end 177.03633 91.997157)
		(width 0.2)
		(layer "B.Cu")
		(net 459)
	)
	(segment
		(start 197.486328 99.535008)
		(end 198.486328 99.535008)
		(width 0.2)
		(layer "B.Cu")
		(net 459)
	)
	(segment
		(start 174.946666 132.973218)
		(end 174.946666 134.320666)
		(width 0.2)
		(layer "B.Cu")
		(net 459)
	)
	(segment
		(start 135.815 71.985)
		(end 135.8 72)
		(width 0.2)
		(layer "B.Cu")
		(net 459)
	)
	(segment
		(start 179.661328 101.547157)
		(end 180.611333 101.547157)
		(width 0.15)
		(layer "B.Cu")
		(net 459)
	)
	(segment
		(start 164.862843 102.997157)
		(end 164.875 102.985)
		(width 0.2)
		(layer "B.Cu")
		(net 459)
	)
	(segment
		(start 166.985 104.94583)
		(end 167.036328 104.997158)
		(width 0.2)
		(layer "B.Cu")
		(net 459)
	)
	(segment
		(start 150.4926 96.2382)
		(end 150.183928 95.929528)
		(width 0.15)
		(layer "B.Cu")
		(net 459)
	)
	(segment
		(start 197.471328 99.520008)
		(end 197.486328 99.535008)
		(width 0.2)
		(layer "B.Cu")
		(net 459)
	)
	(segment
		(start 135.815 71.3)
		(end 134.985 71.3)
		(width 0.2)
		(layer "B.Cu")
		(net 459)
	)
	(segment
		(start 173.336328 90.497157)
		(end 172.836329 90.997156)
		(width 0.15)
		(layer "B.Cu")
		(net 459)
	)
	(segment
		(start 172.036329 90.997156)
		(end 172.836329 90.997156)
		(width 0.15)
		(layer "B.Cu")
		(net 459)
	)
	(segment
		(start 167.051328 90.982157)
		(end 167.036329 90.997156)
		(width 0.15)
		(layer "B.Cu")
		(net 459)
	)
	(segment
		(start 174.5 92.533485)
		(end 174.036329 92.997156)
		(width 0.2)
		(layer "B.Cu")
		(net 459)
	)
	(segment
		(start 197.371328 103.320008)
		(end 197.796328 103.320008)
		(width 0.2)
		(layer "B.Cu")
		(net 459)
	)
	(segment
		(start 150.183928 95.929528)
		(end 150.183928 95.787358)
		(width 0.15)
		(layer "B.Cu")
		(net 459)
	)
	(segment
		(start 201.340626 128.974306)
		(end 201.286328 128.920008)
		(width 0.2)
		(layer "B.Cu")
		(net 459)
	)
	(segment
		(start 153.9772 94.742)
		(end 153.9772 95.781004)
		(width 0.15)
		(layer "B.Cu")
		(net 459)
	)
	(segment
		(start 174.985 99.048485)
		(end 175.036327 98.997158)
		(width 0.2)
		(layer "B.Cu")
		(net 459)
	)
	(segment
		(start 196.686328 94.035008)
		(end 196.686328 93.020008)
		(width 0.2)
		(layer "B.Cu")
		(net 459)
	)
	(segment
		(start 135.815 71.3)
		(end 135.815 71.985)
		(width 0.2)
		(layer "B.Cu")
		(net 459)
	)
	(segment
		(start 174.5 92.485)
		(end 174.5 92.533485)
		(width 0.2)
		(layer "B.Cu")
		(net 459)
	)
	(segment
		(start 209.271328 103.520008)
		(end 210.086328 103.520008)
		(width 0.2)
		(layer "B.Cu")
		(net 459)
	)
	(segment
		(start 177.789171 94.75)
		(end 178.036327 94.997156)
		(width 0.2)
		(layer "B.Cu")
		(net 459)
	)
	(segment
		(start 196.371328 99.520008)
		(end 196.371328 98.935008)
		(width 0.2)
		(layer "B.Cu")
		(net 459)
	)
	(segment
		(start 202.201328 128.974306)
		(end 201.340626 128.974306)
		(width 0.2)
		(layer "B.Cu")
		(net 459)
	)
	(segment
		(start 196.371328 98.935008)
		(end 196.386328 98.920008)
		(width 0.2)
		(layer "B.Cu")
		(net 459)
	)
	(segment
		(start 178.036329 105.997157)
		(end 178.036329 107.024307)
		(width 0.2)
		(layer "B.Cu")
		(net 459)
	)
	(segment
		(start 198.786328 94.635008)
		(end 198.786328 93.120008)
		(width 0.2)
		(layer "B.Cu")
		(net 459)
	)
	(segment
		(start 166.985 104.125)
		(end 166.985 104.94583)
		(width 0.2)
		(layer "B.Cu")
		(net 459)
	)
	(segment
		(start 191.201328 128.974306)
		(end 190.63203 128.974306)
		(width 0.2)
		(layer "B.Cu")
		(net 459)
	)
	(segment
		(start 174.985 99.875)
		(end 174.985 99.048485)
		(width 0.2)
		(layer "B.Cu")
		(net 459)
	)
	(segment
		(start 135.815 79.7)
		(end 135.815 80.385)
		(width 0.2)
		(layer "B.Cu")
		(net 459)
	)
	(segment
		(start 209.271328 105.020008)
		(end 210.086328 105.020008)
		(width 0.2)
		(layer "B.Cu")
		(net 459)
	)
	(segment
		(start 169.836327 104.797157)
		(end 170.036328 104.997158)
		(width 0.2)
		(layer "B.Cu")
		(net 459)
	)
	(segment
		(start 177.985 98.048485)
		(end 178.036327 97.997158)
		(width 0.2)
		(layer "B.Cu")
		(net 459)
	)
	(segment
		(start 169.307 114.607)
		(end 169.3 114.6)
		(width 0.2)
		(layer "B.Cu")
		(net 459)
	)
	(segment
		(start 160.015 101.975827)
		(end 160.036328 101.997155)
		(width 0.2)
		(layer "B.Cu")
		(net 459)
	)
	(segment
		(start 162.111328 99.247157)
		(end 162.111328 99.922158)
		(width 0.15)
		(layer "B.Cu")
		(net 459)
	)
	(segment
		(start 159.985 104.018485)
		(end 160.002843 104.036328)
		(width 0.2)
		(layer "B.Cu")
		(net 459)
	)
	(segment
		(start 174.015 103.125)
		(end 174.015 103.975828)
		(width 0.2)
		(layer "B.Cu")
		(net 459)
	)
	(segment
		(start 160.015 101.125)
		(end 160.015 101.975827)
		(width 0.2)
		(layer "B.Cu")
		(net 459)
	)
	(segment
		(start 198.586328 104.120008)
		(end 198.786328 104.320008)
		(width 0.2)
		(layer "B.Cu")
		(net 459)
	)
	(segment
		(start 195.671328 102.035008)
		(end 195.686328 102.020008)
		(width 0.2)
		(layer "B.Cu")
		(net 459)
	)
	(segment
		(start 150.20297 95.8064)
		(end 150.183928 95.787358)
		(width 0.15)
		(layer "B.Cu")
		(net 459)
	)
	(segment
		(start 196.371328 99.520008)
		(end 197.471328 99.520008)
		(width 0.2)
		(layer "B.Cu")
		(net 459)
	)
	(segment
		(start 135.815 80.385)
		(end 135.8 80.4)
		(width 0.2)
		(layer "B.Cu")
		(net 459)
	)
	(segment
		(start 198.786328 104.320008)
		(end 207.486328 104.320008)
		(width 0.2)
		(layer "B.Cu")
		(net 459)
	)
	(segment
		(start 135.815 78.69)
		(end 135.775 78.65)
		(width 0.2)
		(layer "B.Cu")
		(net 459)
	)
	(segment
		(start 174.015 103.975828)
		(end 174.036329 103.997157)
		(width 0.2)
		(layer "B.Cu")
		(net 459)
	)
	(segment
		(start 199.786328 92.735008)
		(end 199.786328 92.120008)
		(width 0.2)
		(layer "B.Cu")
		(net 459)
	)
	(segment
		(start 167.015 102.125)
		(end 167.015 102.975828)
		(width 0.2)
		(layer "B.Cu")
		(net 459)
	)
	(segment
		(start 135.775 71.26)
		(end 135.815 71.3)
		(width 0.2)
		(layer "B.Cu")
		(net 459)
	)
	(segment
		(start 153.9772 95.781004)
		(end 153.924 95.834204)
		(width 0.15)
		(layer "B.Cu")
		(net 459)
	)
	(segment
		(start 179.7035 118.271)
		(end 179.7035 115.0035)
		(width 0.2)
		(layer "B.Cu")
		(net 459)
	)
	(segment
		(start 150.9014 96.2382)
		(end 150.4926 96.2382)
		(width 0.15)
		(layer "B.Cu")
		(net 459)
	)
	(segment
		(start 169.307 115.731)
		(end 169.307 114.607)
		(width 0.2)
		(layer "B.Cu")
		(net 459)
	)
	(segment
		(start 198.686328 99.335008)
		(end 198.486328 99.535008)
		(width 0.2)
		(layer "B.Cu")
		(net 459)
	)
	(segment
		(start 169.536327 90.997156)
		(end 170.036328 91.497157)
		(width 0.2)
		(layer "In5.Cu")
		(net 459)
	)
	(segment
		(start 167.036329 90.997156)
		(end 169.536327 90.997156)
		(width 0.2)
		(layer "In5.Cu")
		(net 459)
	)
	(segment
		(start 170.036328 91.497157)
		(end 175.911328 91.497157)
		(width 0.2)
		(layer "In5.Cu")
		(net 459)
	)
	(segment
		(start 176.411328 91.997157)
		(end 177.03633 91.997157)
		(width 0.2)
		(layer "In5.Cu")
		(net 459)
	)
	(segment
		(start 171.536328 91.497157)
		(end 171.78633 91.247155)
		(width 0.2)
		(layer "In5.Cu")
		(net 459)
	)
	(segment
		(start 171.78633 91.247155)
		(end 172.036329 90.997156)
		(width 0.2)
		(layer "In5.Cu")
		(net 459)
	)
	(segment
		(start 175.911328 91.497157)
		(end 176.411328 91.997157)
		(width 0.2)
		(layer "In5.Cu")
		(net 459)
	)
	(segment
		(start 170.536329 96.497157)
		(end 171.036329 96.997157)
		(width 0.15)
		(layer "F.Cu")
		(net 460)
	)
	(segment
		(start 170.536329 94.497156)
		(end 170.03633 94.997155)
		(width 0.15)
		(layer "F.Cu")
		(net 460)
	)
	(segment
		(start 168.536329 94.497157)
		(end 168.036329 93.997157)
		(width 0.15)
		(layer "F.Cu")
		(net 460)
	)
	(segment
		(start 165.536329 93.497156)
		(end 165.036329 92.997156)
		(width 0.15)
		(layer "F.Cu")
		(net 460)
	)
	(segment
		(start 166.536329 92.497157)
		(end 166.036329 91.997157)
		(width 0.15)
		(layer "F.Cu")
		(net 460)
	)
	(segment
		(start 166.536329 94.497156)
		(end 166.03633 93.997157)
		(width 0.15)
		(layer "F.Cu")
		(net 460)
	)
	(segment
		(start 165.536329 95.497156)
		(end 165.036329 94.997157)
		(width 0.15)
		(layer "F.Cu")
		(net 460)
	)
	(segment
		(start 166.536329 91.497157)
		(end 166.036329 90.997156)
		(width 0.15)
		(layer "F.Cu")
		(net 460)
	)
	(segment
		(start 166.536329 96.497157)
		(end 166.036329 96.997157)
		(width 0.15)
		(layer "F.Cu")
		(net 460)
	)
	(segment
		(start 143.6825 92.6)
		(end 144.6492 92.6)
		(width 0.15)
		(layer "F.Cu")
		(net 460)
	)
	(segment
		(start 143.0325 92.6)
		(end 143.6825 92.6)
		(width 0.2)
		(layer "F.Cu")
		(net 460)
	)
	(via
		(at 171.036329 96.997157)
		(size 0.5)
		(drill 0.2)
		(layers "F.Cu" "B.Cu")
		(net 460)
	)
	(via
		(at 170.073 95.03)
		(size 0.5)
		(drill 0.2)
		(layers "F.Cu" "B.Cu")
		(net 460)
	)
	(via
		(at 168.036329 93.997157)
		(size 0.5)
		(drill 0.2)
		(layers "F.Cu" "B.Cu")
		(net 460)
	)
	(via
		(at 165.036329 94.997157)
		(size 0.5)
		(drill 0.2)
		(layers "F.Cu" "B.Cu")
		(net 460)
	)
	(via
		(at 166.036329 91.997157)
		(size 0.5)
		(drill 0.2)
		(layers "F.Cu" "B.Cu")
		(net 460)
	)
	(via
		(at 165.036329 92.997156)
		(size 0.5)
		(drill 0.2)
		(layers "F.Cu" "B.Cu")
		(net 460)
	)
	(via
		(at 166.03633 93.997157)
		(size 0.5)
		(drill 0.2)
		(layers "F.Cu" "B.Cu")
		(net 460)
	)
	(via
		(at 166.036329 90.997156)
		(size 0.5)
		(drill 0.2)
		(layers "F.Cu" "B.Cu")
		(net 460)
	)
	(via
		(at 166.036329 96.997157)
		(size 0.5)
		(drill 0.2)
		(layers "F.Cu" "B.Cu")
		(net 460)
	)
	(via
		(at 116.4 80.7)
		(size 0.5)
		(drill 0.2)
		(layers "F.Cu" "B.Cu")
		(free yes)
		(net 460)
	)
	(via
		(at 115.8 82.5)
		(size 0.5)
		(drill 0.2)
		(layers "F.Cu" "B.Cu")
		(free yes)
		(net 460)
	)
	(via
		(at 134.4 67.8)
		(size 0.5)
		(drill 0.2)
		(layers "F.Cu" "B.Cu")
		(free yes)
		(net 460)
	)
	(via
		(at 134.4 67.2)
		(size 0.5)
		(drill 0.2)
		(layers "F.Cu" "B.Cu")
		(free yes)
		(net 460)
	)
	(via
		(at 134.4 69)
		(size 0.5)
		(drill 0.2)
		(layers "F.Cu" "B.Cu")
		(free yes)
		(net 460)
	)
	(via
		(at 134.4 68.4)
		(size 0.5)
		(drill 0.2)
		(layers "F.Cu" "B.Cu")
		(free yes)
		(net 460)
	)
	(via
		(at 133.8 67.2)
		(size 0.5)
		(drill 0.2)
		(layers "F.Cu" "B.Cu")
		(free yes)
		(net 460)
	)
	(via
		(at 133.8 67.8)
		(size 0.5)
		(drill 0.2)
		(layers "F.Cu" "B.Cu")
		(free yes)
		(net 460)
	)
	(via
		(at 115.8 80.7)
		(size 0.5)
		(drill 0.2)
		(layers "F.Cu" "B.Cu")
		(free yes)
		(net 460)
	)
	(via
		(at 117 81.9)
		(size 0.5)
		(drill 0.2)
		(layers "F.Cu" "B.Cu")
		(free yes)
		(net 460)
	)
	(via
		(at 116.4 81.3)
		(size 0.5)
		(drill 0.2)
		(layers "F.Cu" "B.Cu")
		(free yes)
		(net 460)
	)
	(via
		(at 174.053954 97.940262)
		(size 0.5)
		(drill 0.2)
		(layers "F.Cu" "B.Cu")
		(net 460)
	)
	(via
		(at 143.6825 92.6)
		(size 0.5)
		(drill 0.2)
		(layers "F.Cu" "B.Cu")
		(net 460)
	)
	(via
		(at 180.536328 97.947157)
		(size 0.5)
		(drill 0.2)
		(layers "F.Cu" "B.Cu")
		(net 460)
	)
	(via
		(at 116.4 81.9)
		(size 0.5)
		(drill 0.2)
		(layers "F.Cu" "B.Cu")
		(free yes)
		(net 460)
	)
	(via
		(at 117 80.7)
		(size 0.5)
		(drill 0.2)
		(layers "F.Cu" "B.Cu")
		(free yes)
		(net 460)
	)
	(via
		(at 133.8 69)
		(size 0.5)
		(drill 0.2)
		(layers "F.Cu" "B.Cu")
		(free yes)
		(net 460)
	)
	(via
		(at 115.8 81.9)
		(size 0.5)
		(drill 0.2)
		(layers "F.Cu" "B.Cu")
		(free yes)
		(net 460)
	)
	(via
		(at 116.4 82.5)
		(size 0.5)
		(drill 0.2)
		(layers "F.Cu" "B.Cu")
		(free yes)
		(net 460)
	)
	(via
		(at 180.836328 86.597157)
		(size 0.5)
		(drill 0.2)
		(layers "F.Cu" "B.Cu")
		(net 460)
	)
	(via
		(at 133.8 68.4)
		(size 0.5)
		(drill 0.2)
		(layers "F.Cu" "B.Cu")
		(free yes)
		(net 460)
	)
	(via
		(at 134.4 66.6)
		(size 0.5)
		(drill 0.2)
		(layers "F.Cu" "B.Cu")
		(free yes)
		(net 460)
	)
	(via
		(at 133.8 66.6)
		(size 0.5)
		(drill 0.2)
		(layers "F.Cu" "B.Cu")
		(free yes)
		(net 460)
	)
	(via
		(at 117 81.3)
		(size 0.5)
		(drill 0.2)
		(layers "F.Cu" "B.Cu")
		(free yes)
		(net 460)
	)
	(via
		(at 117 82.5)
		(size 0.5)
		(drill 0.2)
		(layers "F.Cu" "B.Cu")
		(free yes)
		(net 460)
	)
	(via
		(at 115.8 81.3)
		(size 0.5)
		(drill 0.2)
		(layers "F.Cu" "B.Cu")
		(free yes)
		(net 460)
	)
	(segment
		(start 165.861328 96.347157)
		(end 165.861328 96.822156)
		(width 0.15)
		(layer "B.Cu")
		(net 460)
	)
	(segment
		(start 170.765 94.338)
		(end 170.073 95.03)
		(width 0.2)
		(layer "B.Cu")
		(net 460)
	)
	(segment
		(start 165.216328 95.177156)
		(end 165.036329 94.997157)
		(width 0.15)
		(layer "B.Cu")
		(net 460)
	)
	(segment
		(start 164.336328 92.817157)
		(end 164.85633 92.817157)
		(width 0.15)
		(layer "B.Cu")
		(net 460)
	)
	(segment
		(start 167.015 96.018486)
		(end 166.036329 96.997157)
		(width 0.2)
		(layer "B.Cu")
		(net 460)
	)
	(segment
		(start 167.015 95.875)
		(end 167.015 96.018486)
		(width 0.2)
		(layer "B.Cu")
		(net 460)
	)
	(segment
		(start 165.216328 95.622157)
		(end 165.216328 95.177156)
		(width 0.15)
		(layer "B.Cu")
		(net 460)
	)
	(segment
		(start 180.586328 97.897157)
		(end 180.536328 97.947157)
		(width 0.2)
		(layer "B.Cu")
		(net 460)
	)
	(segment
		(start 181.436328 97.897157)
		(end 180.586328 97.897157)
		(width 0.2)
		(layer "B.Cu")
		(net 460)
	)
	(segment
		(start 167.856329 94.177157)
		(end 168.036329 93.997157)
		(width 0.15)
		(layer "B.Cu")
		(net 460)
	)
	(segment
		(start 169.856328 95.246672)
		(end 170.073 95.03)
		(width 0.15)
		(layer "B.Cu")
		(net 460)
	)
	(segment
		(start 169.856328 95.697157)
		(end 169.856328 95.246672)
		(width 0.15)
		(layer "B.Cu")
		(net 460)
	)
	(segment
		(start 165.861328 96.822156)
		(end 166.036329 96.997157)
		(width 0.15)
		(layer "B.Cu")
		(net 460)
	)
	(segment
		(start 166.036329 91.997157)
		(end 166.036329 91.977158)
		(width 0.15)
		(layer "B.Cu")
		(net 460)
	)
	(segment
		(start 167.411328 94.177157)
		(end 167.856329 94.177157)
		(width 0.15)
		(layer "B.Cu")
		(net 460)
	)
	(segment
		(start 164.85633 92.817157)
		(end 165.036329 92.997156)
		(width 0.15)
		(layer "B.Cu")
		(net 460)
	)
	(segment
		(start 165.11 94)
		(end 166.033487 94)
		(width 0.2)
		(layer "B.Cu")
		(net 460)
	)
	(segment
		(start 166.661328 94.177157)
		(end 166.21633 94.177157)
		(width 0.15)
		(layer "B.Cu")
		(net 460)
	)
	(segment
		(start 170.765 94.125)
		(end 170.765 94.338)
		(width 0.2)
		(layer "B.Cu")
		(net 460)
	)
	(segment
		(start 181.536328 86.597157)
		(end 180.836328 86.597157)
		(width 0.2)
		(layer "B.Cu")
		(net 460)
	)
	(segment
		(start 171.191328 96.372157)
		(end 171.191328 96.842158)
		(width 0.15)
		(layer "B.Cu")
		(net 460)
	)
	(segment
		(start 166.036329 91.977158)
		(end 165.356328 91.297157)
		(width 0.15)
		(layer "B.Cu")
		(net 460)
	)
	(segment
		(start 171.191328 96.842158)
		(end 171.036329 96.997157)
		(width 0.15)
		(layer "B.Cu")
		(net 460)
	)
	(segment
		(start 165.356328 90.522157)
		(end 165.56133 90.522157)
		(width 0.15)
		(layer "B.Cu")
		(net 460)
	)
	(segment
		(start 174.8 97.875)
		(end 174.119216 97.875)
		(width 0.2)
		(layer "B.Cu")
		(net 460)
	)
	(segment
		(start 164.658486 95.375)
		(end 165.036329 94.997157)
		(width 0.2)
		(layer "B.Cu")
		(net 460)
	)
	(segment
		(start 174.119216 97.875)
		(end 174.053954 97.940262)
		(width 0.2)
		(layer "B.Cu")
		(net 460)
	)
	(segment
		(start 166.033487 94)
		(end 166.03633 93.997157)
		(width 0.2)
		(layer "B.Cu")
		(net 460)
	)
	(segment
		(start 164.075 95.375)
		(end 164.658486 95.375)
		(width 0.2)
		(layer "B.Cu")
		(net 460)
	)
	(segment
		(start 165.56133 90.522157)
		(end 166.036329 90.997156)
		(width 0.15)
		(layer "B.Cu")
		(net 460)
	)
	(segment
		(start 166.21633 94.177157)
		(end 166.03633 93.997157)
		(width 0.15)
		(layer "B.Cu")
		(net 460)
	)
	(segment
		(start 131.7 82.8)
		(end 141.55 82.8)
		(width 0.15)
		(layer "F.Cu")
		(net 461)
	)
	(segment
		(start 131.6 82.7)
		(end 131.7 82.8)
		(width 0.15)
		(layer "F.Cu")
		(net 461)
	)
	(segment
		(start 143.0325 87.6)
		(end 142.9975 87.6)
		(width 0.15)
		(layer "F.Cu")
		(net 461)
	)
	(segment
		(start 142.4 83.65)
		(end 142.4 87)
		(width 0.15)
		(layer "F.Cu")
		(net 461)
	)
	(segment
		(start 141.55 82.8)
		(end 142.4 83.65)
		(width 0.15)
		(layer "F.Cu")
		(net 461)
	)
	(segment
		(start 143.0325 87.6)
		(end 144.6492 87.6)
		(width 0.15)
		(layer "F.Cu")
		(net 461)
	)
	(segment
		(start 144.6492 87.6)
		(end 144.7 87.5492)
		(width 0.15)
		(layer "F.Cu")
		(net 461)
	)
	(segment
		(start 142.9975 87.6)
		(end 142.3975 87)
		(width 0.15)
		(layer "F.Cu")
		(net 461)
	)
	(via
		(at 129.8 80.9)
		(size 0.5)
		(drill 0.2)
		(layers "F.Cu" "B.Cu")
		(free yes)
		(net 461)
	)
	(via
		(at 138.2 58)
		(size 0.5)
		(drill 0.2)
		(layers "F.Cu" "B.Cu")
		(free yes)
		(net 461)
	)
	(via
		(at 131.6 82.1)
		(size 0.5)
		(drill 0.2)
		(layers "F.Cu" "B.Cu")
		(free yes)
		(net 461)
	)
	(via
		(at 137.6 56.8)
		(size 0.5)
		(drill 0.2)
		(layers "F.Cu" "B.Cu")
		(free yes)
		(net 461)
	)
	(via
		(at 129.8 82.1)
		(size 0.5)
		(drill 0.2)
		(layers "F.Cu" "B.Cu")
		(free yes)
		(net 461)
	)
	(via
		(at 130.4 80.9)
		(size 0.5)
		(drill 0.2)
		(layers "F.Cu" "B.Cu")
		(free yes)
		(net 461)
	)
	(via
		(at 131.6 82.7)
		(size 0.5)
		(drill 0.2)
		(layers "F.Cu" "B.Cu")
		(free yes)
		(net 461)
	)
	(via
		(at 137.6 57.6)
		(size 0.5)
		(drill 0.2)
		(layers "F.Cu" "B.Cu")
		(free yes)
		(net 461)
	)
	(via
		(at 131 80.9)
		(size 0.5)
		(drill 0.2)
		(layers "F.Cu" "B.Cu")
		(free yes)
		(net 461)
	)
	(via
		(at 138.8 56.8)
		(size 0.5)
		(drill 0.2)
		(layers "F.Cu" "B.Cu")
		(free yes)
		(net 461)
	)
	(via
		(at 131 81.5)
		(size 0.5)
		(drill 0.2)
		(layers "F.Cu" "B.Cu")
		(free yes)
		(net 461)
	)
	(via
		(at 129.8 82.7)
		(size 0.5)
		(drill 0.2)
		(layers "F.Cu" "B.Cu")
		(free yes)
		(net 461)
	)
	(via
		(at 129.8 81.5)
		(size 0.5)
		(drill 0.2)
		(layers "F.Cu" "B.Cu")
		(free yes)
		(net 461)
	)
	(via
		(at 131.6 81.5)
		(size 0.5)
		(drill 0.2)
		(layers "F.Cu" "B.Cu")
		(free yes)
		(net 461)
	)
	(via
		(at 138.2 57.2)
		(size 0.5)
		(drill 0.2)
		(layers "F.Cu" "B.Cu")
		(free yes)
		(net 461)
	)
	(via
		(at 136.4 56.8)
		(size 0.5)
		(drill 0.2)
		(layers "F.Cu" "B.Cu")
		(free yes)
		(net 461)
	)
	(via
		(at 135.8 57.2)
		(size 0.5)
		(drill 0.2)
		(layers "F.Cu" "B.Cu")
		(free yes)
		(net 461)
	)
	(via
		(at 130.4 81.5)
		(size 0.5)
		(drill 0.2)
		(layers "F.Cu" "B.Cu")
		(free yes)
		(net 461)
	)
	(via
		(at 131.6 80.9)
		(size 0.5)
		(drill 0.2)
		(layers "F.Cu" "B.Cu")
		(free yes)
		(net 461)
	)
	(via
		(at 137 57.2)
		(size 0.5)
		(drill 0.2)
		(layers "F.Cu" "B.Cu")
		(free yes)
		(net 461)
	)
	(via
		(at 130.4 82.1)
		(size 0.5)
		(drill 0.2)
		(layers "F.Cu" "B.Cu")
		(free yes)
		(net 461)
	)
	(via
		(at 131 82.1)
		(size 0.5)
		(drill 0.2)
		(layers "F.Cu" "B.Cu")
		(free yes)
		(net 461)
	)
	(via
		(at 135.8 58)
		(size 0.5)
		(drill 0.2)
		(layers "F.Cu" "B.Cu")
		(free yes)
		(net 461)
	)
	(via
		(at 136.4 57.6)
		(size 0.5)
		(drill 0.2)
		(layers "F.Cu" "B.Cu")
		(free yes)
		(net 461)
	)
	(via
		(at 137 58)
		(size 0.5)
		(drill 0.2)
		(layers "F.Cu" "B.Cu")
		(free yes)
		(net 461)
	)
	(via
		(at 131 82.7)
		(size 0.5)
		(drill 0.2)
		(layers "F.Cu" "B.Cu")
		(free yes)
		(net 461)
	)
	(via
		(at 138.8 57.6)
		(size 0.5)
		(drill 0.2)
		(layers "F.Cu" "B.Cu")
		(free yes)
		(net 461)
	)
	(via
		(at 130.4 82.7)
		(size 0.5)
		(drill 0.2)
		(layers "F.Cu" "B.Cu")
		(free yes)
		(net 461)
	)
	(segment
		(start 136.024143 94.525)
		(end 134.01 94.525)
		(width 0.2)
		(layer "F.Cu")
		(net 463)
	)
	(segment
		(start 133.985 93.615)
		(end 134 93.6)
		(width 0.2)
		(layer "F.Cu")
		(net 463)
	)
	(segment
		(start 116.2 106.65)
		(end 115.95 106.4)
		(width 0.2)
		(layer "F.Cu")
		(net 463)
	)
	(segment
		(start 126 59.85)
		(end 126 60.6)
		(width 0.2)
		(layer "F.Cu")
		(net 463)
	)
	(segment
		(start 133.6 92.3)
		(end 128.8 92.3)
		(width 0.2)
		(layer "F.Cu")
		(net 463)
	)
	(segment
		(start 133.985 94.5)
		(end 133.985 93.615)
		(width 0.2)
		(layer "F.Cu")
		(net 463)
	)
	(segment
		(start 115.95 106.4)
		(end 115.95 102.75)
		(width 0.2)
		(layer "F.Cu")
		(net 463)
	)
	(segment
		(start 134 92.7)
		(end 133.6 92.3)
		(width 0.2)
		(layer "F.Cu")
		(net 463)
	)
	(segment
		(start 114.915 112.725)
		(end 114.915 111.785)
		(width 0.2)
		(layer "F.Cu")
		(net 463)
	)
	(segment
		(start 134.01 94.525)
		(end 133.985 94.5)
		(width 0.2)
		(layer "F.Cu")
		(net 463)
	)
	(segment
		(start 114.915 111.785)
		(end 116.2 110.5)
		(width 0.2)
		(layer "F.Cu")
		(net 463)
	)
	(segment
		(start 116.2 110.5)
		(end 116.2 106.65)
		(width 0.2)
		(layer "F.Cu")
		(net 463)
	)
	(segment
		(start 125.767157 58.857672)
		(end 125.767157 57.817672)
		(width 0.25)
		(layer "F.Cu")
		(net 463)
	)
	(segment
		(start 134 93.6)
		(end 134 92.7)
		(width 0.2)
		(layer "F.Cu")
		(net 463)
	)
	(via
		(at 184.05 116.835)
		(size 0.5)
		(drill 0.2)
		(layers "F.Cu" "B.Cu")
		(free yes)
		(net 463)
	)
	(via
		(at 126.6 64)
		(size 0.5)
		(drill 0.2)
		(layers "F.Cu" "B.Cu")
		(free yes)
		(net 463)
	)
	(via
		(at 125.2 109.3)
		(size 0.5)
		(drill 0.2)
		(layers "F.Cu" "B.Cu")
		(free yes)
		(net 463)
	)
	(via
		(at 126 64.4)
		(size 0.5)
		(drill 0.2)
		(layers "F.Cu" "B.Cu")
		(free yes)
		(net 463)
	)
	(via
		(at 125.4 64.8)
		(size 0.5)
		(drill 0.2)
		(layers "F.Cu" "B.Cu")
		(free yes)
		(net 463)
	)
	(via
		(at 125.2 108.1)
		(size 0.5)
		(drill 0.2)
		(layers "F.Cu" "B.Cu")
		(free yes)
		(net 463)
	)
	(via
		(at 126 65.2)
		(size 0.5)
		(drill 0.2)
		(layers "F.Cu" "B.Cu")
		(free yes)
		(net 463)
	)
	(via
		(at 125.6 108.7)
		(size 0.5)
		(drill 0.2)
		(layers "F.Cu" "B.Cu")
		(free yes)
		(net 463)
	)
	(via
		(at 184.65 116.235)
		(size 0.5)
		(drill 0.2)
		(layers "F.Cu" "B.Cu")
		(free yes)
		(net 463)
	)
	(via
		(at 119.4 59.4)
		(size 0.5)
		(drill 0.2)
		(layers "F.Cu" "B.Cu")
		(net 463)
	)
	(via
		(at 125.4 65.6)
		(size 0.5)
		(drill 0.2)
		(layers "F.Cu" "B.Cu")
		(free yes)
		(net 463)
	)
	(via
		(at 126.6 64.8)
		(size 0.5)
		(drill 0.2)
		(layers "F.Cu" "B.Cu")
		(free yes)
		(net 463)
	)
	(via
		(at 184.05 116.235)
		(size 0.5)
		(drill 0.2)
		(layers "F.Cu" "B.Cu")
		(free yes)
		(net 463)
	)
	(via
		(at 184.65 116.835)
		(size 0.5)
		(drill 0.2)
		(layers "F.Cu" "B.Cu")
		(free yes)
		(net 463)
	)
	(via
		(at 125.4 64)
		(size 0.5)
		(drill 0.2)
		(layers "F.Cu" "B.Cu")
		(free yes)
		(net 463)
	)
	(via
		(at 124.4 108.1)
		(size 0.5)
		(drill 0.2)
		(layers "F.Cu" "B.Cu")
		(free yes)
		(net 463)
	)
	(via
		(at 124.4 109.3)
		(size 0.5)
		(drill 0.2)
		(layers "F.Cu" "B.Cu")
		(free yes)
		(net 463)
	)
	(via
		(at 126.6 65.6)
		(size 0.5)
		(drill 0.2)
		(layers "F.Cu" "B.Cu")
		(free yes)
		(net 463)
	)
	(via
		(at 124.8 108.7)
		(size 0.5)
		(drill 0.2)
		(layers "F.Cu" "B.Cu")
		(free yes)
		(net 463)
	)
	(via
		(at 134 93.6)
		(size 0.5)
		(drill 0.2)
		(layers "F.Cu" "B.Cu")
		(net 463)
	)
	(segment
		(start 129.547157 120.547157)
		(end 164.936328 120.547157)
		(width 1)
		(layer "B.Cu")
		(net 463)
	)
	(segment
		(start 120.515 59.4)
		(end 119.4 59.4)
		(width 0.2)
		(layer "B.Cu")
		(net 463)
	)
	(segment
		(start 142.536328 91.885008)
		(end 139.764992 91.885008)
		(width 0.2)
		(layer "B.Cu")
		(net 463)
	)
	(segment
		(start 134 93.6)
		(end 138.05 93.6)
		(width 0.2)
		(layer "B.Cu")
		(net 463)
	)
	(segment
		(start 138.05 93.6)
		(end 139.764992 91.885008)
		(width 0.2)
		(layer "B.Cu")
		(net 463)
	)
	(segment
		(start 125.2 108.1)
		(end 125.2 116.2)
		(width 1)
		(layer "B.Cu")
		(net 463)
	)
	(segment
		(start 125.2 116.2)
		(end 129.547157 120.547157)
		(width 1)
		(layer "B.Cu")
		(net 463)
	)
	(segment
		(start 125.2 116.2)
		(end 125.2 109.3)
		(width 0.5)
		(layer "B.Cu")
		(net 463)
	)
	(segment
		(start 165.292484 120.191001)
		(end 182.108999 120.191001)
		(width 0.5)
		(layer "In5.Cu")
		(net 463)
	)
	(segment
		(start 182.108999 120.191001)
		(end 184.05 118.25)
		(width 0.5)
		(layer "In5.Cu")
		(net 463)
	)
	(segment
		(start 184.05 118.25)
		(end 184.05 116.235)
		(width 0.5)
		(layer "In5.Cu")
		(net 463)
	)
	(segment
		(start 119.4 64.6)
		(end 119.4 64.1)
		(width 0.1)
		(layer "In6.Cu")
		(net 463)
	)
	(segment
		(start 119.2 63.6)
		(end 119.45 63.85)
		(width 0.2)
		(layer "In6.Cu")
		(net 463)
	)
	(segment
		(start 119.2 63.6)
		(end 119.2 59.6)
		(width 0.2)
		(layer "In6.Cu")
		(net 463)
	)
	(segment
		(start 119.2 59.6)
		(end 119.4 59.4)
		(width 0.2)
		(layer "In6.Cu")
		(net 463)
	)
	(segment
		(start 119.4 64.1)
		(end 119.2 63.9)
		(width 0.2)
		(layer "In6.Cu")
		(net 463)
	)
	(segment
		(start 119.2 63.9)
		(end 119.2 63.6)
		(width 0.2)
		(layer "In6.Cu")
		(net 463)
	)
	(segment
		(start 148.521328 105.497157)
		(end 149.161334 105.497157)
		(width 0.1)
		(layer "F.Cu")
		(net 464)
	)
	(segment
		(start 161.536328 105.497158)
		(end 161.036328 104.997159)
		(width 0.15)
		(layer "F.Cu")
		(net 464)
	)
	(via
		(at 161.036328 104.997159)
		(size 0.5)
		(drill 0.2)
		(layers "F.Cu" "B.Cu")
		(net 464)
	)
	(via blind
		(at 149.161334 105.497157)
		(size 0.5)
		(drill 0.2)
		(layers "F.Cu" "In2.Cu")
		(net 464)
	)
	(segment
		(start 160.261317 105.772168)
		(end 161.036328 104.997157)
		(width 0.15)
		(layer "In2.Cu")
		(net 464)
	)
	(segment
		(start 150.411328 105.497157)
		(end 150.686339 105.772168)
		(width 0.15)
		(layer "In2.Cu")
		(net 464)
	)
	(segment
		(start 150.686339 105.772168)
		(end 160.261317 105.772168)
		(width 0.15)
		(layer "In2.Cu")
		(net 464)
	)
	(segment
		(start 149.161334 105.497157)
		(end 150.411328 105.497157)
		(width 0.15)
		(layer "In2.Cu")
		(net 464)
	)
	(segment
		(start 165.536329 97.497157)
		(end 165.036329 97.997156)
		(width 0.15)
		(layer "F.Cu")
		(net 465)
	)
	(segment
		(start 167.536329 97.497156)
		(end 167.036329 97.997156)
		(width 0.15)
		(layer "F.Cu")
		(net 465)
	)
	(segment
		(start 169.536329 97.497156)
		(end 170.036329 97.997156)
		(width 0.15)
		(layer "F.Cu")
		(net 465)
	)
	(segment
		(start 171.536329 93.497156)
		(end 172.036329 92.997156)
		(width 0.15)
		(layer "F.Cu")
		(net 465)
	)
	(segment
		(start 171.536329 95.497156)
		(end 172.036329 94.997157)
		(width 0.15)
		(layer "F.Cu")
		(net 465)
	)
	(segment
		(start 170.536329 92.497157)
		(end 171.036329 91.997157)
		(width 0.15)
		(layer "F.Cu")
		(net 465)
	)
	(segment
		(start 169.536329 93.497156)
		(end 169.03633 92.997156)
		(width 0.15)
		(layer "F.Cu")
		(net 465)
	)
	(segment
		(start 168.536329 92.497156)
		(end 168.03633 91.997157)
		(width 0.15)
		(layer "F.Cu")
		(net 465)
	)
	(segment
		(start 167.536329 93.497156)
		(end 167.036329 92.997157)
		(width 0.15)
		(layer "F.Cu")
		(net 465)
	)
	(segment
		(start 168.536329 98.497157)
		(end 168.036329 98.997157)
		(width 0.15)
		(layer "F.Cu")
		(net 465)
	)
	(segment
		(start 166.536328 98.497157)
		(end 166.036329 98.997156)
		(width 0.15)
		(layer "F.Cu")
		(net 465)
	)
	(segment
		(start 167.536329 99.497157)
		(end 167.036329 99.997156)
		(width 0.15)
		(layer "F.Cu")
		(net 465)
	)
	(segment
		(start 165.536329 99.497156)
		(end 165.036329 99.997156)
		(width 0.15)
		(layer "F.Cu")
		(net 465)
	)
	(segment
		(start 171.536329 99.497156)
		(end 172.036329 99.997156)
		(width 0.15)
		(layer "F.Cu")
		(net 465)
	)
	(segment
		(start 169.536329 99.497157)
		(end 170.036329 99.997156)
		(width 0.15)
		(layer "F.Cu")
		(net 465)
	)
	(segment
		(start 171.536329 97.497157)
		(end 172.036329 97.997156)
		(width 0.15)
		(layer "F.Cu")
		(net 465)
	)
	(segment
		(start 170.53633 98.497157)
		(end 171.036329 98.997156)
		(width 0.15)
		(layer "F.Cu")
		(net 465)
	)
	(segment
		(start 143.6825 85.2)
		(end 144.675 85.2)
		(width 0.15)
		(layer "F.Cu")
		(net 465)
	)
	(segment
		(start 143.0325 85.2)
		(end 143.6825 85.2)
		(width 0.2)
		(layer "F.Cu")
		(net 465)
	)
	(via
		(at 165.036329 97.997156)
		(size 0.5)
		(drill 0.2)
		(layers "F.Cu" "B.Cu")
		(net 465)
	)
	(via
		(at 167.036329 97.997156)
		(size 0.5)
		(drill 0.2)
		(layers "F.Cu" "B.Cu")
		(net 465)
	)
	(via
		(at 170.036329 97.997156)
		(size 0.5)
		(drill 0.2)
		(layers "F.Cu" "B.Cu")
		(net 465)
	)
	(via
		(at 172.036329 92.997156)
		(size 0.5)
		(drill 0.2)
		(layers "F.Cu" "B.Cu")
		(net 465)
	)
	(via
		(at 172.036329 94.997157)
		(size 0.5)
		(drill 0.2)
		(layers "F.Cu" "B.Cu")
		(net 465)
	)
	(via
		(at 171.036329 91.997157)
		(size 0.5)
		(drill 0.2)
		(layers "F.Cu" "B.Cu")
		(net 465)
	)
	(via
		(at 169.057 92.997157)
		(size 0.5)
		(drill 0.2)
		(layers "F.Cu" "B.Cu")
		(net 465)
	)
	(via
		(at 168.03633 91.997157)
		(size 0.5)
		(drill 0.2)
		(layers "F.Cu" "B.Cu")
		(net 465)
	)
	(via
		(at 167.036329 92.997157)
		(size 0.5)
		(drill 0.2)
		(layers "F.Cu" "B.Cu")
		(net 465)
	)
	(via
		(at 168.036329 98.997157)
		(size 0.5)
		(drill 0.2)
		(layers "F.Cu" "B.Cu")
		(net 465)
	)
	(via
		(at 166.036329 98.997156)
		(size 0.5)
		(drill 0.2)
		(layers "F.Cu" "B.Cu")
		(net 465)
	)
	(via
		(at 167.036329 99.997156)
		(size 0.5)
		(drill 0.2)
		(layers "F.Cu" "B.Cu")
		(net 465)
	)
	(via
		(at 165.036329 99.997156)
		(size 0.5)
		(drill 0.2)
		(layers "F.Cu" "B.Cu")
		(net 465)
	)
	(via
		(at 172.036329 99.997156)
		(size 0.5)
		(drill 0.2)
		(layers "F.Cu" "B.Cu")
		(net 465)
	)
	(via
		(at 170.036329 99.997156)
		(size 0.5)
		(drill 0.2)
		(layers "F.Cu" "B.Cu")
		(net 465)
	)
	(via
		(at 171.036329 98.997156)
		(size 0.5)
		(drill 0.2)
		(layers "F.Cu" "B.Cu")
		(net 465)
	)
	(via
		(at 172.036329 97.997156)
		(size 0.5)
		(drill 0.2)
		(layers "F.Cu" "B.Cu")
		(net 465)
	)
	(via
		(at 153.375 84.85)
		(size 0.5)
		(drill 0.2)
		(layers "F.Cu" "B.Cu")
		(free yes)
		(net 465)
	)
	(via
		(at 128.7825 93.75)
		(size 0.5)
		(drill 0.2)
		(layers "F.Cu" "B.Cu")
		(free yes)
		(net 465)
	)
	(via
		(at 153.075 85.35)
		(size 0.5)
		(drill 0.2)
		(layers "F.Cu" "B.Cu")
		(free yes)
		(net 465)
	)
	(via
		(at 128.1825 93.35)
		(size 0.5)
		(drill 0.2)
		(layers "F.Cu" "B.Cu")
		(free yes)
		(net 465)
	)
	(via
		(at 154.6 85.85)
		(size 0.5)
		(drill 0.2)
		(layers "F.Cu" "B.Cu")
		(free yes)
		(net 465)
	)
	(via
		(at 128.1825 94.15)
		(size 0.5)
		(drill 0.2)
		(layers "F.Cu" "B.Cu")
		(free yes)
		(net 465)
	)
	(via
		(at 153.7 85.35)
		(size 0.5)
		(drill 0.2)
		(layers "F.Cu" "B.Cu")
		(free yes)
		(net 465)
	)
	(via
		(at 154 85.85)
		(size 0.5)
		(drill 0.2)
		(layers "F.Cu" "B.Cu")
		(free yes)
		(net 465)
	)
	(via
		(at 154 84.85)
		(size 0.5)
		(drill 0.2)
		(layers "F.Cu" "B.Cu")
		(free yes)
		(net 465)
	)
	(via
		(at 129.3825 93.35)
		(size 0.5)
		(drill 0.2)
		(layers "F.Cu" "B.Cu")
		(free yes)
		(net 465)
	)
	(via
		(at 129.3825 94.15)
		(size 0.5)
		(drill 0.2)
		(layers "F.Cu" "B.Cu")
		(free yes)
		(net 465)
	)
	(via
		(at 154.6 84.85)
		(size 0.5)
		(drill 0.2)
		(layers "F.Cu" "B.Cu")
		(free yes)
		(net 465)
	)
	(via
		(at 154.3 85.35)
		(size 0.5)
		(drill 0.2)
		(layers "F.Cu" "B.Cu")
		(free yes)
		(net 465)
	)
	(via
		(at 153.375 85.85)
		(size 0.5)
		(drill 0.2)
		(layers "F.Cu" "B.Cu")
		(free yes)
		(net 465)
	)
	(via
		(at 143.6825 85.2)
		(size 0.5)
		(drill 0.2)
		(layers "F.Cu" "B.Cu")
		(net 465)
	)
	(segment
		(start 167.736328 98.317157)
		(end 167.35633 98.317157)
		(width 0.15)
		(layer "B.Cu")
		(net 465)
	)
	(segment
		(start 169.411328 97.817157)
		(end 169.85633 97.817157)
		(width 0.15)
		(layer "B.Cu")
		(net 465)
	)
	(segment
		(start 168.03633 91.997157)
		(end 168.307843 91.997157)
		(width 0.2)
		(layer "B.Cu")
		(net 465)
	)
	(segment
		(start 167.036329 99.997156)
		(end 167.036329 100.481329)
		(width 0.2)
		(layer "B.Cu")
		(net 465)
	)
	(segment
		(start 164.71633 97.677157)
		(end 165.036329 97.997156)
		(width 0.15)
		(layer "B.Cu")
		(net 465)
	)
	(segment
		(start 165.036329 100.442158)
		(end 165.216328 100.622157)
		(width 0.15)
		(layer "B.Cu")
		(net 465)
	)
	(segment
		(start 165.716328 98.677155)
		(end 166.036329 98.997156)
		(width 0.15)
		(layer "B.Cu")
		(net 465)
	)
	(segment
		(start 169.356328 92.697829)
		(end 169.057 92.997157)
		(width 0.15)
		(layer "B.Cu")
		(net 465)
	)
	(segment
		(start 164.336328 97.677157)
		(end 164.71633 97.677157)
		(width 0.15)
		(layer "B.Cu")
		(net 465)
	)
	(segment
		(start 169.411328 99.817157)
		(end 169.85633 99.817157)
		(width 0.15)
		(layer "B.Cu")
		(net 465)
	)
	(segment
		(start 172.736328 92.817157)
		(end 172.216328 92.817157)
		(width 0.15)
		(layer "B.Cu")
		(net 465)
	)
	(segment
		(start 170.716328 98.677155)
		(end 171.036329 98.997156)
		(width 0.15)
		(layer "B.Cu")
		(net 465)
	)
	(segment
		(start 165.716328 98.372157)
		(end 165.716328 98.677155)
		(width 0.15)
		(layer "B.Cu")
		(net 465)
	)
	(segment
		(start 168.216329 99.177157)
		(end 168.036329 98.997157)
		(width 0.15)
		(layer "B.Cu")
		(net 465)
	)
	(segment
		(start 173.336328 91.427157)
		(end 173.291328 91.472157)
		(width 0.15)
		(layer "B.Cu")
		(net 465)
	)
	(segment
		(start 171.831328 95.202158)
		(end 172.036329 94.997157)
		(width 0.15)
		(layer "B.Cu")
		(net 465)
	)
	(segment
		(start 168.661328 99.177157)
		(end 168.216329 99.177157)
		(width 0.15)
		(layer "B.Cu")
		(net 465)
	)
	(segment
		(start 173.291328 91.472157)
		(end 171.561329 91.472157)
		(width 0.15)
		(layer "B.Cu")
		(net 465)
	)
	(segment
		(start 172.033485 93)
		(end 172.036329 92.997156)
		(width 0.2)
		(layer "B.Cu")
		(net 465)
	)
	(segment
		(start 169.336328 93.276485)
		(end 169.057 92.997157)
		(width 0.15)
		(layer "B.Cu")
		(net 465)
	)
	(segment
		(start 171.834171 95.625)
		(end 171.831328 95.622157)
		(width 0.2)
		(layer "B.Cu")
		(net 465)
	)
	(segment
		(start 171.235 93)
		(end 172.033485 93)
		(width 0.2)
		(layer "B.Cu")
		(net 465)
	)
	(segment
		(start 172.236328 99.797157)
		(end 172.036329 99.997156)
		(width 0.15)
		(layer "B.Cu")
		(net 465)
	)
	(segment
		(start 169.356328 92.367157)
		(end 169.356328 92.697829)
		(width 0.15)
		(layer "B.Cu")
		(net 465)
	)
	(segment
		(start 165.036329 99.997156)
		(end 165.036329 100.442158)
		(width 0.15)
		(layer "B.Cu")
		(net 465)
	)
	(segment
		(start 172.736328 97.817157)
		(end 172.216328 97.817157)
		(width 0.15)
		(layer "B.Cu")
		(net 465)
	)
	(segment
		(start 169.85633 99.817157)
		(end 170.036329 99.997156)
		(width 0.15)
		(layer "B.Cu")
		(net 465)
	)
	(segment
		(start 169.336328 93.697157)
		(end 169.336328 93.276485)
		(width 0.15)
		(layer "B.Cu")
		(net 465)
	)
	(segment
		(start 172.836328 99.797157)
		(end 172.236328 99.797157)
		(width 0.15)
		(layer "B.Cu")
		(net 465)
	)
	(segment
		(start 167.036329 100.481329)
		(end 167.18 100.625)
		(width 0.2)
		(layer "B.Cu")
		(net 465)
	)
	(segment
		(start 169.85633 97.817157)
		(end 170.036329 97.997156)
		(width 0.15)
		(layer "B.Cu")
		(net 465)
	)
	(segment
		(start 171.831328 95.622157)
		(end 171.831328 95.202158)
		(width 0.15)
		(layer "B.Cu")
		(net 465)
	)
	(segment
		(start 172.216328 92.817157)
		(end 172.036329 92.997156)
		(width 0.15)
		(layer "B.Cu")
		(net 465)
	)
	(segment
		(start 167.35633 98.317157)
		(end 167.036329 97.997156)
		(width 0.15)
		(layer "B.Cu")
		(net 465)
	)
	(segment
		(start 170.716328 98.297157)
		(end 170.716328 98.677155)
		(width 0.15)
		(layer "B.Cu")
		(net 465)
	)
	(segment
		(start 170.055 100.015827)
		(end 170.036329 99.997156)
		(width 0.2)
		(layer "B.Cu")
		(net 465)
	)
	(segment
		(start 171.036329 91.997157)
		(end 171.561329 91.472157)
		(width 0.15)
		(layer "B.Cu")
		(net 465)
	)
	(segment
		(start 168.307843 91.997157)
		(end 168.68 91.625)
		(width 0.2)
		(layer "B.Cu")
		(net 465)
	)
	(segment
		(start 172.216328 97.817157)
		(end 172.036329 97.997156)
		(width 0.15)
		(layer "B.Cu")
		(net 465)
	)
	(segment
		(start 172.765 95.625)
		(end 171.834171 95.625)
		(width 0.2)
		(layer "B.Cu")
		(net 465)
	)
	(segment
		(start 170.055 100.75)
		(end 170.055 100.015827)
		(width 0.2)
		(layer "B.Cu")
		(net 465)
	)
	(segment
		(start 115.885 112.725)
		(end 117.075 112.725)
		(width 0.2)
		(layer "F.Cu")
		(net 466)
	)
	(segment
		(start 117.075 112.725)
		(end 117.1 112.7)
		(width 0.2)
		(layer "F.Cu")
		(net 466)
	)
	(segment
		(start 117.097157 114.697157)
		(end 117.1 114.7)
		(width 0.2)
		(layer "F.Cu")
		(net 466)
	)
	(segment
		(start 134.75 98.25)
		(end 134.75 95.625)
		(width 0.2)
		(layer "F.Cu")
		(net 466)
	)
	(segment
		(start 134.75 95.625)
		(end 135.2 95.175)
		(width 0.2)
		(layer "F.Cu")
		(net 466)
	)
	(segment
		(start 135.2 95.175)
		(end 136.024143 95.175)
		(width 0.2)
		(layer "F.Cu")
		(net 466)
	)
	(segment
		(start 116.286328 114.697157)
		(end 117.097157 114.697157)
		(width 0.2)
		(layer "F.Cu")
		(net 466)
	)
	(via
		(at 117.1 112.7)
		(size 0.5)
		(drill 0.2)
		(layers "F.Cu" "B.Cu")
		(net 466)
	)
	(via
		(at 117.1 114.7)
		(size 0.5)
		(drill 0.2)
		(layers "F.Cu" "B.Cu")
		(net 466)
	)
	(via
		(at 134.75 98.25)
		(size 0.5)
		(drill 0.2)
		(layers "F.Cu" "B.Cu")
		(net 466)
	)
	(segment
		(start 131.4 101.6)
		(end 131.4 105.2)
		(width 0.2)
		(layer "In2.Cu")
		(net 466)
	)
	(segment
		(start 134.75 98.25)
		(end 131.4 101.6)
		(width 0.2)
		(layer "In2.Cu")
		(net 466)
	)
	(segment
		(start 118.1 106.3)
		(end 117.1 107.3)
		(width 0.2)
		(layer "In2.Cu")
		(net 466)
	)
	(segment
		(start 131.4 105.2)
		(end 130.3 106.3)
		(width 0.2)
		(layer "In2.Cu")
		(net 466)
	)
	(segment
		(start 130.3 106.3)
		(end 118.1 106.3)
		(width 0.2)
		(layer "In2.Cu")
		(net 466)
	)
	(segment
		(start 117.1 107.3)
		(end 117.1 112.7)
		(width 0.2)
		(layer "In2.Cu")
		(net 466)
	)
	(segment
		(start 117.1 112.7)
		(end 117.1 114.7)
		(width 0.2)
		(layer "In2.Cu")
		(net 466)
	)
	(segment
		(start 130.4675 101.55)
		(end 130.4675 102.1675)
		(width 0.15)
		(layer "F.Cu")
		(net 468)
	)
	(segment
		(start 141.85 94.525)
		(end 142.625 93.75)
		(width 0.2)
		(layer "F.Cu")
		(net 468)
	)
	(segment
		(start 139.025 94.525)
		(end 139 94.5)
		(width 0.2)
		(layer "F.Cu")
		(net 468)
	)
	(segment
		(start 130.4675 102.1675)
		(end 130.5 102.2)
		(width 0.15)
		(layer "F.Cu")
		(net 468)
	)
	(segment
		(start 140.225857 94.525)
		(end 139.025 94.525)
		(width 0.2)
		(layer "F.Cu")
		(net 468)
	)
	(segment
		(start 140.225857 94.525)
		(end 141.85 94.525)
		(width 0.2)
		(layer "F.Cu")
		(net 468)
	)
	(via
		(at 130.5 102.2)
		(size 0.5)
		(drill 0.2)
		(layers "F.Cu" "B.Cu")
		(net 468)
	)
	(via
		(at 139 94.5)
		(size 0.5)
		(drill 0.2)
		(layers "F.Cu" "B.Cu")
		(net 468)
	)
	(segment
		(start 139.806336 94.5)
		(end 140.536328 93.770008)
		(width 0.2)
		(layer "B.Cu")
		(net 468)
	)
	(segment
		(start 140.536328 93.770008)
		(end 140.536328 92.855008)
		(width 0.2)
		(layer "B.Cu")
		(net 468)
	)
	(segment
		(start 139 94.5)
		(end 139.806336 94.5)
		(width 0.2)
		(layer "B.Cu")
		(net 468)
	)
	(segment
		(start 130.5 102.2)
		(end 132.2 102.2)
		(width 0.15)
		(layer "In5.Cu")
		(net 468)
	)
	(segment
		(start 132.2 102.2)
		(end 134.2 100.2)
		(width 0.15)
		(layer "In5.Cu")
		(net 468)
	)
	(segment
		(start 136.1 94.5)
		(end 139 94.5)
		(width 0.15)
		(layer "In5.Cu")
		(net 468)
	)
	(segment
		(start 134.2 96.4)
		(end 136.1 94.5)
		(width 0.15)
		(layer "In5.Cu")
		(net 468)
	)
	(segment
		(start 134.2 100.2)
		(end 134.2 96.4)
		(width 0.15)
		(layer "In5.Cu")
		(net 468)
	)
	(segment
		(start 141.51552 95.1992)
		(end 141.49132 95.175)
		(width 0.2)
		(layer "F.Cu")
		(net 469)
	)
	(segment
		(start 142.625 95.1992)
		(end 141.51552 95.1992)
		(width 0.2)
		(layer "F.Cu")
		(net 469)
	)
	(segment
		(start 140.225857 95.175)
		(end 141.49132 95.175)
		(width 0.2)
		(layer "F.Cu")
		(net 469)
	)
	(segment
		(start 118.825 90.075)
		(end 118.85 90.05)
		(width 0.15)
		(layer "F.Cu")
		(net 469)
	)
	(segment
		(start 118.182806 90.075)
		(end 118.825 90.075)
		(width 0.15)
		(layer "F.Cu")
		(net 469)
	)
	(via
		(at 141.49132 95.175)
		(size 0.5)
		(drill 0.2)
		(layers "F.Cu" "B.Cu")
		(net 469)
	)
	(via
		(at 118.85 90.05)
		(size 0.5)
		(drill 0.2)
		(layers "F.Cu" "B.Cu")
		(net 469)
	)
	(segment
		(start 131.1 94.9)
		(end 131.375 95.175)
		(width 0.15)
		(layer "B.Cu")
		(net 469)
	)
	(segment
		(start 130.8 92)
		(end 131.1 92.3)
		(width 0.15)
		(layer "B.Cu")
		(net 469)
	)
	(segment
		(start 119.6 92)
		(end 130.8 92)
		(width 0.15)
		(layer "B.Cu")
		(net 469)
	)
	(segment
		(start 141.49132 92.950016)
		(end 141.49132 95.175)
		(width 0.2)
		(layer "B.Cu")
		(net 469)
	)
	(segment
		(start 131.375 95.175)
		(end 141.49132 95.175)
		(width 0.15)
		(layer "B.Cu")
		(net 469)
	)
	(segment
		(start 131.1 92.3)
		(end 131.1 94.9)
		(width 0.15)
		(layer "B.Cu")
		(net 469)
	)
	(segment
		(start 118.85 90.05)
		(end 118.85 91.25)
		(width 0.15)
		(layer "B.Cu")
		(net 469)
	)
	(segment
		(start 141.586328 92.855008)
		(end 141.49132 92.950016)
		(width 0.2)
		(layer "B.Cu")
		(net 469)
	)
	(segment
		(start 118.85 91.25)
		(end 119.6 92)
		(width 0.15)
		(layer "B.Cu")
		(net 469)
	)
	(segment
		(start 135.115 59.7)
		(end 134.2 59.7)
		(width 0.15)
		(layer "F.Cu")
		(net 470)
	)
	(segment
		(start 140.225857 95.825)
		(end 141.575 95.825)
		(width 0.2)
		(layer "F.Cu")
		(net 470)
	)
	(segment
		(start 142.5 96.8242)
		(end 142.5 96.75)
		(width 0.2)
		(layer "F.Cu")
		(net 470)
	)
	(segment
		(start 142.5 96.75)
		(end 141.77817 96.02817)
		(width 0.2)
		(layer "F.Cu")
		(net 470)
	)
	(segment
		(start 141.575 95.825)
		(end 141.77817 96.02817)
		(width 0.2)
		(layer "F.Cu")
		(net 470)
	)
	(segment
		(start 185 118.67)
		(end 185 119.3)
		(width 0.15)
		(layer "F.Cu")
		(net 470)
	)
	(segment
		(start 119.35 101.55)
		(end 118.76 101.55)
		(width 0.15)
		(layer "F.Cu")
		(net 470)
	)
	(via
		(at 119.35 101.55)
		(size 0.5)
		(drill 0.2)
		(layers "F.Cu" "B.Cu")
		(net 470)
	)
	(via
		(at 134.2 59.7)
		(size 0.5)
		(drill 0.2)
		(layers "F.Cu" "B.Cu")
		(net 470)
	)
	(via
		(at 141.77817 96.02817)
		(size 0.5)
		(drill 0.2)
		(layers "F.Cu" "B.Cu")
		(net 470)
	)
	(via
		(at 185 119.3)
		(size 0.5)
		(drill 0.2)
		(layers "F.Cu" "B.Cu")
		(net 470)
	)
	(via
		(at 128.35 58.7)
		(size 0.5)
		(drill 0.2)
		(layers "F.Cu" "B.Cu")
		(net 470)
	)
	(segment
		(start 121 96.040016)
		(end 121 96)
		(width 0.15)
		(layer "B.Cu")
		(net 470)
	)
	(segment
		(start 119.4 89.3)
		(end 119.4 63.460829)
		(width 0.15)
		(layer "B.Cu")
		(net 470)
	)
	(segment
		(start 142.536328 95.270012)
		(end 142.536328 92.855008)
		(width 0.2)
		(layer "B.Cu")
		(net 470)
	)
	(segment
		(start 121 101)
		(end 120.45 101.55)
		(width 0.15)
		(layer "B.Cu")
		(net 470)
	)
	(segment
		(start 120.820008 95.820008)
		(end 135.929992 95.820008)
		(width 0.15)
		(layer "B.Cu")
		(net 470)
	)
	(segment
		(start 121 96)
		(end 120.820008 95.820008)
		(width 0.15)
		(layer "B.Cu")
		(net 470)
	)
	(segment
		(start 120.45 101.55)
		(end 119.35 101.55)
		(width 0.15)
		(layer "B.Cu")
		(net 470)
	)
	(segment
		(start 124.463603 58)
		(end 127.65 58)
		(width 0.15)
		(layer "B.Cu")
		(net 470)
	)
	(segment
		(start 135.929992 95.820008)
		(end 141.570008 95.820008)
		(width 0.2)
		(layer "B.Cu")
		(net 470)
	)
	(segment
		(start 118.55 89.55)
		(end 119.15 89.55)
		(width 0.15)
		(layer "B.Cu")
		(net 470)
	)
	(segment
		(start 118.3 89.8)
		(end 118.55 89.55)
		(width 0.15)
		(layer "B.Cu")
		(net 470)
	)
	(segment
		(start 118.3 95.1)
		(end 118.3 89.8)
		(width 0.15)
		(layer "B.Cu")
		(net 470)
	)
	(segment
		(start 123.547157 59.313672)
		(end 123.547157 58.916446)
		(width 0.15)
		(layer "B.Cu")
		(net 470)
	)
	(segment
		(start 123.547157 58.916446)
		(end 124.463603 58)
		(width 0.15)
		(layer "B.Cu")
		(net 470)
	)
	(segment
		(start 127.65 58)
		(end 128.35 58.7)
		(width 0.15)
		(layer "B.Cu")
		(net 470)
	)
	(segment
		(start 121.179992 95.820008)
		(end 121 96)
		(width 0.15)
		(layer "B.Cu")
		(net 470)
	)
	(segment
		(start 119.15 89.55)
		(end 119.4 89.3)
		(width 0.15)
		(layer "B.Cu")
		(net 470)
	)
	(segment
		(start 141.77817 96.02817)
		(end 142.536328 95.270012)
		(width 0.2)
		(layer "B.Cu")
		(net 470)
	)
	(segment
		(start 120.820008 95.820008)
		(end 119.020008 95.820008)
		(width 0.15)
		(layer "B.Cu")
		(net 470)
	)
	(segment
		(start 141.570008 95.820008)
		(end 141.77817 96.02817)
		(width 0.2)
		(layer "B.Cu")
		(net 470)
	)
	(segment
		(start 121 101)
		(end 121 96.040016)
		(width 0.15)
		(layer "B.Cu")
		(net 470)
	)
	(segment
		(start 119.020008 95.820008)
		(end 118.3 95.1)
		(width 0.15)
		(layer "B.Cu")
		(net 470)
	)
	(segment
		(start 119.4 63.460829)
		(end 123.547157 59.313672)
		(width 0.15)
		(layer "B.Cu")
		(net 470)
	)
	(segment
		(start 142.1 122.2)
		(end 142.6 122.7)
		(width 0.15)
		(layer "In5.Cu")
		(net 470)
	)
	(segment
		(start 181.6 122.7)
		(end 185 119.3)
		(width 0.15)
		(layer "In5.Cu")
		(net 470)
	)
	(segment
		(start 141.77817 96.02817)
		(end 141.82817 96.02817)
		(width 0.15)
		(layer "In5.Cu")
		(net 470)
	)
	(segment
		(start 142.6 122.7)
		(end 181.6 122.7)
		(width 0.15)
		(layer "In5.Cu")
		(net 470)
	)
	(segment
		(start 134.2 59.7)
		(end 129.35 59.7)
		(width 0.15)
		(layer "In5.Cu")
		(net 470)
	)
	(segment
		(start 142.1 96.3)
		(end 142.1 122.2)
		(width 0.15)
		(layer "In5.Cu")
		(net 470)
	)
	(segment
		(start 141.82817 96.02817)
		(end 142.1 96.3)
		(width 0.15)
		(layer "In5.Cu")
		(net 470)
	)
	(segment
		(start 129.35 59.7)
		(end 128.35 58.7)
		(width 0.15)
		(layer "In5.Cu")
		(net 470)
	)
	(segment
		(start 158.536329 95.497156)
		(end 158.036329 94.997157)
		(width 0.15)
		(layer "F.Cu")
		(net 479)
	)
	(segment
		(start 152.036328 78.847157)
		(end 152.036328 80.997157)
		(width 0.15)
		(layer "F.Cu")
		(net 479)
	)
	(via blind
		(at 158.036329 94.997157)
		(size 0.5)
		(drill 0.2)
		(layers "F.Cu" "In2.Cu")
		(net 479)
	)
	(via
		(at 152.036328 80.997157)
		(size 0.5)
		(drill 0.2)
		(layers "F.Cu" "B.Cu")
		(net 479)
	)
	(segment
		(start 152.036328 89.227157)
		(end 152.036328 80.997157)
		(width 0.1)
		(layer "In2.Cu")
		(net 479)
	)
	(segment
		(start 157.806328 94.997157)
		(end 152.036328 89.227157)
		(width 0.1)
		(layer "In2.Cu")
		(net 479)
	)
	(segment
		(start 158.036329 94.997157)
		(end 157.806328 94.997157)
		(width 0.1)
		(layer "In2.Cu")
		(net 479)
	)
	(segment
		(start 158.536329 94.497156)
		(end 158.036329 93.997157)
		(width 0.15)
		(layer "F.Cu")
		(net 480)
	)
	(segment
		(start 152.536328 78.847157)
		(end 152.536328 80.497157)
		(width 0.15)
		(layer "F.Cu")
		(net 480)
	)
	(via blind
		(at 158.036329 93.997157)
		(size 0.5)
		(drill 0.2)
		(layers "F.Cu" "In2.Cu")
		(net 480)
	)
	(via
		(at 152.536328 80.497157)
		(size 0.5)
		(drill 0.2)
		(layers "F.Cu" "B.Cu")
		(net 480)
	)
	(segment
		(start 157.266328 93.997157)
		(end 152.536328 89.267157)
		(width 0.1)
		(layer "In2.Cu")
		(net 480)
	)
	(segment
		(start 158.036329 93.997157)
		(end 157.266328 93.997157)
		(width 0.1)
		(layer "In2.Cu")
		(net 480)
	)
	(segment
		(start 152.536328 89.267157)
		(end 152.536328 80.497157)
		(width 0.1)
		(layer "In2.Cu")
		(net 480)
	)
	(segment
		(start 159.536329 95.497156)
		(end 159.036329 94.997157)
		(width 0.15)
		(layer "F.Cu")
		(net 481)
	)
	(segment
		(start 151.536328 78.847157)
		(end 151.536328 80.497157)
		(width 0.15)
		(layer "F.Cu")
		(net 481)
	)
	(via blind
		(at 159.036329 94.997157)
		(size 0.5)
		(drill 0.2)
		(layers "F.Cu" "In2.Cu")
		(net 481)
	)
	(via
		(at 151.536328 80.497157)
		(size 0.5)
		(drill 0.2)
		(layers "F.Cu" "B.Cu")
		(net 481)
	)
	(segment
		(start 157.816306 95.497135)
		(end 151.536328 89.217157)
		(width 0.1)
		(layer "In2.Cu")
		(net 481)
	)
	(segment
		(start 159.036329 94.997157)
		(end 158.536351 95.497135)
		(width 0.1)
		(layer "In2.Cu")
		(net 481)
	)
	(segment
		(start 151.536328 89.217157)
		(end 151.536328 80.497157)
		(width 0.1)
		(layer "In2.Cu")
		(net 481)
	)
	(segment
		(start 158.536351 95.497135)
		(end 157.816306 95.497135)
		(width 0.1)
		(layer "In2.Cu")
		(net 481)
	)
	(segment
		(start 160.536329 95.497156)
		(end 160.036329 94.997157)
		(width 0.15)
		(layer "F.Cu")
		(net 482)
	)
	(segment
		(start 151.036328 78.847157)
		(end 151.036328 80.997157)
		(width 0.15)
		(layer "F.Cu")
		(net 482)
	)
	(via blind
		(at 160.036329 94.997157)
		(size 0.5)
		(drill 0.2)
		(layers "F.Cu" "In2.Cu")
		(net 482)
	)
	(via
		(at 151.036328 80.997157)
		(size 0.5)
		(drill 0.2)
		(layers "F.Cu" "B.Cu")
		(net 482)
	)
	(segment
		(start 151.036328 80.997157)
		(end 151.036328 89.187157)
		(width 0.1)
		(layer "In2.Cu")
		(net 482)
	)
	(segment
		(start 151.036328 89.187157)
		(end 157.596317 95.747146)
		(width 0.1)
		(layer "In2.Cu")
		(net 482)
	)
	(segment
		(start 159.28634 95.747146)
		(end 160.036329 94.997157)
		(width 0.1)
		(layer "In2.Cu")
		(net 482)
	)
	(segment
		(start 157.596317 95.747146)
		(end 159.28634 95.747146)
		(width 0.1)
		(layer "In2.Cu")
		(net 482)
	)
	(segment
		(start 161.536329 95.497156)
		(end 161.036329 94.997157)
		(width 0.15)
		(layer "F.Cu")
		(net 483)
	)
	(segment
		(start 150.536328 78.847157)
		(end 150.536328 80.497157)
		(width 0.15)
		(layer "F.Cu")
		(net 483)
	)
	(via blind
		(at 161.036329 94.997157)
		(size 0.5)
		(drill 0.2)
		(layers "F.Cu" "In2.Cu")
		(net 483)
	)
	(via
		(at 150.536328 80.497157)
		(size 0.5)
		(drill 0.2)
		(layers "F.Cu" "B.Cu")
		(net 483)
	)
	(segment
		(start 150.536328 89.167157)
		(end 150.536328 80.497157)
		(width 0.1)
		(layer "In2.Cu")
		(net 483)
	)
	(segment
		(start 161.036329 94.997157)
		(end 160.036329 95.997157)
		(width 0.1)
		(layer "In2.Cu")
		(net 483)
	)
	(segment
		(start 160.036329 95.997157)
		(end 157.366328 95.997157)
		(width 0.1)
		(layer "In2.Cu")
		(net 483)
	)
	(segment
		(start 157.366328 95.997157)
		(end 150.536328 89.167157)
		(width 0.1)
		(layer "In2.Cu")
		(net 483)
	)
	(segment
		(start 160.536327 96.497157)
		(end 161.036328 95.997157)
		(width 0.15)
		(layer "F.Cu")
		(net 484)
	)
	(segment
		(start 150.036328 78.847157)
		(end 150.036328 80.997157)
		(width 0.15)
		(layer "F.Cu")
		(net 484)
	)
	(via blind
		(at 161.036328 95.997157)
		(size 0.5)
		(drill 0.2)
		(layers "F.Cu" "In2.Cu")
		(net 484)
	)
	(via
		(at 150.036328 80.997157)
		(size 0.5)
		(drill 0.2)
		(layers "F.Cu" "B.Cu")
		(net 484)
	)
	(segment
		(start 157.166328 96.247157)
		(end 160.786328 96.247157)
		(width 0.1)
		(layer "In2.Cu")
		(net 484)
	)
	(segment
		(start 160.786328 96.247157)
		(end 161.036328 95.997157)
		(width 0.1)
		(layer "In2.Cu")
		(net 484)
	)
	(segment
		(start 150.036328 80.997157)
		(end 150.036328 89.117157)
		(width 0.1)
		(layer "In2.Cu")
		(net 484)
	)
	(segment
		(start 150.036328 89.117157)
		(end 157.166328 96.247157)
		(width 0.1)
		(layer "In2.Cu")
		(net 484)
	)
	(segment
		(start 161.536327 96.497157)
		(end 162.036327 95.997157)
		(width 0.15)
		(layer "F.Cu")
		(net 485)
	)
	(segment
		(start 149.536328 78.847157)
		(end 149.536328 80.497157)
		(width 0.15)
		(layer "F.Cu")
		(net 485)
	)
	(via blind
		(at 162.036327 95.997157)
		(size 0.5)
		(drill 0.2)
		(layers "F.Cu" "In2.Cu")
		(net 485)
	)
	(via
		(at 149.536328 80.497157)
		(size 0.5)
		(drill 0.2)
		(layers "F.Cu" "B.Cu")
		(net 485)
	)
	(segment
		(start 149.536328 89.067157)
		(end 149.536328 80.497157)
		(width 0.1)
		(layer "In2.Cu")
		(net 485)
	)
	(segment
		(start 162.036327 95.997157)
		(end 161.536327 96.497157)
		(width 0.1)
		(layer "In2.Cu")
		(net 485)
	)
	(segment
		(start 161.536327 96.497157)
		(end 156.966328 96.497157)
		(width 0.1)
		(layer "In2.Cu")
		(net 485)
	)
	(segment
		(start 156.966328 96.497157)
		(end 149.536328 89.067157)
		(width 0.1)
		(layer "In2.Cu")
		(net 485)
	)
	(segment
		(start 162.536327 96.497157)
		(end 163.036327 95.997157)
		(width 0.15)
		(layer "F.Cu")
		(net 486)
	)
	(segment
		(start 149.036328 78.847157)
		(end 149.036328 80.997157)
		(width 0.15)
		(layer "F.Cu")
		(net 486)
	)
	(via blind
		(at 163.036327 95.997157)
		(size 0.5)
		(drill 0.2)
		(layers "F.Cu" "In2.Cu")
		(net 486)
	)
	(via
		(at 149.036328 80.997157)
		(size 0.5)
		(drill 0.2)
		(layers "F.Cu" "B.Cu")
		(net 486)
	)
	(segment
		(start 162.286327 96.747157)
		(end 156.796328 96.747157)
		(width 0.1)
		(layer "In2.Cu")
		(net 486)
	)
	(segment
		(start 156.796328 96.747157)
		(end 149.036328 88.987157)
		(width 0.1)
		(layer "In2.Cu")
		(net 486)
	)
	(segment
		(start 149.036328 88.987157)
		(end 149.036328 80.997157)
		(width 0.1)
		(layer "In2.Cu")
		(net 486)
	)
	(segment
		(start 163.036327 95.997157)
		(end 162.286327 96.747157)
		(width 0.1)
		(layer "In2.Cu")
		(net 486)
	)
	(segment
		(start 163.536326 96.497157)
		(end 164.036327 95.997157)
		(width 0.15)
		(layer "F.Cu")
		(net 487)
	)
	(segment
		(start 148.536328 78.847157)
		(end 148.536328 80.497157)
		(width 0.15)
		(layer "F.Cu")
		(net 487)
	)
	(via blind
		(at 164.036327 95.997157)
		(size 0.5)
		(drill 0.2)
		(layers "F.Cu" "In2.Cu")
		(net 487)
	)
	(via
		(at 148.536328 80.497157)
		(size 0.5)
		(drill 0.2)
		(layers "F.Cu" "B.Cu")
		(net 487)
	)
	(segment
		(start 148.536328 88.957157)
		(end 148.536328 80.497157)
		(width 0.1)
		(layer "In2.Cu")
		(net 487)
	)
	(segment
		(start 164.036327 95.997157)
		(end 163.036327 96.997157)
		(width 0.1)
		(layer "In2.Cu")
		(net 487)
	)
	(segment
		(start 156.576328 96.997157)
		(end 148.536328 88.957157)
		(width 0.1)
		(layer "In2.Cu")
		(net 487)
	)
	(segment
		(start 163.036327 96.997157)
		(end 156.576328 96.997157)
		(width 0.1)
		(layer "In2.Cu")
		(net 487)
	)
	(segment
		(start 162.526329 101.507156)
		(end 162.026329 101.007157)
		(width 0.15)
		(layer "F.Cu")
		(net 488)
	)
	(segment
		(start 148.712399 96.290001)
		(end 149.212399 96.79)
		(width 0.15)
		(layer "F.Cu")
		(net 488)
	)
	(segment
		(start 148.8948 93.5228)
		(end 148.8948 92.837)
		(width 0.1)
		(layer "F.Cu")
		(net 488)
	)
	(segment
		(start 148.082 94.3356)
		(end 148.8948 93.5228)
		(width 0.1)
		(layer "F.Cu")
		(net 488)
	)
	(segment
		(start 148.082 95.9866)
		(end 148.082 94.3356)
		(width 0.1)
		(layer "F.Cu")
		(net 488)
	)
	(segment
		(start 148.372557 96.277157)
		(end 148.082 95.9866)
		(width 0.1)
		(layer "F.Cu")
		(net 488)
	)
	(segment
		(start 148.696328 96.277157)
		(end 148.372557 96.277157)
		(width 0.1)
		(layer "F.Cu")
		(net 488)
	)
	(via blind
		(at 162.026329 101.007157)
		(size 0.5)
		(drill 0.2)
		(layers "F.Cu" "In2.Cu")
		(net 488)
	)
	(via blind
		(at 149.212399 96.79)
		(size 0.5)
		(drill 0.2)
		(layers "F.Cu" "In2.Cu")
		(net 488)
	)
	(segment
		(start 161.586328 101.447158)
		(end 150.773958 101.447158)
		(width 0.1)
		(layer "In2.Cu")
		(net 488)
	)
	(segment
		(start 148.6154 99.2886)
		(end 148.6154 97.386999)
		(width 0.1)
		(layer "In2.Cu")
		(net 488)
	)
	(segment
		(start 162.026329 101.007157)
		(end 161.586328 101.447158)
		(width 0.1)
		(layer "In2.Cu")
		(net 488)
	)
	(segment
		(start 150.773958 101.447158)
		(end 148.6154 99.2886)
		(width 0.1)
		(layer "In2.Cu")
		(net 488)
	)
	(segment
		(start 148.6154 97.386999)
		(end 149.212399 96.79)
		(width 0.1)
		(layer "In2.Cu")
		(net 488)
	)
	(segment
		(start 159.546327 100.487156)
		(end 159.046328 100.987156)
		(width 0.15)
		(layer "F.Cu")
		(net 489)
	)
	(segment
		(start 148.1328 97.282)
		(end 148.6916 97.282)
		(width 0.1)
		(layer "F.Cu")
		(net 489)
	)
	(segment
		(start 148.686999 97.280601)
		(end 149.186999 97.7806)
		(width 0.15)
		(layer "F.Cu")
		(net 489)
	)
	(segment
		(start 147.8026 96.9518)
		(end 148.1328 97.282)
		(width 0.1)
		(layer "F.Cu")
		(net 489)
	)
	(segment
		(start 147.8026 92.8902)
		(end 147.8026 96.9518)
		(width 0.1)
		(layer "F.Cu")
		(net 489)
	)
	(via blind
		(at 159.046328 100.987156)
		(size 0.5)
		(drill 0.2)
		(layers "F.Cu" "In2.Cu")
		(net 489)
	)
	(via blind
		(at 149.186999 97.7806)
		(size 0.5)
		(drill 0.2)
		(layers "F.Cu" "In2.Cu")
		(net 489)
	)
	(segment
		(start 149.279293 98.947788)
		(end 149.289009 98.967963)
		(width 0.1)
		(layer "In2.Cu")
		(net 489)
	)
	(segment
		(start 149.320478 98.999431)
		(end 149.340653 99.009147)
		(width 0.1)
		(layer "In2.Cu")
		(net 489)
	)
	(segment
		(start 149.444392 98.98547)
		(end 149.515904 98.913957)
		(width 0.1)
		(layer "In2.Cu")
		(net 489)
	)
	(segment
		(start 149.597811 98.885296)
		(end 149.619643 98.890279)
		(width 0.1)
		(layer "In2.Cu")
		(net 489)
	)
	(segment
		(start 149.403144 98.69063)
		(end 149.403144 98.713023)
		(width 0.1)
		(layer "In2.Cu")
		(net 489)
	)
	(segment
		(start 149.374484 98.772537)
		(end 149.302971 98.844049)
		(width 0.1)
		(layer "In2.Cu")
		(net 489)
	)
	(segment
		(start 149.374484 98.631116)
		(end 149.388445 98.648623)
		(width 0.1)
		(layer "In2.Cu")
		(net 489)
	)
	(segment
		(start 149.362485 99.01413)
		(end 149.384878 99.01413)
		(width 0.1)
		(layer "In2.Cu")
		(net 489)
	)
	(segment
		(start 149.186999 98.443631)
		(end 149.374484 98.631116)
		(width 0.1)
		(layer "In2.Cu")
		(net 489)
	)
	(segment
		(start 149.639818 98.899995)
		(end 149.657326 98.913958)
		(width 0.1)
		(layer "In2.Cu")
		(net 489)
	)
	(segment
		(start 149.289009 98.967963)
		(end 149.302971 98.98547)
		(width 0.1)
		(layer "In2.Cu")
		(net 489)
	)
	(segment
		(start 149.279293 98.881732)
		(end 149.27431 98.903563)
		(width 0.1)
		(layer "In2.Cu")
		(net 489)
	)
	(segment
		(start 149.553587 98.890279)
		(end 149.575418 98.885296)
		(width 0.1)
		(layer "In2.Cu")
		(net 489)
	)
	(segment
		(start 149.27431 98.925956)
		(end 149.279293 98.947788)
		(width 0.1)
		(layer "In2.Cu")
		(net 489)
	)
	(segment
		(start 149.340653 99.009147)
		(end 149.362485 99.01413)
		(width 0.1)
		(layer "In2.Cu")
		(net 489)
	)
	(segment
		(start 149.403144 98.713023)
		(end 149.398161 98.734854)
		(width 0.1)
		(layer "In2.Cu")
		(net 489)
	)
	(segment
		(start 149.27431 98.903563)
		(end 149.27431 98.925956)
		(width 0.1)
		(layer "In2.Cu")
		(net 489)
	)
	(segment
		(start 149.289009 98.861557)
		(end 149.279293 98.881732)
		(width 0.1)
		(layer "In2.Cu")
		(net 489)
	)
	(segment
		(start 149.302971 98.844049)
		(end 149.289009 98.861557)
		(width 0.1)
		(layer "In2.Cu")
		(net 489)
	)
	(segment
		(start 149.398161 98.734854)
		(end 149.388445 98.755029)
		(width 0.1)
		(layer "In2.Cu")
		(net 489)
	)
	(segment
		(start 149.619643 98.890279)
		(end 149.639818 98.899995)
		(width 0.1)
		(layer "In2.Cu")
		(net 489)
	)
	(segment
		(start 149.657326 98.913958)
		(end 151.730524 100.987156)
		(width 0.1)
		(layer "In2.Cu")
		(net 489)
	)
	(segment
		(start 149.406709 99.009147)
		(end 149.426884 98.999431)
		(width 0.1)
		(layer "In2.Cu")
		(net 489)
	)
	(segment
		(start 149.302971 98.98547)
		(end 149.320478 98.999431)
		(width 0.1)
		(layer "In2.Cu")
		(net 489)
	)
	(segment
		(start 149.575418 98.885296)
		(end 149.597811 98.885296)
		(width 0.1)
		(layer "In2.Cu")
		(net 489)
	)
	(segment
		(start 151.730524 100.987156)
		(end 159.046328 100.987156)
		(width 0.1)
		(layer "In2.Cu")
		(net 489)
	)
	(segment
		(start 149.388445 98.648623)
		(end 149.398161 98.668798)
		(width 0.1)
		(layer "In2.Cu")
		(net 489)
	)
	(segment
		(start 149.515904 98.913957)
		(end 149.533412 98.899995)
		(width 0.1)
		(layer "In2.Cu")
		(net 489)
	)
	(segment
		(start 149.384878 99.01413)
		(end 149.406709 99.009147)
		(width 0.1)
		(layer "In2.Cu")
		(net 489)
	)
	(segment
		(start 149.533412 98.899995)
		(end 149.553587 98.890279)
		(width 0.1)
		(layer "In2.Cu")
		(net 489)
	)
	(segment
		(start 149.186999 97.7806)
		(end 149.186999 98.443631)
		(width 0.1)
		(layer "In2.Cu")
		(net 489)
	)
	(segment
		(start 149.398161 98.668798)
		(end 149.403144 98.69063)
		(width 0.1)
		(layer "In2.Cu")
		(net 489)
	)
	(segment
		(start 149.388445 98.755029)
		(end 149.374484 98.772537)
		(width 0.1)
		(layer "In2.Cu")
		(net 489)
	)
	(segment
		(start 149.426884 98.999431)
		(end 149.444392 98.98547)
		(width 0.1)
		(layer "In2.Cu")
		(net 489)
	)
	(segment
		(start 159.536327 99.487156)
		(end 159.036328 99.987156)
		(width 0.15)
		(layer "F.Cu")
		(net 490)
	)
	(segment
		(start 151.682327 98.266358)
		(end 152.182327 98.766357)
		(width 0.15)
		(layer "F.Cu")
		(net 490)
	)
	(via blind
		(at 159.036328 99.987156)
		(size 0.5)
		(drill 0.2)
		(layers "F.Cu" "In2.Cu")
		(net 490)
	)
	(via blind
		(at 152.182327 98.766357)
		(size 0.5)
		(drill 0.2)
		(layers "F.Cu" "In2.Cu")
		(net 490)
	)
	(segment
		(start 154.504466 99.844584)
		(end 154.518686 99.853519)
		(width 0.1)
		(layer "In2.Cu")
		(net 490)
	)
	(segment
		(start 152.407632 99.35462)
		(end 152.419777 99.379839)
		(width 0.1)
		(layer "In2.Cu")
		(net 490)
	)
	(segment
		(start 152.655115 99.731666)
		(end 152.648886 99.758955)
		(width 0.1)
		(layer "In2.Cu")
		(net 490)
	)
	(segment
		(start 152.502182 99.059919)
		(end 152.50841 99.087208)
		(width 0.1)
		(layer "In2.Cu")
		(net 490)
	)
	(segment
		(start 152.814385 99.890936)
		(end 152.839604 99.878791)
		(width 0.1)
		(layer "In2.Cu")
		(net 490)
	)
	(segment
		(start 154.304352 99.879615)
		(end 154.313287 99.865395)
		(width 0.1)
		(layer "In2.Cu")
		(net 490)
	)
	(segment
		(start 153.568741 100.149504)
		(end 153.584576 100.165339)
		(width 0.1)
		(layer "In2.Cu")
		(net 490)
	)
	(segment
		(start 154.325163 99.853519)
		(end 154.339383 99.844584)
		(width 0.1)
		(layer "In2.Cu")
		(net 490)
	)
	(segment
		(start 153.549432 100.109408)
		(end 153.556828 100.130544)
		(width 0.1)
		(layer "In2.Cu")
		(net 490)
	)
	(segment
		(start 153.193159 98.960005)
		(end 153.215045 98.977458)
		(width 0.1)
		(layer "In2.Cu")
		(net 490)
	)
	(segment
		(start 152.861488 99.861339)
		(end 153.002909 99.719917)
		(width 0.1)
		(layer "In2.Cu")
		(net 490)
	)
	(segment
		(start 153.846925 99.887156)
		(end 153.996925 99.887156)
		(width 0.1)
		(layer "In2.Cu")
		(net 490)
	)
	(segment
		(start 154.621925 99.987156)
		(end 159.036328 99.987156)
		(width 0.1)
		(layer "In2.Cu")
		(net 490)
	)
	(segment
		(start 153.794417 100.109408)
		(end 153.796925 100.087156)
		(width 0.1)
		(layer "In2.Cu")
		(net 490)
	)
	(segment
		(start 154.046925 100.087156)
		(end 154.049432 100.109408)
		(width 0.1)
		(layer "In2.Cu")
		(net 490)
	)
	(segment
		(start 152.437229 99.401724)
		(end 152.459113 99.419176)
		(width 0.1)
		(layer "In2.Cu")
		(net 490)
	)
	(segment
		(start 153.179686 99.719917)
		(end 153.446925 99.987156)
		(width 0.1)
		(layer "In2.Cu")
		(net 490)
	)
	(segment
		(start 152.484332 99.431321)
		(end 152.511621 99.437549)
		(width 0.1)
		(layer "In2.Cu")
		(net 490)
	)
	(segment
		(start 152.706596 99.878791)
		(end 152.731815 99.890936)
		(width 0.1)
		(layer "In2.Cu")
		(net 490)
	)
	(segment
		(start 153.16794 98.94786)
		(end 153.193159 98.960005)
		(width 0.1)
		(layer "In2.Cu")
		(net 490)
	)
	(segment
		(start 153.696925 100.187156)
		(end 153.719177 100.184648)
		(width 0.1)
		(layer "In2.Cu")
		(net 490)
	)
	(segment
		(start 154.240313 100.177252)
		(end 154.259273 100.165339)
		(width 0.1)
		(layer "In2.Cu")
		(net 490)
	)
	(segment
		(start 154.146925 100.187156)
		(end 154.196925 100.187156)
		(width 0.1)
		(layer "In2.Cu")
		(net 490)
	)
	(segment
		(start 153.077302 99.684091)
		(end 153.105293 99.684091)
		(width 0.1)
		(layer "In2.Cu")
		(net 490)
	)
	(segment
		(start 154.056828 100.130544)
		(end 154.068741 100.149504)
		(width 0.1)
		(layer "In2.Cu")
		(net 490)
	)
	(segment
		(start 153.112661 98.941632)
		(end 153.140651 98.941631)
		(width 0.1)
		(layer "In2.Cu")
		(net 490)
	)
	(segment
		(start 154.605235 99.985276)
		(end 154.621925 99.987156)
		(width 0.1)
		(layer "In2.Cu")
		(net 490)
	)
	(segment
		(start 154.554352 99.944698)
		(end 154.563287 99.958918)
		(width 0.1)
		(layer "In2.Cu")
		(net 490)
	)
	(segment
		(start 153.82523 99.892108)
		(end 153.835798 99.88841)
		(width 0.1)
		(layer "In2.Cu")
		(net 490)
	)
	(segment
		(start 152.490037 99.167708)
		(end 152.472585 99.189592)
		(width 0.1)
		(layer "In2.Cu")
		(net 490)
	)
	(segment
		(start 153.801876 99.915462)
		(end 153.807833 99.905982)
		(width 0.1)
		(layer "In2.Cu")
		(net 490)
	)
	(segment
		(start 152.592121 99.419176)
		(end 152.614005 99.401724)
		(width 0.1)
		(layer "In2.Cu")
		(net 490)
	)
	(segment
		(start 154.339383 99.844584)
		(end 154.355235 99.839037)
		(width 0.1)
		(layer "In2.Cu")
		(net 490)
	)
	(segment
		(start 152.50841 99.115199)
		(end 152.502182 99.142489)
		(width 0.1)
		(layer "In2.Cu")
		(net 490)
	)
	(segment
		(start 153.25087 99.079841)
		(end 153.244642 99.107131)
		(width 0.1)
		(layer "In2.Cu")
		(net 490)
	)
	(segment
		(start 154.046925 99.937156)
		(end 154.046925 100.087156)
		(width 0.1)
		(layer "In2.Cu")
		(net 490)
	)
	(segment
		(start 154.045671 99.92603)
		(end 154.046925 99.937156)
		(width 0.1)
		(layer "In2.Cu")
		(net 490)
	)
	(segment
		(start 153.584576 100.165339)
		(end 153.603536 100.177252)
		(width 0.1)
		(layer "In2.Cu")
		(net 490)
	)
	(segment
		(start 152.502182 99.142489)
		(end 152.490037 99.167708)
		(width 0.1)
		(layer "In2.Cu")
		(net 490)
	)
	(segment
		(start 153.050012 99.69032)
		(end 153.077302 99.684091)
		(width 0.1)
		(layer "In2.Cu")
		(net 490)
	)
	(segment
		(start 154.530562 99.865395)
		(end 154.539497 99.879615)
		(width 0.1)
		(layer "In2.Cu")
		(net 490)
	)
	(segment
		(start 152.684712 99.684562)
		(end 152.66726 99.706447)
		(width 0.1)
		(layer "In2.Cu")
		(net 490)
	)
	(segment
		(start 154.471925 99.837156)
		(end 154.488614 99.839037)
		(width 0.1)
		(layer "In2.Cu")
		(net 490)
	)
	(segment
		(start 153.646925 100.187156)
		(end 153.696925 100.187156)
		(width 0.1)
		(layer "In2.Cu")
		(net 490)
	)
	(segment
		(start 154.103536 100.177252)
		(end 154.124672 100.184648)
		(width 0.1)
		(layer "In2.Cu")
		(net 490)
	)
	(segment
		(start 152.648886 99.786946)
		(end 152.655115 99.814235)
		(width 0.1)
		(layer "In2.Cu")
		(net 490)
	)
	(segment
		(start 153.835798 99.88841)
		(end 153.846925 99.887156)
		(width 0.1)
		(layer "In2.Cu")
		(net 490)
	)
	(segment
		(start 154.124672 100.184648)
		(end 154.146925 100.187156)
		(width 0.1)
		(layer "In2.Cu")
		(net 490)
	)
	(segment
		(start 153.719177 100.184648)
		(end 153.740313 100.177252)
		(width 0.1)
		(layer "In2.Cu")
		(net 490)
	)
	(segment
		(start 152.539612 99.437549)
		(end 152.566902 99.431321)
		(width 0.1)
		(layer "In2.Cu")
		(net 490)
	)
	(segment
		(start 153.446925 99.987156)
		(end 153.469177 99.989663)
		(width 0.1)
		(layer "In2.Cu")
		(net 490)
	)
	(segment
		(start 154.575163 99.970794)
		(end 154.589383 99.979729)
		(width 0.1)
		(layer "In2.Cu")
		(net 490)
	)
	(segment
		(start 153.544417 100.064903)
		(end 153.549432 100.109408)
		(width 0.1)
		(layer "In2.Cu")
		(net 490)
	)
	(segment
		(start 152.50841 99.087208)
		(end 152.50841 99.115199)
		(width 0.1)
		(layer "In2.Cu")
		(net 490)
	)
	(segment
		(start 153.08537 98.94786)
		(end 153.112661 98.941632)
		(width 0.1)
		(layer "In2.Cu")
		(net 490)
	)
	(segment
		(start 153.250869 99.051849)
		(end 153.25087 99.079841)
		(width 0.1)
		(layer "In2.Cu")
		(net 490)
	)
	(segment
		(start 154.294417 100.109408)
		(end 154.296925 100.087156)
		(width 0.1)
		(layer "In2.Cu")
		(net 490)
	)
	(segment
		(start 154.259273 100.165339)
		(end 154.275108 100.149504)
		(width 0.1)
		(layer "In2.Cu")
		(net 490)
	)
	(segment
		(start 153.232497 99.13235)
		(end 153.215045 99.154234)
		(width 0.1)
		(layer "In2.Cu")
		(net 490)
	)
	(segment
		(start 153.556828 100.130544)
		(end 153.568741 100.149504)
		(width 0.1)
		(layer "In2.Cu")
		(net 490)
	)
	(segment
		(start 154.298805 99.895467)
		(end 154.304352 99.879615)
		(width 0.1)
		(layer "In2.Cu")
		(net 490)
	)
	(segment
		(start 153.81575 99.898065)
		(end 153.82523 99.892108)
		(width 0.1)
		(layer "In2.Cu")
		(net 490)
	)
	(segment
		(start 154.084576 100.165339)
		(end 154.103536 100.177252)
		(width 0.1)
		(layer "In2.Cu")
		(net 490)
	)
	(segment
		(start 154.488614 99.839037)
		(end 154.504466 99.844584)
		(width 0.1)
		(layer "In2.Cu")
		(net 490)
	)
	(segment
		(start 152.655115 99.814235)
		(end 152.66726 99.839455)
		(width 0.1)
		(layer "In2.Cu")
		(net 490)
	)
	(segment
		(start 152.839604 99.878791)
		(end 152.861488 99.861339)
		(width 0.1)
		(layer "In2.Cu")
		(net 490)
	)
	(segment
		(start 152.648886 99.758955)
		(end 152.648886 99.786946)
		(width 0.1)
		(layer "In2.Cu")
		(net 490)
	)
	(segment
		(start 153.232497 98.999342)
		(end 153.244642 99.024561)
		(width 0.1)
		(layer "In2.Cu")
		(net 490)
	)
	(segment
		(start 152.407632 99.27205)
		(end 152.401403 99.29934)
		(width 0.1)
		(layer "In2.Cu")
		(net 490)
	)
	(segment
		(start 152.182327 98.766357)
		(end 152.226126 98.766357)
		(width 0.1)
		(layer "In2.Cu")
		(net 490)
	)
	(segment
		(start 153.759273 100.165339)
		(end 153.775108 100.149504)
		(width 0.1)
		(layer "In2.Cu")
		(net 490)
	)
	(segment
		(start 153.038269 98.977459)
		(end 153.060151 98.960005)
		(width 0.1)
		(layer "In2.Cu")
		(net 490)
	)
	(segment
		(start 152.66726 99.839455)
		(end 152.684712 99.861339)
		(width 0.1)
		(layer "In2.Cu")
		(net 490)
	)
	(segment
		(start 153.525108 100.024807)
		(end 153.537021 100.043767)
		(width 0.1)
		(layer "In2.Cu")
		(net 490)
	)
	(segment
		(start 153.996925 99.887156)
		(end 154.008051 99.88841)
		(width 0.1)
		(layer "In2.Cu")
		(net 490)
	)
	(segment
		(start 152.401403 99.29934)
		(end 152.401403 99.327331)
		(width 0.1)
		(layer "In2.Cu")
		(net 490)
	)
	(segment
		(start 153.537021 100.043767)
		(end 153.544417 100.064903)
		(width 0.1)
		(layer "In2.Cu")
		(net 490)
	)
	(segment
		(start 153.787021 100.130544)
		(end 153.794417 100.109408)
		(width 0.1)
		(layer "In2.Cu")
		(net 490)
	)
	(segment
		(start 154.018619 99.892108)
		(end 154.028099 99.898065)
		(width 0.1)
		(layer "In2.Cu")
		(net 490)
	)
	(segment
		(start 153.215045 98.977458)
		(end 153.232497 98.999342)
		(width 0.1)
		(layer "In2.Cu")
		(net 490)
	)
	(segment
		(start 154.371925 99.837156)
		(end 154.471925 99.837156)
		(width 0.1)
		(layer "In2.Cu")
		(net 490)
	)
	(segment
		(start 154.296925 99.912156)
		(end 154.298805 99.895467)
		(width 0.1)
		(layer "In2.Cu")
		(net 490)
	)
	(segment
		(start 152.511621 99.437549)
		(end 152.539612 99.437549)
		(width 0.1)
		(layer "In2.Cu")
		(net 490)
	)
	(segment
		(start 154.563287 99.958918)
		(end 154.575163 99.970794)
		(width 0.1)
		(layer "In2.Cu")
		(net 490)
	)
	(segment
		(start 152.472585 99.012816)
		(end 152.490037 99.0347)
		(width 0.1)
		(layer "In2.Cu")
		(net 490)
	)
	(segment
		(start 154.008051 99.88841)
		(end 154.018619 99.892108)
		(width 0.1)
		(layer "In2.Cu")
		(net 490)
	)
	(segment
		(start 153.157801 99.702465)
		(end 153.179686 99.719917)
		(width 0.1)
		(layer "In2.Cu")
		(net 490)
	)
	(segment
		(start 152.419777 99.246831)
		(end 152.407632 99.27205)
		(width 0.1)
		(layer "In2.Cu")
		(net 490)
	)
	(segment
		(start 154.068741 100.149504)
		(end 154.084576 100.165339)
		(width 0.1)
		(layer "In2.Cu")
		(net 490)
	)
	(segment
		(start 154.036016 99.905982)
		(end 154.041973 99.915462)
		(width 0.1)
		(layer "In2.Cu")
		(net 490)
	)
	(segment
		(start 152.684712 99.861339)
		(end 152.706596 99.878791)
		(width 0.1)
		(layer "In2.Cu")
		(net 490)
	)
	(segment
		(start 154.313287 99.865395)
		(end 154.325163 99.853519)
		(width 0.1)
		(layer "In2.Cu")
		(net 490)
	)
	(segment
		(start 154.287021 100.130544)
		(end 154.294417 100.109408)
		(width 0.1)
		(layer "In2.Cu")
		(net 490)
	)
	(segment
		(start 153.060151 98.960005)
		(end 153.08537 98.94786)
		(width 0.1)
		(layer "In2.Cu")
		(net 490)
	)
	(segment
		(start 152.490037 99.0347)
		(end 152.502182 99.059919)
		(width 0.1)
		(layer "In2.Cu")
		(net 490)
	)
	(segment
		(start 153.244642 99.107131)
		(end 153.232497 99.13235)
		(width 0.1)
		(layer "In2.Cu")
		(net 490)
	)
	(segment
		(start 154.589383 99.979729)
		(end 154.605235 99.985276)
		(width 0.1)
		(layer "In2.Cu")
		(net 490)
	)
	(segment
		(start 152.731815 99.890936)
		(end 152.759104 99.897164)
		(width 0.1)
		(layer "In2.Cu")
		(net 490)
	)
	(segment
		(start 153.740313 100.177252)
		(end 153.759273 100.165339)
		(width 0.1)
		(layer "In2.Cu")
		(net 490)
	)
	(segment
		(start 152.614005 99.401724)
		(end 153.038269 98.977459)
		(width 0.1)
		(layer "In2.Cu")
		(net 490)
	)
	(segment
		(start 153.469177 99.989663)
		(end 153.490313 99.997059)
		(width 0.1)
		(layer "In2.Cu")
		(net 490)
	)
	(segment
		(start 152.566902 99.431321)
		(end 152.592121 99.419176)
		(width 0.1)
		(layer "In2.Cu")
		(net 490)
	)
	(segment
		(start 153.796925 99.937156)
		(end 153.798178 99.92603)
		(width 0.1)
		(layer "In2.Cu")
		(net 490)
	)
	(segment
		(start 154.355235 99.839037)
		(end 154.371925 99.837156)
		(width 0.1)
		(layer "In2.Cu")
		(net 490)
	)
	(segment
		(start 154.296925 100.087156)
		(end 154.296925 99.912156)
		(width 0.1)
		(layer "In2.Cu")
		(net 490)
	)
	(segment
		(start 153.509273 100.008972)
		(end 153.525108 100.024807)
		(width 0.1)
		(layer "In2.Cu")
		(net 490)
	)
	(segment
		(start 153.140651 98.941631)
		(end 153.16794 98.94786)
		(width 0.1)
		(layer "In2.Cu")
		(net 490)
	)
	(segment
		(start 152.66726 99.706447)
		(end 152.655115 99.731666)
		(width 0.1)
		(layer "In2.Cu")
		(net 490)
	)
	(segment
		(start 153.490313 99.997059)
		(end 153.509273 100.008972)
		(width 0.1)
		(layer "In2.Cu")
		(net 490)
	)
	(segment
		(start 153.603536 100.177252)
		(end 153.624672 100.184648)
		(width 0.1)
		(layer "In2.Cu")
		(net 490)
	)
	(segment
		(start 153.775108 100.149504)
		(end 153.787021 100.130544)
		(width 0.1)
		(layer "In2.Cu")
		(net 490)
	)
	(segment
		(start 153.624672 100.184648)
		(end 153.646925 100.187156)
		(width 0.1)
		(layer "In2.Cu")
		(net 490)
	)
	(segment
		(start 153.798178 99.92603)
		(end 153.801876 99.915462)
		(width 0.1)
		(layer "In2.Cu")
		(net 490)
	)
	(segment
		(start 154.219177 100.184648)
		(end 154.240313 100.177252)
		(width 0.1)
		(layer "In2.Cu")
		(net 490)
	)
	(segment
		(start 152.401403 99.327331)
		(end 152.407632 99.35462)
		(width 0.1)
		(layer "In2.Cu")
		(net 490)
	)
	(segment
		(start 152.226126 98.766357)
		(end 152.472585 99.012816)
		(width 0.1)
		(layer "In2.Cu")
		(net 490)
	)
	(segment
		(start 154.539497 99.879615)
		(end 154.545044 99.895467)
		(width 0.1)
		(layer "In2.Cu")
		(net 490)
	)
	(segment
		(start 152.759104 99.897164)
		(end 152.787095 99.897164)
		(width 0.1)
		(layer "In2.Cu")
		(net 490)
	)
	(segment
		(start 153.796925 100.087156)
		(end 153.796925 99.937156)
		(width 0.1)
		(layer "In2.Cu")
		(net 490)
	)
	(segment
		(start 154.545044 99.895467)
		(end 154.548805 99.928846)
		(width 0.1)
		(layer "In2.Cu")
		(net 490)
	)
	(segment
		(start 153.105293 99.684091)
		(end 153.132582 99.69032)
		(width 0.1)
		(layer "In2.Cu")
		(net 490)
	)
	(segment
		(start 152.472585 99.189592)
		(end 152.437229 99.224947)
		(width 0.1)
		(layer "In2.Cu")
		(net 490)
	)
	(segment
		(start 154.196925 100.187156)
		(end 154.219177 100.184648)
		(width 0.1)
		(layer "In2.Cu")
		(net 490)
	)
	(segment
		(start 153.244642 99.024561)
		(end 153.250869 99.051849)
		(width 0.1)
		(layer "In2.Cu")
		(net 490)
	)
	(segment
		(start 153.024793 99.702465)
		(end 153.050012 99.69032)
		(width 0.1)
		(layer "In2.Cu")
		(net 490)
	)
	(segment
		(start 152.419777 99.379839)
		(end 152.437229 99.401724)
		(width 0.1)
		(layer "In2.Cu")
		(net 490)
	)
	(segment
		(start 153.215045 99.154234)
		(end 152.684712 99.684562)
		(width 0.1)
		(layer "In2.Cu")
		(net 490)
	)
	(segment
		(start 152.459113 99.419176)
		(end 152.484332 99.431321)
		(width 0.1)
		(layer "In2.Cu")
		(net 490)
	)
	(segment
		(start 154.041973 99.915462)
		(end 154.045671 99.92603)
		(width 0.1)
		(layer "In2.Cu")
		(net 490)
	)
	(segment
		(start 153.807833 99.905982)
		(end 153.81575 99.898065)
		(width 0.1)
		(layer "In2.Cu")
		(net 490)
	)
	(segment
		(start 154.518686 99.853519)
		(end 154.530562 99.865395)
		(width 0.1)
		(layer "In2.Cu")
		(net 490)
	)
	(segment
		(start 154.548805 99.928846)
		(end 154.554352 99.944698)
		(width 0.1)
		(layer "In2.Cu")
		(net 490)
	)
	(segment
		(start 154.049432 100.109408)
		(end 154.056828 100.130544)
		(width 0.1)
		(layer "In2.Cu")
		(net 490)
	)
	(segment
		(start 153.132582 99.69032)
		(end 153.157801 99.702465)
		(width 0.1)
		(layer "In2.Cu")
		(net 490)
	)
	(segment
		(start 153.002909 99.719917)
		(end 153.024793 99.702465)
		(width 0.1)
		(layer "In2.Cu")
		(net 490)
	)
	(segment
		(start 154.275108 100.149504)
		(end 154.287021 100.130544)
		(width 0.1)
		(layer "In2.Cu")
		(net 490)
	)
	(segment
		(start 154.028099 99.898065)
		(end 154.036016 99.905982)
		(width 0.1)
		(layer "In2.Cu")
		(net 490)
	)
	(segment
		(start 152.437229 99.224947)
		(end 152.419777 99.246831)
		(width 0.1)
		(layer "In2.Cu")
		(net 490)
	)
	(segment
		(start 152.787095 99.897164)
		(end 152.814385 99.890936)
		(width 0.1)
		(layer "In2.Cu")
		(net 490)
	)
	(segment
		(start 161.536329 99.487156)
		(end 161.036329 98.987157)
		(width 0.15)
		(layer "F.Cu")
		(net 491)
	)
	(segment
		(start 151.682327 97.275758)
		(end 152.182327 97.775757)
		(width 0.15)
		(layer "F.Cu")
		(net 491)
	)
	(via blind
		(at 161.036329 98.987157)
		(size 0.5)
		(drill 0.2)
		(layers "F.Cu" "In2.Cu")
		(net 491)
	)
	(via blind
		(at 152.182327 97.775757)
		(size 0.5)
		(drill 0.2)
		(layers "F.Cu" "In2.Cu")
		(net 491)
	)
	(segment
		(start 152.916643 97.635442)
		(end 152.89439 97.637949)
		(width 0.1)
		(layer "In2.Cu")
		(net 491)
	)
	(segment
		(start 153.014135 97.713189)
		(end 153.006739 97.692053)
		(width 0.1)
		(layer "In2.Cu")
		(net 491)
	)
	(segment
		(start 153.016643 97.836957)
		(end 153.016643 97.735442)
		(width 0.1)
		(layer "In2.Cu")
		(net 491)
	)
	(segment
		(start 158.760528 98.851357)
		(end 158.326328 98.417157)
		(width 0.1)
		(layer "In2.Cu")
		(net 491)
	)
	(segment
		(start 161.036329 98.987157)
		(end 160.900529 98.851357)
		(width 0.1)
		(layer "In2.Cu")
		(net 491)
	)
	(segment
		(start 153.01915 97.859209)
		(end 153.016643 97.836957)
		(width 0.1)
		(layer "In2.Cu")
		(net 491)
	)
	(segment
		(start 152.778991 97.91514)
		(end 152.760031 97.927053)
		(width 0.1)
		(layer "In2.Cu")
		(net 491)
	)
	(segment
		(start 152.806739 97.880345)
		(end 152.794826 97.899305)
		(width 0.1)
		(layer "In2.Cu")
		(net 491)
	)
	(segment
		(start 152.873254 97.645345)
		(end 152.854294 97.657258)
		(width 0.1)
		(layer "In2.Cu")
		(net 491)
	)
	(segment
		(start 152.960031 97.645345)
		(end 152.938895 97.637949)
		(width 0.1)
		(layer "In2.Cu")
		(net 491)
	)
	(segment
		(start 152.89439 97.637949)
		(end 152.873254 97.645345)
		(width 0.1)
		(layer "In2.Cu")
		(net 491)
	)
	(segment
		(start 152.738895 97.934449)
		(end 152.716643 97.936957)
		(width 0.1)
		(layer "In2.Cu")
		(net 491)
	)
	(segment
		(start 152.854294 97.657258)
		(end 152.838459 97.673093)
		(width 0.1)
		(layer "In2.Cu")
		(net 491)
	)
	(segment
		(start 153.026546 97.880345)
		(end 153.01915 97.859209)
		(width 0.1)
		(layer "In2.Cu")
		(net 491)
	)
	(segment
		(start 152.838459 97.673093)
		(end 152.826546 97.692053)
		(width 0.1)
		(layer "In2.Cu")
		(net 491)
	)
	(segment
		(start 152.760031 97.927053)
		(end 152.738895 97.934449)
		(width 0.1)
		(layer "In2.Cu")
		(net 491)
	)
	(segment
		(start 152.716643 97.936957)
		(end 152.343527 97.936957)
		(width 0.1)
		(layer "In2.Cu")
		(net 491)
	)
	(segment
		(start 152.81915 97.713189)
		(end 152.816643 97.735442)
		(width 0.1)
		(layer "In2.Cu")
		(net 491)
	)
	(segment
		(start 152.978991 97.657258)
		(end 152.960031 97.645345)
		(width 0.1)
		(layer "In2.Cu")
		(net 491)
	)
	(segment
		(start 153.739128 97.936957)
		(end 153.116643 97.936957)
		(width 0.1)
		(layer "In2.Cu")
		(net 491)
	)
	(segment
		(start 152.814135 97.859209)
		(end 152.806739 97.880345)
		(width 0.1)
		(layer "In2.Cu")
		(net 491)
	)
	(segment
		(start 153.116643 97.936957)
		(end 153.09439 97.934449)
		(width 0.1)
		(layer "In2.Cu")
		(net 491)
	)
	(segment
		(start 152.343527 97.936957)
		(end 152.182327 97.775757)
		(width 0.1)
		(layer "In2.Cu")
		(net 491)
	)
	(segment
		(start 152.826546 97.692053)
		(end 152.81915 97.713189)
		(width 0.1)
		(layer "In2.Cu")
		(net 491)
	)
	(segment
		(start 153.054294 97.91514)
		(end 153.038459 97.899305)
		(width 0.1)
		(layer "In2.Cu")
		(net 491)
	)
	(segment
		(start 153.038459 97.899305)
		(end 153.026546 97.880345)
		(width 0.1)
		(layer "In2.Cu")
		(net 491)
	)
	(segment
		(start 152.816643 97.735442)
		(end 152.816643 97.836957)
		(width 0.1)
		(layer "In2.Cu")
		(net 491)
	)
	(segment
		(start 153.09439 97.934449)
		(end 153.073254 97.927053)
		(width 0.1)
		(layer "In2.Cu")
		(net 491)
	)
	(segment
		(start 158.326328 98.417157)
		(end 154.219328 98.417157)
		(width 0.1)
		(layer "In2.Cu")
		(net 491)
	)
	(segment
		(start 152.994826 97.673093)
		(end 152.978991 97.657258)
		(width 0.1)
		(layer "In2.Cu")
		(net 491)
	)
	(segment
		(start 152.794826 97.899305)
		(end 152.778991 97.91514)
		(width 0.1)
		(layer "In2.Cu")
		(net 491)
	)
	(segment
		(start 152.938895 97.637949)
		(end 152.916643 97.635442)
		(width 0.1)
		(layer "In2.Cu")
		(net 491)
	)
	(segment
		(start 153.016643 97.735442)
		(end 153.014135 97.713189)
		(width 0.1)
		(layer "In2.Cu")
		(net 491)
	)
	(segment
		(start 152.816643 97.836957)
		(end 152.814135 97.859209)
		(width 0.1)
		(layer "In2.Cu")
		(net 491)
	)
	(segment
		(start 154.219328 98.417157)
		(end 153.739128 97.936957)
		(width 0.1)
		(layer "In2.Cu")
		(net 491)
	)
	(segment
		(start 160.900529 98.851357)
		(end 158.760528 98.851357)
		(width 0.1)
		(layer "In2.Cu")
		(net 491)
	)
	(segment
		(start 153.006739 97.692053)
		(end 152.994826 97.673093)
		(width 0.1)
		(layer "In2.Cu")
		(net 491)
	)
	(segment
		(start 153.073254 97.927053)
		(end 153.054294 97.91514)
		(width 0.1)
		(layer "In2.Cu")
		(net 491)
	)
	(segment
		(start 160.536329 101.487156)
		(end 160.036329 100.987157)
		(width 0.15)
		(layer "F.Cu")
		(net 492)
	)
	(segment
		(start 150.691727 97.275758)
		(end 151.191727 97.775757)
		(width 0.15)
		(layer "F.Cu")
		(net 492)
	)
	(via blind
		(at 151.191727 97.775757)
		(size 0.5)
		(drill 0.2)
		(layers "F.Cu" "In2.Cu")
		(net 492)
	)
	(via blind
		(at 160.036329 100.987157)
		(size 0.5)
		(drill 0.2)
		(layers "F.Cu" "In2.Cu")
		(net 492)
	)
	(segment
		(start 159.864357 100.987157)
		(end 159.3596 100.4824)
		(width 0.1)
		(layer "In2.Cu")
		(net 492)
	)
	(segment
		(start 152.8826 100.4824)
		(end 151.7142 99.314)
		(width 0.1)
		(layer "In2.Cu")
		(net 492)
	)
	(segment
		(start 151.7142 98.2726)
		(end 151.217357 97.775757)
		(width 0.1)
		(layer "In2.Cu")
		(net 492)
	)
	(segment
		(start 151.7142 99.314)
		(end 151.7142 98.2726)
		(width 0.1)
		(layer "In2.Cu")
		(net 492)
	)
	(segment
		(start 151.217357 97.775757)
		(end 151.191727 97.775757)
		(width 0.1)
		(layer "In2.Cu")
		(net 492)
	)
	(segment
		(start 159.3596 100.4824)
		(end 152.8826 100.4824)
		(width 0.1)
		(layer "In2.Cu")
		(net 492)
	)
	(segment
		(start 160.036329 100.987157)
		(end 159.864357 100.987157)
		(width 0.1)
		(layer "In2.Cu")
		(net 492)
	)
	(segment
		(start 150.165171 100.155505)
		(end 150.155455 100.135329)
		(width 0.1)
		(layer "F.Cu")
		(net 493)
	)
	(segment
		(start 150.155455 100.135329)
		(end 150.141493 100.117822)
		(width 0.1)
		(layer "F.Cu")
		(net 493)
	)
	(segment
		(start 150.141493 100.117822)
		(end 150.123985 100.10386)
		(width 0.1)
		(layer "F.Cu")
		(net 493)
	)
	(segment
		(start 149.703266 100.135329)
		(end 149.717228 100.117821)
		(width 0.1)
		(layer "F.Cu")
		(net 493)
	)
	(segment
		(start 149.693551 100.221561)
		(end 149.688567 100.199728)
		(width 0.1)
		(layer "F.Cu")
		(net 493)
	)
	(segment
		(start 149.820966 100.282921)
		(end 149.799136 100.287904)
		(width 0.1)
		(layer "F.Cu")
		(net 493)
	)
	(segment
		(start 149.734736 100.273206)
		(end 149.717228 100.259243)
		(width 0.1)
		(layer "F.Cu")
		(net 493)
	)
	(segment
		(start 150.574428 100.550757)
		(end 150.424336 100.400665)
		(width 0.1)
		(layer "F.Cu")
		(net 493)
	)
	(segment
		(start 149.754912 100.282922)
		(end 149.734736 100.273206)
		(width 0.1)
		(layer "F.Cu")
		(net 493)
	)
	(segment
		(start 149.688567 100.199728)
		(end 149.688568 100.177336)
		(width 0.1)
		(layer "F.Cu")
		(net 493)
	)
	(segment
		(start 150.170153 100.199729)
		(end 150.170152 100.177335)
		(width 0.1)
		(layer "F.Cu")
		(net 493)
	)
	(segment
		(start 150.059585 100.570746)
		(end 150.037755 100.565765)
		(width 0.1)
		(layer "F.Cu")
		(net 493)
	)
	(segment
		(start 150.017579 100.556049)
		(end 150.000071 100.542086)
		(width 0.1)
		(layer "F.Cu")
		(net 493)
	)
	(segment
		(start 158.186328 100.147157)
		(end 154.535062 100.147157)
		(width 0.1)
		(layer "F.Cu")
		(net 493)
	)
	(segment
		(start 149.872612 99.852486)
		(end 149.85865 99.834979)
		(width 0.1)
		(layer "F.Cu")
		(net 493)
	)
	(segment
		(start 154.535062 100.147157)
		(end 154.131462 100.550757)
		(width 0.1)
		(layer "F.Cu")
		(net 493)
	)
	(segment
		(start 150.141493 100.542087)
		(end 150.123985 100.556048)
		(width 0.1)
		(layer "F.Cu")
		(net 493)
	)
	(segment
		(start 149.976394 100.438348)
		(end 149.986109 100.418172)
		(width 0.1)
		(layer "F.Cu")
		(net 493)
	)
	(segment
		(start 149.85865 100.259244)
		(end 149.841142 100.273205)
		(width 0.1)
		(layer "F.Cu")
		(net 493)
	)
	(segment
		(start 149.97141 100.482571)
		(end 149.971411 100.460179)
		(width 0.1)
		(layer "F.Cu")
		(net 493)
	)
	(segment
		(start 150.103809 100.565764)
		(end 150.081979 100.570747)
		(width 0.1)
		(layer "F.Cu")
		(net 493)
	)
	(segment
		(start 149.688568 100.177336)
		(end 149.693551 100.155505)
		(width 0.1)
		(layer "F.Cu")
		(net 493)
	)
	(segment
		(start 150.037755 100.565765)
		(end 150.017579 100.556049)
		(width 0.1)
		(layer "F.Cu")
		(net 493)
	)
	(segment
		(start 149.85865 99.834979)
		(end 149.687828 99.664157)
		(width 0.1)
		(layer "F.Cu")
		(net 493)
	)
	(segment
		(start 149.976394 100.504404)
		(end 149.97141 100.482571)
		(width 0.1)
		(layer "F.Cu")
		(net 493)
	)
	(segment
		(start 149.986109 100.418172)
		(end 150.000071 100.400664)
		(width 0.1)
		(layer "F.Cu")
		(net 493)
	)
	(segment
		(start 149.882328 99.872662)
		(end 149.872612 99.852486)
		(width 0.1)
		(layer "F.Cu")
		(net 493)
	)
	(segment
		(start 150.320598 100.376988)
		(end 150.300422 100.386703)
		(width 0.1)
		(layer "F.Cu")
		(net 493)
	)
	(segment
		(start 150.170152 100.177335)
		(end 150.165171 100.155505)
		(width 0.1)
		(layer "F.Cu")
		(net 493)
	)
	(segment
		(start 150.017579 100.10386)
		(end 150.000071 100.117822)
		(width 0.1)
		(layer "F.Cu")
		(net 493)
	)
	(segment
		(start 150.000071 100.117822)
		(end 149.85865 100.259244)
		(width 0.1)
		(layer "F.Cu")
		(net 493)
	)
	(segment
		(start 150.037755 100.094145)
		(end 150.017579 100.10386)
		(width 0.1)
		(layer "F.Cu")
		(net 493)
	)
	(segment
		(start 150.364821 100.372004)
		(end 150.342429 100.372005)
		(width 0.1)
		(layer "F.Cu")
		(net 493)
	)
	(segment
		(start 149.776742 100.287903)
		(end 149.754912 100.282922)
		(width 0.1)
		(layer "F.Cu")
		(net 493)
	)
	(segment
		(start 149.717228 100.259243)
		(end 149.703266 100.241735)
		(width 0.1)
		(layer "F.Cu")
		(net 493)
	)
	(segment
		(start 149.971411 100.460179)
		(end 149.976394 100.438348)
		(width 0.1)
		(layer "F.Cu")
		(net 493)
	)
	(segment
		(start 149.693551 100.155505)
		(end 149.703266 100.135329)
		(width 0.1)
		(layer "F.Cu")
		(net 493)
	)
	(segment
		(start 150.059586 100.089162)
		(end 150.037755 100.094145)
		(width 0.1)
		(layer "F.Cu")
		(net 493)
	)
	(segment
		(start 154.131462 100.550757)
		(end 150.574428 100.550757)
		(width 0.1)
		(layer "F.Cu")
		(net 493)
	)
	(segment
		(start 149.88731 99.916886)
		(end 149.887309 99.894492)
		(width 0.1)
		(layer "F.Cu")
		(net 493)
	)
	(segment
		(start 149.841142 100.273205)
		(end 149.820966 100.282921)
		(width 0.1)
		(layer "F.Cu")
		(net 493)
	)
	(segment
		(start 149.872611 99.958892)
		(end 149.882327 99.938716)
		(width 0.1)
		(layer "F.Cu")
		(net 493)
	)
	(segment
		(start 150.300422 100.386703)
		(end 150.282914 100.400665)
		(width 0.1)
		(layer "F.Cu")
		(net 493)
	)
	(segment
		(start 150.000071 100.542086)
		(end 149.986109 100.524578)
		(width 0.1)
		(layer "F.Cu")
		(net 493)
	)
	(segment
		(start 150.424336 100.400665)
		(end 150.406828 100.386703)
		(width 0.1)
		(layer "F.Cu")
		(net 493)
	)
	(segment
		(start 150.406828 100.386703)
		(end 150.386654 100.376988)
		(width 0.1)
		(layer "F.Cu")
		(net 493)
	)
	(segment
		(start 150.141493 100.259243)
		(end 150.155454 100.241735)
		(width 0.1)
		(layer "F.Cu")
		(net 493)
	)
	(segment
		(start 149.85865 99.9764)
		(end 149.872611 99.958892)
		(width 0.1)
		(layer "F.Cu")
		(net 493)
	)
	(segment
		(start 149.986109 100.524578)
		(end 149.976394 100.504404)
		(width 0.1)
		(layer "F.Cu")
		(net 493)
	)
	(segment
		(start 150.282914 100.400665)
		(end 150.141493 100.542087)
		(width 0.1)
		(layer "F.Cu")
		(net 493)
	)
	(segment
		(start 149.703266 100.241735)
		(end 149.693551 100.221561)
		(width 0.1)
		(layer "F.Cu")
		(net 493)
	)
	(segment
		(start 149.799136 100.287904)
		(end 149.776742 100.287903)
		(width 0.1)
		(layer "F.Cu")
		(net 493)
	)
	(segment
		(start 149.887309 99.894492)
		(end 149.882328 99.872662)
		(width 0.1)
		(layer "F.Cu")
		(net 493)
	)
	(segment
		(start 158.536328 100.497157)
		(end 158.186328 100.147157)
		(width 0.1)
		(layer "F.Cu")
		(net 493)
	)
	(segment
		(start 150.123985 100.556048)
		(end 150.103809 100.565764)
		(width 0.1)
		(layer "F.Cu")
		(net 493)
	)
	(segment
		(start 150.16517 100.221559)
		(end 150.170153 100.199729)
		(width 0.1)
		(layer "F.Cu")
		(net 493)
	)
	(segment
		(start 150.000071 100.400664)
		(end 150.141493 100.259243)
		(width 0.1)
		(layer "F.Cu")
		(net 493)
	)
	(segment
		(start 150.123985 100.10386)
		(end 150.103811 100.094145)
		(width 0.1)
		(layer "F.Cu")
		(net 493)
	)
	(segment
		(start 149.882327 99.938716)
		(end 149.88731 99.916886)
		(width 0.1)
		(layer "F.Cu")
		(net 493)
	)
	(segment
		(start 149.687828 99.664157)
		(end 149.687828 99.283157)
		(width 0.1)
		(layer "F.Cu")
		(net 493)
	)
	(segment
		(start 150.081979 100.570747)
		(end 150.059585 100.570746)
		(width 0.1)
		(layer "F.Cu")
		(net 493)
	)
	(segment
		(start 149.717228 100.117821)
		(end 149.85865 99.9764)
		(width 0.1)
		(layer "F.Cu")
		(net 493)
	)
	(segment
		(start 150.103811 100.094145)
		(end 150.081978 100.089161)
		(width 0.1)
		(layer "F.Cu")
		(net 493)
	)
	(segment
		(start 150.342429 100.372005)
		(end 150.320598 100.376988)
		(width 0.1)
		(layer "F.Cu")
		(net 493)
	)
	(segment
		(start 150.081978 100.089161)
		(end 150.059586 100.089162)
		(width 0.1)
		(layer "F.Cu")
		(net 493)
	)
	(segment
		(start 150.155454 100.241735)
		(end 150.16517 100.221559)
		(width 0.1)
		(layer "F.Cu")
		(net 493)
	)
	(segment
		(start 150.386654 100.376988)
		(end 150.364821 100.372004)
		(width 0.1)
		(layer "F.Cu")
		(net 493)
	)
	(segment
		(start 162.539244 99.484129)
		(end 163.039243 98.984129)
		(width 0.15)
		(layer "F.Cu")
		(net 494)
	)
	(segment
		(start 152.696328 97.277157)
		(end 153.333328 97.277157)
		(width 0.15)
		(layer "F.Cu")
		(net 494)
	)
	(segment
		(start 153.333328 97.277157)
		(end 153.485128 97.428957)
		(width 0.15)
		(layer "F.Cu")
		(net 494)
	)
	(via blind
		(at 153.485128 97.428957)
		(size 0.5)
		(drill 0.2)
		(layers "F.Cu" "In2.Cu")
		(net 494)
	)
	(via blind
		(at 163.044643 98.983529)
		(size 0.5)
		(drill 0.2)
		(layers "F.Cu" "In2.Cu")
		(net 494)
	)
	(segment
		(start 159.437354 98.344815)
		(end 159.450373 98.336635)
		(width 0.1)
		(layer "In2.Cu")
		(net 494)
	)
	(segment
		(start 159.426482 98.355687)
		(end 159.437354 98.344815)
		(width 0.1)
		(layer "In2.Cu")
		(net 494)
	)
	(segment
		(start 159.480164 98.329835)
		(end 159.642842 98.329835)
		(width 0.1)
		(layer "In2.Cu")
		(net 494)
	)
	(segment
		(start 159.685651 98.344815)
		(end 159.696523 98.355687)
		(width 0.1)
		(layer "In2.Cu")
		(net 494)
	)
	(segment
		(start 159.372632 98.460359)
		(end 159.385651 98.452179)
		(width 0.1)
		(layer "In2.Cu")
		(net 494)
	)
	(segment
		(start 159.737354 98.452179)
		(end 159.750373 98.460359)
		(width 0.1)
		(layer "In2.Cu")
		(net 494)
	)
	(segment
		(start 159.642842 98.329835)
		(end 159.65812 98.331557)
		(width 0.1)
		(layer "In2.Cu")
		(net 494)
	)
	(segment
		(start 159.780164 98.467158)
		(end 162.528272 98.467158)
		(width 0.1)
		(layer "In2.Cu")
		(net 494)
	)
	(segment
		(start 159.65812 98.331557)
		(end 159.672632 98.336635)
		(width 0.1)
		(layer "In2.Cu")
		(net 494)
	)
	(segment
		(start 153.485128 97.428957)
		(end 153.689957 97.428957)
		(width 0.1)
		(layer "In2.Cu")
		(net 494)
	)
	(segment
		(start 162.528272 98.467158)
		(end 163.044643 98.983529)
		(width 0.1)
		(layer "In2.Cu")
		(net 494)
	)
	(segment
		(start 159.672632 98.336635)
		(end 159.685651 98.344815)
		(width 0.1)
		(layer "In2.Cu")
		(net 494)
	)
	(segment
		(start 159.404703 98.428288)
		(end 159.409781 98.413776)
		(width 0.1)
		(layer "In2.Cu")
		(net 494)
	)
	(segment
		(start 153.689957 97.428957)
		(end 154.4066 98.1456)
		(width 0.1)
		(layer "In2.Cu")
		(net 494)
	)
	(segment
		(start 159.35812 98.465437)
		(end 159.372632 98.460359)
		(width 0.1)
		(layer "In2.Cu")
		(net 494)
	)
	(segment
		(start 159.418302 98.368706)
		(end 159.426482 98.355687)
		(width 0.1)
		(layer "In2.Cu")
		(net 494)
	)
	(segment
		(start 159.409781 98.413776)
		(end 159.413224 98.383218)
		(width 0.1)
		(layer "In2.Cu")
		(net 494)
	)
	(segment
		(start 159.704703 98.368706)
		(end 159.709781 98.383218)
		(width 0.1)
		(layer "In2.Cu")
		(net 494)
	)
	(segment
		(start 154.4066 98.1456)
		(end 158.49877 98.1456)
		(width 0.1)
		(layer "In2.Cu")
		(net 494)
	)
	(segment
		(start 159.450373 98.336635)
		(end 159.464885 98.331557)
		(width 0.1)
		(layer "In2.Cu")
		(net 494)
	)
	(segment
		(start 159.713224 98.413776)
		(end 159.718302 98.428288)
		(width 0.1)
		(layer "In2.Cu")
		(net 494)
	)
	(segment
		(start 159.718302 98.428288)
		(end 159.726482 98.441307)
		(width 0.1)
		(layer "In2.Cu")
		(net 494)
	)
	(segment
		(start 159.764885 98.465437)
		(end 159.780164 98.467158)
		(width 0.1)
		(layer "In2.Cu")
		(net 494)
	)
	(segment
		(start 159.750373 98.460359)
		(end 159.764885 98.465437)
		(width 0.1)
		(layer "In2.Cu")
		(net 494)
	)
	(segment
		(start 159.726482 98.441307)
		(end 159.737354 98.452179)
		(width 0.1)
		(layer "In2.Cu")
		(net 494)
	)
	(segment
		(start 159.696523 98.355687)
		(end 159.704703 98.368706)
		(width 0.1)
		(layer "In2.Cu")
		(net 494)
	)
	(segment
		(start 159.396523 98.441307)
		(end 159.404703 98.428288)
		(width 0.1)
		(layer "In2.Cu")
		(net 494)
	)
	(segment
		(start 159.464885 98.331557)
		(end 159.480164 98.329835)
		(width 0.1)
		(layer "In2.Cu")
		(net 494)
	)
	(segment
		(start 159.413224 98.383218)
		(end 159.418302 98.368706)
		(width 0.1)
		(layer "In2.Cu")
		(net 494)
	)
	(segment
		(start 159.342842 98.467158)
		(end 159.35812 98.465437)
		(width 0.1)
		(layer "In2.Cu")
		(net 494)
	)
	(segment
		(start 158.820328 98.467158)
		(end 159.342842 98.467158)
		(width 0.1)
		(layer "In2.Cu")
		(net 494)
	)
	(segment
		(start 159.385651 98.452179)
		(end 159.396523 98.441307)
		(width 0.1)
		(layer "In2.Cu")
		(net 494)
	)
	(segment
		(start 159.709781 98.383218)
		(end 159.713224 98.413776)
		(width 0.1)
		(layer "In2.Cu")
		(net 494)
	)
	(segment
		(start 158.49877 98.1456)
		(end 158.820328 98.467158)
		(width 0.1)
		(layer "In2.Cu")
		(net 494)
	)
	(segment
		(start 160.546329 98.497156)
		(end 160.046329 97.997157)
		(width 0.15)
		(layer "F.Cu")
		(net 495)
	)
	(segment
		(start 151.682527 95.270556)
		(end 151.182528 95.770556)
		(width 0.15)
		(layer "F.Cu")
		(net 495)
	)
	(via blind
		(at 160.046329 97.997157)
		(size 0.5)
		(drill 0.2)
		(layers "F.Cu" "In2.Cu")
		(net 495)
	)
	(via blind
		(at 151.182528 95.770556)
		(size 0.5)
		(drill 0.2)
		(layers "F.Cu" "In2.Cu")
		(net 495)
	)
	(segment
		(start 152.140917 96.728945)
		(end 151.182528 95.770556)
		(width 0.1)
		(layer "In2.Cu")
		(net 495)
	)
	(segment
		(start 159.616328 97.567156)
		(end 154.662292 97.567156)
		(width 0.1)
		(layer "In2.Cu")
		(net 495)
	)
	(segment
		(start 160.046329 97.997157)
		(end 159.616328 97.567156)
		(width 0.1)
		(layer "In2.Cu")
		(net 495)
	)
	(segment
		(start 153.824081 96.728945)
		(end 152.140917 96.728945)
		(width 0.1)
		(layer "In2.Cu")
		(net 495)
	)
	(segment
		(start 154.662292 97.567156)
		(end 153.824081 96.728945)
		(width 0.1)
		(layer "In2.Cu")
		(net 495)
	)
	(segment
		(start 161.536329 101.497156)
		(end 161.036329 100.997157)
		(width 0.15)
		(layer "F.Cu")
		(net 496)
	)
	(segment
		(start 153.402928 99.277157)
		(end 153.586728 99.460957)
		(width 0.15)
		(layer "F.Cu")
		(net 496)
	)
	(segment
		(start 152.696328 99.277157)
		(end 153.402928 99.277157)
		(width 0.15)
		(layer "F.Cu")
		(net 496)
	)
	(via blind
		(at 153.586728 99.460957)
		(size 0.5)
		(drill 0.2)
		(layers "F.Cu" "In2.Cu")
		(net 496)
	)
	(via blind
		(at 161.036329 100.997157)
		(size 0.5)
		(drill 0.2)
		(layers "F.Cu" "In2.Cu")
		(net 496)
	)
	(segment
		(start 159.555728 100.197557)
		(end 159.555728 99.740357)
		(width 0.1)
		(layer "In2.Cu")
		(net 496)
	)
	(segment
		(start 154.214835 99.606421)
		(end 154.188415 99.615665)
		(width 0.1)
		(layer "In2.Cu")
		(net 496)
	)
	(segment
		(start 154.488536 99.006486)
		(end 154.464835 98.991593)
		(width 0.1)
		(layer "In2.Cu")
		(net 496)
	)
	(segment
		(start 159.555728 99.740357)
		(end 159.301728 99.486357)
		(width 0.1)
		(layer "In2.Cu")
		(net 496)
	)
	(segment
		(start 154.188415 99.615665)
		(end 154.1606 99.6188)
		(width 0.1)
		(layer "In2.Cu")
		(net 496)
	)
	(segment
		(start 159.301728 99.486357)
		(end 158.120443 99.486357)
		(width 0.1)
		(layer "In2.Cu")
		(net 496)
	)
	(segment
		(start 154.4106 98.979215)
		(end 154.382784 98.982349)
		(width 0.1)
		(layer "In2.Cu")
		(net 496)
	)
	(segment
		(start 154.6606 99.6188)
		(end 154.632784 99.615665)
		(width 0.1)
		(layer "In2.Cu")
		(net 496)
	)
	(segment
		(start 154.547978 99.548035)
		(end 154.538734 99.521615)
		(width 0.1)
		(layer "In2.Cu")
		(net 496)
	)
	(segment
		(start 160.50153 100.462358)
		(end 159.820529 100.462358)
		(width 0.1)
		(layer "In2.Cu")
		(net 496)
	)
	(segment
		(start 154.1606 99.6188)
		(end 153.744571 99.6188)
		(width 0.1)
		(layer "In2.Cu")
		(net 496)
	)
	(segment
		(start 161.036329 100.997157)
		(end 160.50153 100.462358)
		(width 0.1)
		(layer "In2.Cu")
		(net 496)
	)
	(segment
		(start 154.632784 99.615665)
		(end 154.606364 99.606421)
		(width 0.1)
		(layer "In2.Cu")
		(net 496)
	)
	(segment
		(start 157.988 99.6188)
		(end 154.6606 99.6188)
		(width 0.1)
		(layer "In2.Cu")
		(net 496)
	)
	(segment
		(start 154.5356 99.104215)
		(end 154.532465 99.076399)
		(width 0.1)
		(layer "In2.Cu")
		(net 496)
	)
	(segment
		(start 158.120443 99.486357)
		(end 157.988 99.6188)
		(width 0.1)
		(layer "In2.Cu")
		(net 496)
	)
	(segment
		(start 154.356364 98.991593)
		(end 154.332663 99.006486)
		(width 0.1)
		(layer "In2.Cu")
		(net 496)
	)
	(segment
		(start 154.312871 99.026278)
		(end 154.297978 99.049979)
		(width 0.1)
		(layer "In2.Cu")
		(net 496)
	)
	(segment
		(start 154.464835 98.991593)
		(end 154.438415 98.982349)
		(width 0.1)
		(layer "In2.Cu")
		(net 496)
	)
	(segment
		(start 154.2856 99.4938)
		(end 154.282465 99.521615)
		(width 0.1)
		(layer "In2.Cu")
		(net 496)
	)
	(segment
		(start 154.288734 99.076399)
		(end 154.2856 99.104215)
		(width 0.1)
		(layer "In2.Cu")
		(net 496)
	)
	(segment
		(start 159.820529 100.462358)
		(end 159.555728 100.197557)
		(width 0.1)
		(layer "In2.Cu")
		(net 496)
	)
	(segment
		(start 154.438415 98.982349)
		(end 154.4106 98.979215)
		(width 0.1)
		(layer "In2.Cu")
		(net 496)
	)
	(segment
		(start 154.332663 99.006486)
		(end 154.312871 99.026278)
		(width 0.1)
		(layer "In2.Cu")
		(net 496)
	)
	(segment
		(start 154.273221 99.548035)
		(end 154.258328 99.571736)
		(width 0.1)
		(layer "In2.Cu")
		(net 496)
	)
	(segment
		(start 154.582663 99.591528)
		(end 154.562871 99.571736)
		(width 0.1)
		(layer "In2.Cu")
		(net 496)
	)
	(segment
		(start 154.258328 99.571736)
		(end 154.238536 99.591528)
		(width 0.1)
		(layer "In2.Cu")
		(net 496)
	)
	(segment
		(start 154.282465 99.521615)
		(end 154.273221 99.548035)
		(width 0.1)
		(layer "In2.Cu")
		(net 496)
	)
	(segment
		(start 154.606364 99.606421)
		(end 154.582663 99.591528)
		(width 0.1)
		(layer "In2.Cu")
		(net 496)
	)
	(segment
		(start 154.238536 99.591528)
		(end 154.214835 99.606421)
		(width 0.1)
		(layer "In2.Cu")
		(net 496)
	)
	(segment
		(start 154.523221 99.049979)
		(end 154.508328 99.026278)
		(width 0.1)
		(layer "In2.Cu")
		(net 496)
	)
	(segment
		(start 154.538734 99.521615)
		(end 154.5356 99.4938)
		(width 0.1)
		(layer "In2.Cu")
		(net 496)
	)
	(segment
		(start 154.5356 99.4938)
		(end 154.5356 99.104215)
		(width 0.1)
		(layer "In2.Cu")
		(net 496)
	)
	(segment
		(start 154.382784 98.982349)
		(end 154.356364 98.991593)
		(width 0.1)
		(layer "In2.Cu")
		(net 496)
	)
	(segment
		(start 153.744571 99.6188)
		(end 153.586728 99.460957)
		(width 0.1)
		(layer "In2.Cu")
		(net 496)
	)
	(segment
		(start 154.508328 99.026278)
		(end 154.488536 99.006486)
		(width 0.1)
		(layer "In2.Cu")
		(net 496)
	)
	(segment
		(start 154.297978 99.049979)
		(end 154.288734 99.076399)
		(width 0.1)
		(layer "In2.Cu")
		(net 496)
	)
	(segment
		(start 154.532465 99.076399)
		(end 154.523221 99.049979)
		(width 0.1)
		(layer "In2.Cu")
		(net 496)
	)
	(segment
		(start 154.2856 99.104215)
		(end 154.2856 99.4938)
		(width 0.1)
		(layer "In2.Cu")
		(net 496)
	)
	(segment
		(start 154.562871 99.571736)
		(end 154.547978 99.548035)
		(width 0.1)
		(layer "In2.Cu")
		(net 496)
	)
	(segment
		(start 160.551129 100.512356)
		(end 160.051129 100.012357)
		(width 0.15)
		(layer "F.Cu")
		(net 497)
	)
	(segment
		(start 153.393528 98.277157)
		(end 153.586728 98.470357)
		(width 0.15)
		(layer "F.Cu")
		(net 497)
	)
	(segment
		(start 152.696328 98.277157)
		(end 153.393528 98.277157)
		(width 0.15)
		(layer "F.Cu")
		(net 497)
	)
	(via blind
		(at 153.586728 98.470357)
		(size 0.5)
		(drill 0.2)
		(layers "F.Cu" "In2.Cu")
		(net 497)
	)
	(via blind
		(at 160.051129 100.012357)
		(size 0.5)
		(drill 0.2)
		(layers "F.Cu" "In2.Cu")
		(net 497)
	)
	(segment
		(start 156.225207 98.699535)
		(end 156.251627 98.690291)
		(width 0.1)
		(layer "In2.Cu")
		(net 497)
	)
	(segment
		(start 155.627171 99.136063)
		(end 155.642064 99.112362)
		(width 0.1)
		(layer "In2.Cu")
		(net 497)
	)
	(segment
		(start 153.586728 98.470357)
		(end 153.803528 98.687157)
		(width 0.1)
		(layer "In2.Cu")
		(net 497)
	)
	(segment
		(start 155.166821 98.757921)
		(end 155.181714 98.73422)
		(width 0.1)
		(layer "In2.Cu")
		(net 497)
	)
	(segment
		(start 156.083678 99.170748)
		(end 156.107379 99.155855)
		(width 0.1)
		(layer "In2.Cu")
		(net 497)
	)
	(segment
		(start 154.877171 98.73422)
		(end 154.892064 98.757921)
		(width 0.1)
		(layer "In2.Cu")
		(net 497)
	)
	(segment
		(start 155.157577 98.784341)
		(end 155.166821 98.757921)
		(width 0.1)
		(layer "In2.Cu")
		(net 497)
	)
	(segment
		(start 155.475207 99.170748)
		(end 155.501627 99.179992)
		(width 0.1)
		(layer "In2.Cu")
		(net 497)
	)
	(segment
		(start 155.307258 98.690291)
		(end 155.333678 98.699535)
		(width 0.1)
		(layer "In2.Cu")
		(net 497)
	)
	(segment
		(start 154.901308 98.784341)
		(end 154.904443 98.812157)
		(width 0.1)
		(layer "In2.Cu")
		(net 497)
	)
	(segment
		(start 155.404443 98.812157)
		(end 155.404443 99.058127)
		(width 0.1)
		(layer "In2.Cu")
		(net 497)
	)
	(segment
		(start 155.251627 98.690291)
		(end 155.279443 98.687157)
		(width 0.1)
		(layer "In2.Cu")
		(net 497)
	)
	(segment
		(start 158.186328 98.687157)
		(end 158.680728 99.181557)
		(width 0.1)
		(layer "In2.Cu")
		(net 497)
	)
	(segment
		(start 155.029443 99.183127)
		(end 155.057258 99.179992)
		(width 0.1)
		(layer "In2.Cu")
		(net 497)
	)
	(segment
		(start 158.680728 99.181557)
		(end 159.377928 99.181557)
		(width 0.1)
		(layer "In2.Cu")
		(net 497)
	)
	(segment
		(start 155.407577 99.085942)
		(end 155.416821 99.112362)
		(width 0.1)
		(layer "In2.Cu")
		(net 497)
	)
	(segment
		(start 156.142064 99.112362)
		(end 156.151308 99.085942)
		(width 0.1)
		(layer "In2.Cu")
		(net 497)
	)
	(segment
		(start 155.654443 99.058127)
		(end 155.654443 98.812157)
		(width 0.1)
		(layer "In2.Cu")
		(net 497)
	)
	(segment
		(start 156.001627 99.179992)
		(end 156.029443 99.183127)
		(width 0.1)
		(layer "In2.Cu")
		(net 497)
	)
	(segment
		(start 159.377928 99.181557)
		(end 160.051129 99.854758)
		(width 0.1)
		(layer "In2.Cu")
		(net 497)
	)
	(segment
		(start 156.279443 98.687157)
		(end 158.186328 98.687157)
		(width 0.1)
		(layer "In2.Cu")
		(net 497)
	)
	(segment
		(start 154.907577 99.085942)
		(end 154.916821 99.112362)
		(width 0.1)
		(layer "In2.Cu")
		(net 497)
	)
	(segment
		(start 155.225207 98.699535)
		(end 155.251627 98.690291)
		(width 0.1)
		(layer "In2.Cu")
		(net 497)
	)
	(segment
		(start 156.181714 98.73422)
		(end 156.201506 98.714428)
		(width 0.1)
		(layer "In2.Cu")
		(net 497)
	)
	(segment
		(start 154.779443 98.687157)
		(end 154.807258 98.690291)
		(width 0.1)
		(layer "In2.Cu")
		(net 497)
	)
	(segment
		(start 155.877171 98.73422)
		(end 155.892064 98.757921)
		(width 0.1)
		(layer "In2.Cu")
		(net 497)
	)
	(segment
		(start 155.154443 98.812157)
		(end 155.157577 98.784341)
		(width 0.1)
		(layer "In2.Cu")
		(net 497)
	)
	(segment
		(start 155.642064 99.112362)
		(end 155.651308 99.085942)
		(width 0.1)
		(layer "In2.Cu")
		(net 497)
	)
	(segment
		(start 155.807258 98.690291)
		(end 155.833678 98.699535)
		(width 0.1)
		(layer "In2.Cu")
		(net 497)
	)
	(segment
		(start 155.657577 98.784341)
		(end 155.666821 98.757921)
		(width 0.1)
		(layer "In2.Cu")
		(net 497)
	)
	(segment
		(start 155.751627 98.690291)
		(end 155.779443 98.687157)
		(width 0.1)
		(layer "In2.Cu")
		(net 497)
	)
	(segment
		(start 155.725207 98.699535)
		(end 155.751627 98.690291)
		(width 0.1)
		(layer "In2.Cu")
		(net 497)
	)
	(segment
		(start 155.901308 98.784341)
		(end 155.904443 98.812157)
		(width 0.1)
		(layer "In2.Cu")
		(net 497)
	)
	(segment
		(start 156.151308 99.085942)
		(end 156.154443 99.058127)
		(width 0.1)
		(layer "In2.Cu")
		(net 497)
	)
	(segment
		(start 154.807258 98.690291)
		(end 154.833678 98.699535)
		(width 0.1)
		(layer "In2.Cu")
		(net 497)
	)
	(segment
		(start 154.857379 98.714428)
		(end 154.877171 98.73422)
		(width 0.1)
		(layer "In2.Cu")
		(net 497)
	)
	(segment
		(start 155.501627 99.179992)
		(end 155.529443 99.183127)
		(width 0.1)
		(layer "In2.Cu")
		(net 497)
	)
	(segment
		(start 155.057258 99.179992)
		(end 155.083678 99.170748)
		(width 0.1)
		(layer "In2.Cu")
		(net 497)
	)
	(segment
		(start 155.892064 98.757921)
		(end 155.901308 98.784341)
		(width 0.1)
		(layer "In2.Cu")
		(net 497)
	)
	(segment
		(start 154.975207 99.170748)
		(end 155.001627 99.179992)
		(width 0.1)
		(layer "In2.Cu")
		(net 497)
	)
	(segment
		(start 153.803528 98.687157)
		(end 154.779443 98.687157)
		(width 0.1)
		(layer "In2.Cu")
		(net 497)
	)
	(segment
		(start 155.654443 98.812157)
		(end 155.657577 98.784341)
		(width 0.1)
		(layer "In2.Cu")
		(net 497)
	)
	(segment
		(start 155.529443 99.183127)
		(end 155.557258 99.179992)
		(width 0.1)
		(layer "In2.Cu")
		(net 497)
	)
	(segment
		(start 155.904443 99.058127)
		(end 155.907577 99.085942)
		(width 0.1)
		(layer "In2.Cu")
		(net 497)
	)
	(segment
		(start 155.557258 99.179992)
		(end 155.583678 99.170748)
		(width 0.1)
		(layer "In2.Cu")
		(net 497)
	)
	(segment
		(start 155.127171 99.136063)
		(end 155.142064 99.112362)
		(width 0.1)
		(layer "In2.Cu")
		(net 497)
	)
	(segment
		(start 156.251627 98.690291)
		(end 156.279443 98.687157)
		(width 0.1)
		(layer "In2.Cu")
		(net 497)
	)
	(segment
		(start 154.904443 98.812157)
		(end 154.904443 99.058127)
		(width 0.1)
		(layer "In2.Cu")
		(net 497)
	)
	(segment
		(start 155.401308 98.784341)
		(end 155.404443 98.812157)
		(width 0.1)
		(layer "In2.Cu")
		(net 497)
	)
	(segment
		(start 155.201506 98.714428)
		(end 155.225207 98.699535)
		(width 0.1)
		(layer "In2.Cu")
		(net 497)
	)
	(segment
		(start 155.666821 98.757921)
		(end 155.681714 98.73422)
		(width 0.1)
		(layer "In2.Cu")
		(net 497)
	)
	(segment
		(start 155.404443 99.058127)
		(end 155.407577 99.085942)
		(width 0.1)
		(layer "In2.Cu")
		(net 497)
	)
	(segment
		(start 156.157577 98.784341)
		(end 156.166821 98.757921)
		(width 0.1)
		(layer "In2.Cu")
		(net 497)
	)
	(segment
		(start 155.083678 99.170748)
		(end 155.107379 99.155855)
		(width 0.1)
		(layer "In2.Cu")
		(net 497)
	)
	(segment
		(start 156.029443 99.183127)
		(end 156.057258 99.179992)
		(width 0.1)
		(layer "In2.Cu")
		(net 497)
	)
	(segment
		(start 155.392064 98.757921)
		(end 155.401308 98.784341)
		(width 0.1)
		(layer "In2.Cu")
		(net 497)
	)
	(segment
		(start 155.154443 99.058127)
		(end 155.154443 98.812157)
		(width 0.1)
		(layer "In2.Cu")
		(net 497)
	)
	(segment
		(start 155.142064 99.112362)
		(end 155.151308 99.085942)
		(width 0.1)
		(layer "In2.Cu")
		(net 497)
	)
	(segment
		(start 155.857379 98.714428)
		(end 155.877171 98.73422)
		(width 0.1)
		(layer "In2.Cu")
		(net 497)
	)
	(segment
		(start 155.779443 98.687157)
		(end 155.807258 98.690291)
		(width 0.1)
		(layer "In2.Cu")
		(net 497)
	)
	(segment
		(start 155.451506 99.155855)
		(end 155.475207 99.170748)
		(width 0.1)
		(layer "In2.Cu")
		(net 497)
	)
	(segment
		(start 155.181714 98.73422)
		(end 155.201506 98.714428)
		(width 0.1)
		(layer "In2.Cu")
		(net 497)
	)
	(segment
		(start 154.916821 99.112362)
		(end 154.931714 99.136063)
		(width 0.1)
		(layer "In2.Cu")
		(net 497)
	)
	(segment
		(start 154.892064 98.757921)
		(end 154.901308 98.784341)
		(width 0.1)
		(layer "In2.Cu")
		(net 497)
	)
	(segment
		(start 156.127171 99.136063)
		(end 156.142064 99.112362)
		(width 0.1)
		(layer "In2.Cu")
		(net 497)
	)
	(segment
		(start 155.907577 99.085942)
		(end 155.916821 99.112362)
		(width 0.1)
		(layer "In2.Cu")
		(net 497)
	)
	(segment
		(start 155.107379 99.155855)
		(end 155.127171 99.136063)
		(width 0.1)
		(layer "In2.Cu")
		(net 497)
	)
	(segment
		(start 155.151308 99.085942)
		(end 155.154443 99.058127)
		(width 0.1)
		(layer "In2.Cu")
		(net 497)
	)
	(segment
		(start 155.431714 99.136063)
		(end 155.451506 99.155855)
		(width 0.1)
		(layer "In2.Cu")
		(net 497)
	)
	(segment
		(start 155.681714 98.73422)
		(end 155.701506 98.714428)
		(width 0.1)
		(layer "In2.Cu")
		(net 497)
	)
	(segment
		(start 155.333678 98.699535)
		(end 155.357379 98.714428)
		(width 0.1)
		(layer "In2.Cu")
		(net 497)
	)
	(segment
		(start 155.607379 99.155855)
		(end 155.627171 99.136063)
		(width 0.1)
		(layer "In2.Cu")
		(net 497)
	)
	(segment
		(start 154.833678 98.699535)
		(end 154.857379 98.714428)
		(width 0.1)
		(layer "In2.Cu")
		(net 497)
	)
	(segment
		(start 155.951506 99.155855)
		(end 155.975207 99.170748)
		(width 0.1)
		(layer "In2.Cu")
		(net 497)
	)
	(segment
		(start 155.416821 99.112362)
		(end 155.431714 99.136063)
		(width 0.1)
		(layer "In2.Cu")
		(net 497)
	)
	(segment
		(start 156.107379 99.155855)
		(end 156.127171 99.136063)
		(width 0.1)
		(layer "In2.Cu")
		(net 497)
	)
	(segment
		(start 156.201506 98.714428)
		(end 156.225207 98.699535)
		(width 0.1)
		(layer "In2.Cu")
		(net 497)
	)
	(segment
		(start 154.904443 99.058127)
		(end 154.907577 99.085942)
		(width 0.1)
		(layer "In2.Cu")
		(net 497)
	)
	(segment
		(start 156.166821 98.757921)
		(end 156.181714 98.73422)
		(width 0.1)
		(layer "In2.Cu")
		(net 497)
	)
	(segment
		(start 155.001627 99.179992)
		(end 155.029443 99.183127)
		(width 0.1)
		(layer "In2.Cu")
		(net 497)
	)
	(segment
		(start 156.057258 99.179992)
		(end 156.083678 99.170748)
		(width 0.1)
		(layer "In2.Cu")
		(net 497)
	)
	(segment
		(start 156.154443 99.058127)
		(end 156.154443 98.812157)
		(width 0.1)
		(layer "In2.Cu")
		(net 497)
	)
	(segment
		(start 155.583678 99.170748)
		(end 155.607379 99.155855)
		(width 0.1)
		(layer "In2.Cu")
		(net 497)
	)
	(segment
		(start 156.154443 98.812157)
		(end 156.157577 98.784341)
		(width 0.1)
		(layer "In2.Cu")
		(net 497)
	)
	(segment
		(start 155.701506 98.714428)
		(end 155.725207 98.699535)
		(width 0.1)
		(layer "In2.Cu")
		(net 497)
	)
	(segment
		(start 155.651308 99.085942)
		(end 155.654443 99.058127)
		(width 0.1)
		(layer "In2.Cu")
		(net 497)
	)
	(segment
		(start 155.833678 98.699535)
		(end 155.857379 98.714428)
		(width 0.1)
		(layer "In2.Cu")
		(net 497)
	)
	(segment
		(start 155.975207 99.170748)
		(end 156.001627 99.179992)
		(width 0.1)
		(layer "In2.Cu")
		(net 497)
	)
	(segment
		(start 155.916821 99.112362)
		(end 155.931714 99.136063)
		(width 0.1)
		(layer "In2.Cu")
		(net 497)
	)
	(segment
		(start 155.904443 98.812157)
		(end 155.904443 99.058127)
		(width 0.1)
		(layer "In2.Cu")
		(net 497)
	)
	(segment
		(start 160.051129 99.854758)
		(end 160.051129 100.012357)
		(width 0.1)
		(layer "In2.Cu")
		(net 497)
	)
	(segment
		(start 155.279443 98.687157)
		(end 155.307258 98.690291)
		(width 0.1)
		(layer "In2.Cu")
		(net 497)
	)
	(segment
		(start 155.377171 98.73422)
		(end 155.392064 98.757921)
		(width 0.1)
		(layer "In2.Cu")
		(net 497)
	)
	(segment
		(start 155.357379 98.714428)
		(end 155.377171 98.73422)
		(width 0.1)
		(layer "In2.Cu")
		(net 497)
	)
	(segment
		(start 155.931714 99.136063)
		(end 155.951506 99.155855)
		(width 0.1)
		(layer "In2.Cu")
		(net 497)
	)
	(segment
		(start 154.951506 99.155855)
		(end 154.975207 99.170748)
		(width 0.1)
		(layer "In2.Cu")
		(net 497)
	)
	(segment
		(start 154.931714 99.136063)
		(end 154.951506 99.155855)
		(width 0.1)
		(layer "In2.Cu")
		(net 497)
	)
	(segment
		(start 150.295419 98.990497)
		(end 150.287502 98.98258)
		(width 0.1)
		(layer "F.Cu")
		(net 498)
	)
	(segment
		(start 150.695157 100.250757)
		(end 150.206328 99.761928)
		(width 0.1)
		(layer "F.Cu")
		(net 498)
	)
	(segment
		(start 149.981557 98.267157)
		(end 149.687828 98.267157)
		(width 0.1)
		(layer "F.Cu")
		(net 498)
	)
	(segment
		(start 150.211279 99.199977)
		(end 150.217236 99.190497)
		(width 0.1)
		(layer "F.Cu")
		(net 498)
	)
	(segment
		(start 150.04398 98.949855)
		(end 150.028145 98.93402)
		(width 0.1)
		(layer "F.Cu")
		(net 498)
	)
	(segment
		(start 150.016232 98.828283)
		(end 150.028145 98.809323)
		(width 0.1)
		(layer "F.Cu")
		(net 498)
	)
	(segment
		(start 150.084076 98.969164)
		(end 150.06294 98.961768)
		(width 0.1)
		(layer "F.Cu")
		(net 498)
	)
	(segment
		(start 150.06294 98.961768)
		(end 150.04398 98.949855)
		(width 0.1)
		(layer "F.Cu")
		(net 498)
	)
	(segment
		(start 150.106328 98.971672)
		(end 150.084076 98.969164)
		(width 0.1)
		(layer "F.Cu")
		(net 498)
	)
	(segment
		(start 150.04398 98.793488)
		(end 150.06294 98.781575)
		(width 0.1)
		(layer "F.Cu")
		(net 498)
	)
	(segment
		(start 150.203821 98.693924)
		(end 150.206328 98.671672)
		(width 0.1)
		(layer "F.Cu")
		(net 498)
	)
	(segment
		(start 154.007194 100.250757)
		(end 150.695157 100.250757)
		(width 0.1)
		(layer "F.Cu")
		(net 498)
	)
	(segment
		(start 150.305074 99.132798)
		(end 150.306328 99.121672)
		(width 0.1)
		(layer "F.Cu")
		(net 498)
	)
	(segment
		(start 150.295419 99.152846)
		(end 150.301376 99.143366)
		(width 0.1)
		(layer "F.Cu")
		(net 498)
	)
	(segment
		(start 150.245201 99.172925)
		(end 150.267454 99.170418)
		(width 0.1)
		(layer "F.Cu")
		(net 498)
	)
	(segment
		(start 150.168677 98.749855)
		(end 150.184512 98.73402)
		(width 0.1)
		(layer "F.Cu")
		(net 498)
	)
	(segment
		(start 150.256328 98.971672)
		(end 150.106328 98.971672)
		(width 0.1)
		(layer "F.Cu")
		(net 498)
	)
	(segment
		(start 150.06294 98.781575)
		(end 150.084076 98.774179)
		(width 0.1)
		(layer "F.Cu")
		(net 498)
	)
	(segment
		(start 150.301376 99.143366)
		(end 150.305074 99.132798)
		(width 0.1)
		(layer "F.Cu")
		(net 498)
	)
	(segment
		(start 150.306328 99.021672)
		(end 150.305074 99.010545)
		(width 0.1)
		(layer "F.Cu")
		(net 498)
	)
	(segment
		(start 150.287502 98.98258)
		(end 150.278022 98.976623)
		(width 0.1)
		(layer "F.Cu")
		(net 498)
	)
	(segment
		(start 158.186328 99.847157)
		(end 154.410794 99.847157)
		(width 0.1)
		(layer "F.Cu")
		(net 498)
	)
	(segment
		(start 150.008836 98.849419)
		(end 150.016232 98.828283)
		(width 0.1)
		(layer "F.Cu")
		(net 498)
	)
	(segment
		(start 150.225153 99.18258)
		(end 150.234633 99.176623)
		(width 0.1)
		(layer "F.Cu")
		(net 498)
	)
	(segment
		(start 150.267454 98.972925)
		(end 150.256328 98.971672)
		(width 0.1)
		(layer "F.Cu")
		(net 498)
	)
	(segment
		(start 150.287502 99.160763)
		(end 150.295419 99.152846)
		(width 0.1)
		(layer "F.Cu")
		(net 498)
	)
	(segment
		(start 150.207581 99.210545)
		(end 150.211279 99.199977)
		(width 0.1)
		(layer "F.Cu")
		(net 498)
	)
	(segment
		(start 150.301376 98.999977)
		(end 150.295419 98.990497)
		(width 0.1)
		(layer "F.Cu")
		(net 498)
	)
	(segment
		(start 150.278022 99.16672)
		(end 150.287502 99.160763)
		(width 0.1)
		(layer "F.Cu")
		(net 498)
	)
	(segment
		(start 150.084076 98.774179)
		(end 150.128581 98.769164)
		(width 0.1)
		(layer "F.Cu")
		(net 498)
	)
	(segment
		(start 150.306328 99.121672)
		(end 150.306328 99.021672)
		(width 0.1)
		(layer "F.Cu")
		(net 498)
	)
	(segment
		(start 150.206328 99.221672)
		(end 150.207581 99.210545)
		(width 0.1)
		(layer "F.Cu")
		(net 498)
	)
	(segment
		(start 150.008836 98.893924)
		(end 150.006328 98.871672)
		(width 0.1)
		(layer "F.Cu")
		(net 498)
	)
	(segment
		(start 150.267454 99.170418)
		(end 150.278022 99.16672)
		(width 0.1)
		(layer "F.Cu")
		(net 498)
	)
	(segment
		(start 154.410794 99.847157)
		(end 154.007194 100.250757)
		(width 0.1)
		(layer "F.Cu")
		(net 498)
	)
	(segment
		(start 150.206328 99.761928)
		(end 150.206328 99.221672)
		(width 0.1)
		(layer "F.Cu")
		(net 498)
	)
	(segment
		(start 150.278022 98.976623)
		(end 150.267454 98.972925)
		(width 0.1)
		(layer "F.Cu")
		(net 498)
	)
	(segment
		(start 158.536328 99.497157)
		(end 158.186328 99.847157)
		(width 0.1)
		(layer "F.Cu")
		(net 498)
	)
	(segment
		(start 150.006328 98.871672)
		(end 150.008836 98.849419)
		(width 0.1)
		(layer "F.Cu")
		(net 498)
	)
	(segment
		(start 150.028145 98.809323)
		(end 150.04398 98.793488)
		(width 0.1)
		(layer "F.Cu")
		(net 498)
	)
	(segment
		(start 150.184512 98.73402)
		(end 150.196425 98.71506)
		(width 0.1)
		(layer "F.Cu")
		(net 498)
	)
	(segment
		(start 150.234633 99.176623)
		(end 150.245201 99.172925)
		(width 0.1)
		(layer "F.Cu")
		(net 498)
	)
	(segment
		(start 150.196425 98.71506)
		(end 150.203821 98.693924)
		(width 0.1)
		(layer "F.Cu")
		(net 498)
	)
	(segment
		(start 150.305074 99.010545)
		(end 150.301376 98.999977)
		(width 0.1)
		(layer "F.Cu")
		(net 498)
	)
	(segment
		(start 150.149717 98.761768)
		(end 150.168677 98.749855)
		(width 0.1)
		(layer "F.Cu")
		(net 498)
	)
	(segment
		(start 150.217236 99.190497)
		(end 150.225153 99.18258)
		(width 0.1)
		(layer "F.Cu")
		(net 498)
	)
	(segment
		(start 150.016232 98.91506)
		(end 150.008836 98.893924)
		(width 0.1)
		(layer "F.Cu")
		(net 498)
	)
	(segment
		(start 150.206328 98.491928)
		(end 149.981557 98.267157)
		(width 0.1)
		(layer "F.Cu")
		(net 498)
	)
	(segment
		(start 150.028145 98.93402)
		(end 150.016232 98.91506)
		(width 0.1)
		(layer "F.Cu")
		(net 498)
	)
	(segment
		(start 150.128581 98.769164)
		(end 150.149717 98.761768)
		(width 0.1)
		(layer "F.Cu")
		(net 498)
	)
	(segment
		(start 150.206328 98.671672)
		(end 150.206328 98.491928)
		(width 0.1)
		(layer "F.Cu")
		(net 498)
	)
	(segment
		(start 161.536329 98.507156)
		(end 161.036329 98.007157)
		(width 0.15)
		(layer "F.Cu")
		(net 499)
	)
	(segment
		(start 151.706329 96.285358)
		(end 152.206328 95.785358)
		(width 0.15)
		(layer "F.Cu")
		(net 499)
	)
	(via blind
		(at 152.206328 95.785358)
		(size 0.5)
		(drill 0.2)
		(layers "F.Cu" "In2.Cu")
		(net 499)
	)
	(via blind
		(at 161.026329 97.997157)
		(size 0.5)
		(drill 0.2)
		(layers "F.Cu" "In2.Cu")
		(net 499)
	)
	(segment
		(start 152.756341 96.212585)
		(end 152.768254 96.193625)
		(width 0.1)
		(layer "In2.Cu")
		(net 499)
	)
	(segment
		(start 152.780665 95.863105)
		(end 152.788061 95.841969)
		(width 0.1)
		(layer "In2.Cu")
		(net 499)
	)
	(segment
		(start 152.556341 95.823009)
		(end 152.568254 95.841969)
		(width 0.1)
		(layer "In2.Cu")
		(net 499)
	)
	(segment
		(start 152.578158 96.150237)
		(end 152.580665 96.172489)
		(width 0.1)
		(layer "In2.Cu")
		(net 499)
	)
	(segment
		(start 152.740506 96.22842)
		(end 152.756341 96.212585)
		(width 0.1)
		(layer "In2.Cu")
		(net 499)
	)
	(segment
		(start 152.721546 96.240333)
		(end 152.740506 96.22842)
		(width 0.1)
		(layer "In2.Cu")
		(net 499)
	)
	(segment
		(start 152.580665 96.172489)
		(end 152.588061 96.193625)
		(width 0.1)
		(layer "In2.Cu")
		(net 499)
	)
	(segment
		(start 152.768254 96.193625)
		(end 152.77565 96.172489)
		(width 0.1)
		(layer "In2.Cu")
		(net 499)
	)
	(segment
		(start 152.588061 96.193625)
		(end 152.599974 96.212585)
		(width 0.1)
		(layer "In2.Cu")
		(net 499)
	)
	(segment
		(start 152.655905 96.247729)
		(end 152.678158 96.250237)
		(width 0.1)
		(layer "In2.Cu")
		(net 499)
	)
	(segment
		(start 152.799974 95.823009)
		(end 152.815809 95.807174)
		(width 0.1)
		(layer "In2.Cu")
		(net 499)
	)
	(segment
		(start 152.778158 95.885358)
		(end 152.780665 95.863105)
		(width 0.1)
		(layer "In2.Cu")
		(net 499)
	)
	(segment
		(start 152.615809 96.22842)
		(end 152.634769 96.240333)
		(width 0.1)
		(layer "In2.Cu")
		(net 499)
	)
	(segment
		(start 152.521546 95.795261)
		(end 152.540506 95.807174)
		(width 0.1)
		(layer "In2.Cu")
		(net 499)
	)
	(segment
		(start 152.568254 95.841969)
		(end 152.57565 95.863105)
		(width 0.1)
		(layer "In2.Cu")
		(net 499)
	)
	(segment
		(start 152.855905 95.787865)
		(end 152.878158 95.785358)
		(width 0.1)
		(layer "In2.Cu")
		(net 499)
	)
	(segment
		(start 152.678158 96.250237)
		(end 152.70041 96.247729)
		(width 0.1)
		(layer "In2.Cu")
		(net 499)
	)
	(segment
		(start 152.834769 95.795261)
		(end 152.855905 95.787865)
		(width 0.1)
		(layer "In2.Cu")
		(net 499)
	)
	(segment
		(start 152.77565 96.172489)
		(end 152.778158 96.150237)
		(width 0.1)
		(layer "In2.Cu")
		(net 499)
	)
	(segment
		(start 152.70041 96.247729)
		(end 152.721546 96.240333)
		(width 0.1)
		(layer "In2.Cu")
		(net 499)
	)
	(segment
		(start 152.578158 95.885358)
		(end 152.578158 96.150237)
		(width 0.1)
		(layer "In2.Cu")
		(net 499)
	)
	(segment
		(start 152.634769 96.240333)
		(end 152.655905 96.247729)
		(width 0.1)
		(layer "In2.Cu")
		(net 499)
	)
	(segment
		(start 152.50041 95.787865)
		(end 152.521546 95.795261)
		(width 0.1)
		(layer "In2.Cu")
		(net 499)
	)
	(segment
		(start 153.234062 95.785358)
		(end 154.725861 97.277157)
		(width 0.1)
		(layer "In2.Cu")
		(net 499)
	)
	(segment
		(start 152.788061 95.841969)
		(end 152.799974 95.823009)
		(width 0.1)
		(layer "In2.Cu")
		(net 499)
	)
	(segment
		(start 152.478158 95.785358)
		(end 152.50041 95.787865)
		(width 0.1)
		(layer "In2.Cu")
		(net 499)
	)
	(segment
		(start 152.206328 95.785358)
		(end 152.478158 95.785358)
		(width 0.1)
		(layer "In2.Cu")
		(net 499)
	)
	(segment
		(start 152.815809 95.807174)
		(end 152.834769 95.795261)
		(width 0.1)
		(layer "In2.Cu")
		(net 499)
	)
	(segment
		(start 160.306329 97.277157)
		(end 161.026329 97.997157)
		(width 0.1)
		(layer "In2.Cu")
		(net 499)
	)
	(segment
		(start 154.725861 97.277157)
		(end 160.306329 97.277157)
		(width 0.1)
		(layer "In2.Cu")
		(net 499)
	)
	(segment
		(start 152.540506 95.807174)
		(end 152.556341 95.823009)
		(width 0.1)
		(layer "In2.Cu")
		(net 499)
	)
	(segment
		(start 152.599974 96.212585)
		(end 152.615809 96.22842)
		(width 0.1)
		(layer "In2.Cu")
		(net 499)
	)
	(segment
		(start 152.878158 95.785358)
		(end 153.234062 95.785358)
		(width 0.1)
		(layer "In2.Cu")
		(net 499)
	)
	(segment
		(start 152.778158 96.150237)
		(end 152.778158 95.885358)
		(width 0.1)
		(layer "In2.Cu")
		(net 499)
	)
	(segment
		(start 152.57565 95.863105)
		(end 152.578158 95.885358)
		(width 0.1)
		(layer "In2.Cu")
		(net 499)
	)
	(segment
		(start 150.704442 96.259527)
		(end 150.204443 96.759527)
		(width 0.15)
		(layer "F.Cu")
		(net 500)
	)
	(segment
		(start 159.536329 98.517156)
		(end 159.036329 98.017157)
		(width 0.15)
		(layer "F.Cu")
		(net 500)
	)
	(via blind
		(at 150.204443 96.759527)
		(size 0.5)
		(drill 0.2)
		(layers "F.Cu" "In2.Cu")
		(net 500)
	)
	(via blind
		(at 159.036329 98.017157)
		(size 0.5)
		(drill 0.2)
		(layers "F.Cu" "In2.Cu")
		(net 500)
	)
	(segment
		(start 151.269367 96.685861)
		(end 151.250407 96.697774)
		(width 0.1)
		(layer "In2.Cu")
		(net 500)
	)
	(segment
		(start 151.312756 96.675958)
		(end 151.290503 96.678465)
		(width 0.1)
		(layer "In2.Cu")
		(net 500)
	)
	(segment
		(start 151.375104 96.697774)
		(end 151.356144 96.685861)
		(width 0.1)
		(layer "In2.Cu")
		(net 500)
	)
	(segment
		(start 151.490503 96.976448)
		(end 151.469367 96.969052)
		(width 0.1)
		(layer "In2.Cu")
		(net 500)
	)
	(segment
		(start 151.469367 96.969052)
		(end 151.450407 96.957139)
		(width 0.1)
		(layer "In2.Cu")
		(net 500)
	)
	(segment
		(start 151.412756 96.775958)
		(end 151.410248 96.753705)
		(width 0.1)
		(layer "In2.Cu")
		(net 500)
	)
	(segment
		(start 151.175104 96.957139)
		(end 151.156144 96.969052)
		(width 0.1)
		(layer "In2.Cu")
		(net 500)
	)
	(segment
		(start 151.112756 96.978956)
		(end 150.423872 96.978956)
		(width 0.1)
		(layer "In2.Cu")
		(net 500)
	)
	(segment
		(start 151.156144 96.969052)
		(end 151.135008 96.976448)
		(width 0.1)
		(layer "In2.Cu")
		(net 500)
	)
	(segment
		(start 151.422659 96.922344)
		(end 151.415263 96.901208)
		(width 0.1)
		(layer "In2.Cu")
		(net 500)
	)
	(segment
		(start 151.212756 96.775958)
		(end 151.212756 96.878956)
		(width 0.1)
		(layer "In2.Cu")
		(net 500)
	)
	(segment
		(start 151.250407 96.697774)
		(end 151.234572 96.713609)
		(width 0.1)
		(layer "In2.Cu")
		(net 500)
	)
	(segment
		(start 151.402852 96.732569)
		(end 151.390939 96.713609)
		(width 0.1)
		(layer "In2.Cu")
		(net 500)
	)
	(segment
		(start 151.410248 96.753705)
		(end 151.402852 96.732569)
		(width 0.1)
		(layer "In2.Cu")
		(net 500)
	)
	(segment
		(start 151.202852 96.922344)
		(end 151.190939 96.941304)
		(width 0.1)
		(layer "In2.Cu")
		(net 500)
	)
	(segment
		(start 151.190939 96.941304)
		(end 151.175104 96.957139)
		(width 0.1)
		(layer "In2.Cu")
		(net 500)
	)
	(segment
		(start 151.135008 96.976448)
		(end 151.112756 96.978956)
		(width 0.1)
		(layer "In2.Cu")
		(net 500)
	)
	(segment
		(start 151.356144 96.685861)
		(end 151.335008 96.678465)
		(width 0.1)
		(layer "In2.Cu")
		(net 500)
	)
	(segment
		(start 153.720524 96.978956)
		(end 151.512756 96.978956)
		(width 0.1)
		(layer "In2.Cu")
		(net 500)
	)
	(segment
		(start 151.335008 96.678465)
		(end 151.312756 96.675958)
		(width 0.1)
		(layer "In2.Cu")
		(net 500)
	)
	(segment
		(start 151.290503 96.678465)
		(end 151.269367 96.685861)
		(width 0.1)
		(layer "In2.Cu")
		(net 500)
	)
	(segment
		(start 151.512756 96.978956)
		(end 151.490503 96.976448)
		(width 0.1)
		(layer "In2.Cu")
		(net 500)
	)
	(segment
		(start 151.210248 96.901208)
		(end 151.202852 96.922344)
		(width 0.1)
		(layer "In2.Cu")
		(net 500)
	)
	(segment
		(start 151.234572 96.713609)
		(end 151.222659 96.732569)
		(width 0.1)
		(layer "In2.Cu")
		(net 500)
	)
	(segment
		(start 151.212756 96.878956)
		(end 151.210248 96.901208)
		(width 0.1)
		(layer "In2.Cu")
		(net 500)
	)
	(segment
		(start 150.423872 96.978956)
		(end 150.204443 96.759527)
		(width 0.1)
		(layer "In2.Cu")
		(net 500)
	)
	(segment
		(start 154.598725 97.857157)
		(end 153.720524 96.978956)
		(width 0.1)
		(layer "In2.Cu")
		(net 500)
	)
	(segment
		(start 151.215263 96.753705)
		(end 151.212756 96.775958)
		(width 0.1)
		(layer "In2.Cu")
		(net 500)
	)
	(segment
		(start 151.412756 96.878956)
		(end 151.412756 96.775958)
		(width 0.1)
		(layer "In2.Cu")
		(net 500)
	)
	(segment
		(start 151.415263 96.901208)
		(end 151.412756 96.878956)
		(width 0.1)
		(layer "In2.Cu")
		(net 500)
	)
	(segment
		(start 159.036329 98.017157)
		(end 158.876329 97.857157)
		(width 0.1)
		(layer "In2.Cu")
		(net 500)
	)
	(segment
		(start 151.434572 96.941304)
		(end 151.422659 96.922344)
		(width 0.1)
		(layer "In2.Cu")
		(net 500)
	)
	(segment
		(start 151.222659 96.732569)
		(end 151.215263 96.753705)
		(width 0.1)
		(layer "In2.Cu")
		(net 500)
	)
	(segment
		(start 151.450407 96.957139)
		(end 151.434572 96.941304)
		(width 0.1)
		(layer "In2.Cu")
		(net 500)
	)
	(segment
		(start 158.876329 97.857157)
		(end 154.598725 97.857157)
		(width 0.1)
		(layer "In2.Cu")
		(net 500)
	)
	(segment
		(start 151.390939 96.713609)
		(end 151.375104 96.697774)
		(width 0.1)
		(layer "In2.Cu")
		(net 500)
	)
	(segment
		(start 169.536327 88.497158)
		(end 169.036327 88.997157)
		(width 0.15)
		(layer "F.Cu")
		(net 510)
	)
	(segment
		(start 160.536327 88.497158)
		(end 161.036327 88.997158)
		(width 0.15)
		(layer "F.Cu")
		(net 510)
	)
	(via
		(at 169.036327 88.997157)
		(size 0.5)
		(drill 0.2)
		(layers "F.Cu" "B.Cu")
		(net 510)
	)
	(via
		(at 161.036327 88.997158)
		(size 0.5)
		(drill 0.2)
		(layers "F.Cu" "B.Cu")
		(net 510)
	)
	(segment
		(start 169.036327 89.612156)
		(end 169.036328 89.612157)
		(width 0.2)
		(layer "B.Cu")
		(net 510)
	)
	(segment
		(start 161.021328 89.012157)
		(end 161.036327 88.997158)
		(width 0.2)
		(layer "B.Cu")
		(net 510)
	)
	(segment
		(start 169.036327 88.997157)
		(end 169.036327 89.612156)
		(width 0.2)
		(layer "B.Cu")
		(net 510)
	)
	(segment
		(start 168.136328 88.497157)
		(end 168.636329 88.997158)
		(width 0.15)
		(layer "B.Cu")
		(net 510)
	)
	(segment
		(start 161.536328 88.497157)
		(end 168.136328 88.497157)
		(width 0.15)
		(layer "B.Cu")
		(net 510)
	)
	(segment
		(start 156.936328 89.697157)
		(end 156.936328 88.497157)
		(width 0.2)
		(layer "B.Cu")
		(net 510)
	)
	(segment
		(start 161.021328 89.797157)
		(end 161.021328 89.012157)
		(width 0.2)
		(layer "B.Cu")
		(net 510)
	)
	(segment
		(start 168.682773 88.997158)
		(end 169.036327 88.997157)
		(width 0.15)
		(layer "B.Cu")
		(net 510)
	)
	(segment
		(start 161.036327 88.997158)
		(end 161.536328 88.497157)
		(width 0.15)
		(layer "B.Cu")
		(net 510)
	)
	(segment
		(start 161.536328 88.497157)
		(end 157.136328 88.497157)
		(width 0.2)
		(layer "B.Cu")
		(net 510)
	)
	(segment
		(start 168.636329 88.997158)
		(end 168.682773 88.997158)
		(width 0.15)
		(layer "B.Cu")
		(net 510)
	)
	(segment
		(start 170.536328 88.497158)
		(end 171.036328 87.997158)
		(width 0.15)
		(layer "F.Cu")
		(net 511)
	)
	(via
		(at 171.036328 87.997158)
		(size 0.5)
		(drill 0.2)
		(layers "F.Cu" "B.Cu")
		(net 511)
	)
	(segment
		(start 171.036328 86.897157)
		(end 171.236328 86.697157)
		(width 0.15)
		(layer "B.Cu")
		(net 511)
	)
	(segment
		(start 171.036328 87.997158)
		(end 171.036328 86.897157)
		(width 0.15)
		(layer "B.Cu")
		(net 511)
	)
	(segment
		(start 162.536329 89.497157)
		(end 162.036329 88.997157)
		(width 0.15)
		(layer "F.Cu")
		(net 512)
	)
	(via
		(at 162.036329 88.997157)
		(size 0.5)
		(drill 0.2)
		(layers "F.Cu" "B.Cu")
		(net 512)
	)
	(segment
		(start 162.136328 89.097156)
		(end 162.036329 88.997157)
		(width 0.15)
		(layer "B.Cu")
		(net 512)
	)
	(segment
		(start 162.136328 89.997157)
		(end 162.136328 89.097156)
		(width 0.15)
		(layer "B.Cu")
		(net 512)
	)
	(segment
		(start 110.436328 115.522157)
		(end 109.962843 115.522157)
		(width 0.15)
		(layer "F.Cu")
		(net 514)
	)
	(segment
		(start 111.422157 116.297157)
		(end 112.286328 116.297157)
		(width 0.2)
		(layer "F.Cu")
		(net 514)
	)
	(segment
		(start 109.962843 115.522157)
		(end 109.785 115.7)
		(width 0.15)
		(layer "F.Cu")
		(net 514)
	)
	(segment
		(start 111.422157 116.297157)
		(end 110.647157 115.522157)
		(width 0.2)
		(layer "F.Cu")
		(net 514)
	)
	(segment
		(start 110.647157 115.522157)
		(end 110.436328 115.522157)
		(width 0.2)
		(layer "F.Cu")
		(net 514)
	)
	(segment
		(start 110.436328 115.522157)
		(end 109.652843 115.522157)
		(width 0.2)
		(layer "F.Cu")
		(net 514)
	)
	(segment
		(start 110.461328 115.497157)
		(end 110.436328 115.522157)
		(width 0.2)
		(layer "F.Cu")
		(net 514)
	)
	(via
		(at 110.436328 115.522157)
		(size 0.5)
		(drill 0.2)
		(layers "F.Cu" "B.Cu")
		(net 514)
	)
	(via
		(at 109.65 119.35)
		(size 0.5)
		(drill 0.2)
		(layers "F.Cu" "B.Cu")
		(net 514)
	)
	(segment
		(start 110.436328 119.063672)
		(end 110.15 119.35)
		(width 0.2)
		(layer "B.Cu")
		(net 514)
	)
	(segment
		(start 110.436328 115.522157)
		(end 110.436328 119.063672)
		(width 0.2)
		(layer "B.Cu")
		(net 514)
	)
	(segment
		(start 110.15 119.35)
		(end 109.65 119.35)
		(width 0.2)
		(layer "B.Cu")
		(net 514)
	)
	(segment
		(start 169.513845 126.047157)
		(end 166.713845 128.847157)
		(width 0.2)
		(layer "In2.Cu")
		(net 514)
	)
	(segment
		(start 142.747157 128.847157)
		(end 166.713845 128.847157)
		(width 0.2)
		(layer "In2.Cu")
		(net 514)
	)
	(segment
		(start 184.236328 128.147157)
		(end 180.936328 128.147157)
		(width 0.2)
		(layer "In2.Cu")
		(net 514)
	)
	(segment
		(start 178.836328 126.047157)
		(end 169.513845 126.047157)
		(width 0.2)
		(layer "In2.Cu")
		(net 514)
	)
	(segment
		(start 110.436328 115.522157)
		(end 129.422157 115.522157)
		(width 0.2)
		(layer "In2.Cu")
		(net 514)
	)
	(segment
		(start 180.936328 128.147157)
		(end 178.836328 126.047157)
		(width 0.2)
		(layer "In2.Cu")
		(net 514)
	)
	(segment
		(start 129.422157 115.522157)
		(end 142.747157 128.847157)
		(width 0.2)
		(layer "In2.Cu")
		(net 514)
	)
	(segment
		(start 200.699241 108.365648)
		(end 200.668593 108.376372)
		(width 0.14)
		(layer "F.Cu")
		(net 519)
	)
	(segment
		(start 200.781328 114.335008)
		(end 199.696328 115.420008)
		(width 0.14)
		(layer "F.Cu")
		(net 519)
	)
	(segment
		(start 199.842724 111.261299)
		(end 199.853472 111.356696)
		(width 0.14)
		(layer "F.Cu")
		(net 519)
	)
	(segment
		(start 200.276035 108.390756)
		(end 200.185422 108.422463)
		(width 0.14)
		(layer "F.Cu")
		(net 519)
	)
	(segment
		(start 200.749693 110.544601)
		(end 200.766968 110.572094)
		(width 0.14)
		(layer "F.Cu")
		(net 519)
	)
	(segment
		(start 201.637846 109.304367)
		(end 201.665339 109.321642)
		(width 0.14)
		(layer "F.Cu")
		(net 519)
	)
	(segment
		(start 199.842724 111.208716)
		(end 199.842724 111.261299)
		(width 0.14)
		(layer "F.Cu")
		(net 519)
	)
	(segment
		(start 201.574932 109.580008)
		(end 200.321432 109.580008)
		(width 0.14)
		(layer "F.Cu")
		(net 519)
	)
	(segment
		(start 200.135422 109.622463)
		(end 200.054137 109.673538)
		(width 0.14)
		(layer "F.Cu")
		(net 519)
	)
	(segment
		(start 200.226035 110.479259)
		(end 200.321432 110.490008)
		(width 0.14)
		(layer "F.Cu")
		(net 519)
	)
	(segment
		(start 200.036254 108.541421)
		(end 199.985179 108.622706)
		(width 0.14)
		(layer "F.Cu")
		(net 519)
	)
	(segment
		(start 200.636328 110.780008)
		(end 200.271432 110.780008)
		(width 0.14)
		(layer "F.Cu")
		(net 519)
	)
	(segment
		(start 201.688298 109.344601)
		(end 201.705573 109.372094)
		(width 0.14)
		(layer "F.Cu")
		(net 519)
	)
	(segment
		(start 199.985179 108.622706)
		(end 199.953472 108.713319)
		(width 0.14)
		(layer "F.Cu")
		(net 519)
	)
	(segment
		(start 199.885179 111.447309)
		(end 199.936254 111.528594)
		(width 0.14)
		(layer "F.Cu")
		(net 519)
	)
	(segment
		(start 200.176035 111.679259)
		(end 200.271432 111.690008)
		(width 0.14)
		(layer "F.Cu")
		(net 519)
	)
	(segment
		(start 200.777692 110.602742)
		(end 200.781328 110.635008)
		(width 0.14)
		(layer "F.Cu")
		(net 519)
	)
	(segment
		(start 200.777692 108.267273)
		(end 200.766968 108.297921)
		(width 0.14)
		(layer "F.Cu")
		(net 519)
	)
	(segment
		(start 200.104137 108.473538)
		(end 200.036254 108.541421)
		(width 0.14)
		(layer "F.Cu")
		(net 519)
	)
	(segment
		(start 200.766968 108.297921)
		(end 200.749693 108.325414)
		(width 0.14)
		(layer "F.Cu")
		(net 519)
	)
	(segment
		(start 199.892724 110.061299)
		(end 199.903472 110.156696)
		(width 0.14)
		(layer "F.Cu")
		(net 519)
	)
	(segment
		(start 201.705573 109.372094)
		(end 201.716297 109.402742)
		(width 0.14)
		(layer "F.Cu")
		(net 519)
	)
	(segment
		(start 200.668593 110.493643)
		(end 200.699241 110.504367)
		(width 0.14)
		(layer "F.Cu")
		(net 519)
	)
	(segment
		(start 201.637846 109.565648)
		(end 201.607198 109.576372)
		(width 0.14)
		(layer "F.Cu")
		(net 519)
	)
	(segment
		(start 200.185422 108.422463)
		(end 200.104137 108.473538)
		(width 0.14)
		(layer "F.Cu")
		(net 519)
	)
	(segment
		(start 201.719932 109.435008)
		(end 201.716297 109.467273)
		(width 0.14)
		(layer "F.Cu")
		(net 519)
	)
	(segment
		(start 200.781328 106.569306)
		(end 200.781328 108.235008)
		(width 0.14)
		(layer "F.Cu")
		(net 519)
	)
	(segment
		(start 201.607198 109.576372)
		(end 201.574932 109.580008)
		(width 0.14)
		(layer "F.Cu")
		(net 519)
	)
	(segment
		(start 200.371432 109.290008)
		(end 201.574932 109.290008)
		(width 0.14)
		(layer "F.Cu")
		(net 519)
	)
	(segment
		(start 199.942724 108.861299)
		(end 199.953472 108.956696)
		(width 0.14)
		(layer "F.Cu")
		(net 519)
	)
	(segment
		(start 200.036254 109.128594)
		(end 200.104137 109.196477)
		(width 0.14)
		(layer "F.Cu")
		(net 519)
	)
	(segment
		(start 201.716297 109.402742)
		(end 201.719932 109.435008)
		(width 0.14)
		(layer "F.Cu")
		(net 519)
	)
	(segment
		(start 200.699241 110.765648)
		(end 200.668593 110.776372)
		(width 0.14)
		(layer "F.Cu")
		(net 519)
	)
	(segment
		(start 199.903472 109.913319)
		(end 199.892724 110.008716)
		(width 0.14)
		(layer "F.Cu")
		(net 519)
	)
	(segment
		(start 201.607198 109.293643)
		(end 201.637846 109.304367)
		(width 0.14)
		(layer "F.Cu")
		(net 519)
	)
	(segment
		(start 200.686328 106.474306)
		(end 200.781328 106.569306)
		(width 0.14)
		(layer "F.Cu")
		(net 519)
	)
	(segment
		(start 199.936254 110.941421)
		(end 199.885179 111.022706)
		(width 0.14)
		(layer "F.Cu")
		(net 519)
	)
	(segment
		(start 200.226035 109.590756)
		(end 200.135422 109.622463)
		(width 0.14)
		(layer "F.Cu")
		(net 519)
	)
	(segment
		(start 200.726734 110.748373)
		(end 200.699241 110.765648)
		(width 0.14)
		(layer "F.Cu")
		(net 519)
	)
	(segment
		(start 200.321432 110.490008)
		(end 200.636328 110.490008)
		(width 0.14)
		(layer "F.Cu")
		(net 519)
	)
	(segment
		(start 201.705573 109.497921)
		(end 201.688298 109.525414)
		(width 0.14)
		(layer "F.Cu")
		(net 519)
	)
	(segment
		(start 200.636328 110.490008)
		(end 200.668593 110.493643)
		(width 0.14)
		(layer "F.Cu")
		(net 519)
	)
	(segment
		(start 199.531328 117.601551)
		(end 199.531328 118.597157)
		(width 0.14)
		(layer "F.Cu")
		(net 519)
	)
	(segment
		(start 199.985179 109.047309)
		(end 200.036254 109.128594)
		(width 0.14)
		(layer "F.Cu")
		(net 519)
	)
	(segment
		(start 201.665339 109.548373)
		(end 201.637846 109.565648)
		(width 0.14)
		(layer "F.Cu")
		(net 519)
	)
	(segment
		(start 199.935179 110.247309)
		(end 199.986254 110.328594)
		(width 0.14)
		(layer "F.Cu")
		(net 519)
	)
	(segment
		(start 201.665339 109.321642)
		(end 201.688298 109.344601)
		(width 0.14)
		(layer "F.Cu")
		(net 519)
	)
	(segment
		(start 200.321432 109.580008)
		(end 200.226035 109.590756)
		(width 0.14)
		(layer "F.Cu")
		(net 519)
	)
	(segment
		(start 199.885179 111.022706)
		(end 199.853472 111.113319)
		(width 0.14)
		(layer "F.Cu")
		(net 519)
	)
	(segment
		(start 199.986254 109.741421)
		(end 199.935179 109.822706)
		(width 0.14)
		(layer "F.Cu")
		(net 519)
	)
	(segment
		(start 200.104137 109.196477)
		(end 200.185422 109.247552)
		(width 0.14)
		(layer "F.Cu")
		(net 519)
	)
	(segment
		(start 200.636328 108.380008)
		(end 200.371432 108.380008)
		(width 0.14)
		(layer "F.Cu")
		(net 519)
	)
	(segment
		(start 199.853472 111.113319)
		(end 199.842724 111.208716)
		(width 0.14)
		(layer "F.Cu")
		(net 519)
	)
	(segment
		(start 199.696328 117.436551)
		(end 199.531328 117.601551)
		(width 0.14)
		(layer "F.Cu")
		(net 519)
	)
	(segment
		(start 200.749693 110.725414)
		(end 200.726734 110.748373)
		(width 0.14)
		(layer "F.Cu")
		(net 519)
	)
	(segment
		(start 200.749693 111.744601)
		(end 200.766968 111.772094)
		(width 0.14)
		(layer "F.Cu")
		(net 519)
	)
	(segment
		(start 200.699241 110.504367)
		(end 200.726734 110.521642)
		(width 0.14)
		(layer "F.Cu")
		(net 519)
	)
	(segment
		(start 200.004137 110.873538)
		(end 199.936254 110.941421)
		(width 0.14)
		(layer "F.Cu")
		(net 519)
	)
	(segment
		(start 200.668593 110.776372)
		(end 200.636328 110.780008)
		(width 0.14)
		(layer "F.Cu")
		(net 519)
	)
	(segment
		(start 200.276035 109.279259)
		(end 200.371432 109.290008)
		(width 0.14)
		(layer "F.Cu")
		(net 519)
	)
	(segment
		(start 201.716297 109.467273)
		(end 201.705573 109.497921)
		(width 0.14)
		(layer "F.Cu")
		(net 519)
	)
	(segment
		(start 200.781328 108.235008)
		(end 200.777692 108.267273)
		(width 0.14)
		(layer "F.Cu")
		(net 519)
	)
	(segment
		(start 201.574932 109.290008)
		(end 201.607198 109.293643)
		(width 0.14)
		(layer "F.Cu")
		(net 519)
	)
	(segment
		(start 199.936254 111.528594)
		(end 200.004137 111.596477)
		(width 0.14)
		(layer "F.Cu")
		(net 519)
	)
	(segment
		(start 200.636328 111.690008)
		(end 200.668593 111.693643)
		(width 0.14)
		(layer "F.Cu")
		(net 519)
	)
	(segment
		(start 200.781328 110.635008)
		(end 200.777692 110.667273)
		(width 0.14)
		(layer "F.Cu")
		(net 519)
	)
	(segment
		(start 200.135422 110.447552)
		(end 200.226035 110.479259)
		(width 0.14)
		(layer "F.Cu")
		(net 519)
	)
	(segment
		(start 200.271432 111.690008)
		(end 200.636328 111.690008)
		(width 0.14)
		(layer "F.Cu")
		(net 519)
	)
	(segment
		(start 199.953472 108.713319)
		(end 199.942724 108.808716)
		(width 0.14)
		(layer "F.Cu")
		(net 519)
	)
	(segment
		(start 200.668593 111.693643)
		(end 200.699241 111.704367)
		(width 0.14)
		(layer "F.Cu")
		(net 519)
	)
	(segment
		(start 200.085422 111.647552)
		(end 200.176035 111.679259)
		(width 0.14)
		(layer "F.Cu")
		(net 519)
	)
	(segment
		(start 201.688298 109.525414)
		(end 201.665339 109.548373)
		(width 0.14)
		(layer "F.Cu")
		(net 519)
	)
	(segment
		(start 199.986254 110.328594)
		(end 200.054137 110.396477)
		(width 0.14)
		(layer "F.Cu")
		(net 519)
	)
	(segment
		(start 200.777692 111.802742)
		(end 200.781328 111.835008)
		(width 0.14)
		(layer "F.Cu")
		(net 519)
	)
	(segment
		(start 200.766968 110.697921)
		(end 200.749693 110.725414)
		(width 0.14)
		(layer "F.Cu")
		(net 519)
	)
	(segment
		(start 200.726734 110.521642)
		(end 200.749693 110.544601)
		(width 0.14)
		(layer "F.Cu")
		(net 519)
	)
	(segment
		(start 200.085422 110.822463)
		(end 200.004137 110.873538)
		(width 0.14)
		(layer "F.Cu")
		(net 519)
	)
	(segment
		(start 200.004137 111.596477)
		(end 200.085422 111.647552)
		(width 0.14)
		(layer "F.Cu")
		(net 519)
	)
	(segment
		(start 199.696328 115.420008)
		(end 199.696328 117.436551)
		(width 0.14)
		(layer "F.Cu")
		(net 519)
	)
	(segment
		(start 200.749693 108.325414)
		(end 200.726734 108.348373)
		(width 0.14)
		(layer "F.Cu")
		(net 519)
	)
	(segment
		(start 199.853472 111.356696)
		(end 199.885179 111.447309)
		(width 0.14)
		(layer "F.Cu")
		(net 519)
	)
	(segment
		(start 200.781328 111.835008)
		(end 200.781328 114.335008)
		(width 0.14)
		(layer "F.Cu")
		(net 519)
	)
	(segment
		(start 200.185422 109.247552)
		(end 200.276035 109.279259)
		(width 0.14)
		(layer "F.Cu")
		(net 519)
	)
	(segment
		(start 199.953472 108.956696)
		(end 199.985179 109.047309)
		(width 0.14)
		(layer "F.Cu")
		(net 519)
	)
	(segment
		(start 200.766968 111.772094)
		(end 200.777692 111.802742)
		(width 0.14)
		(layer "F.Cu")
		(net 519)
	)
	(segment
		(start 200.371432 108.380008)
		(end 200.276035 108.390756)
		(width 0.14)
		(layer "F.Cu")
		(net 519)
	)
	(segment
		(start 200.766968 110.572094)
		(end 200.777692 110.602742)
		(width 0.14)
		(layer "F.Cu")
		(net 519)
	)
	(segment
		(start 200.176035 110.790756)
		(end 200.085422 110.822463)
		(width 0.14)
		(layer "F.Cu")
		(net 519)
	)
	(segment
		(start 200.271432 110.780008)
		(end 200.176035 110.790756)
		(width 0.14)
		(layer "F.Cu")
		(net 519)
	)
	(segment
		(start 199.942724 108.808716)
		(end 199.942724 108.861299)
		(width 0.14)
		(layer "F.Cu")
		(net 519)
	)
	(segment
		(start 199.892724 110.008716)
		(end 199.892724 110.061299)
		(width 0.14)
		(layer "F.Cu")
		(net 519)
	)
	(segment
		(start 200.668593 108.376372)
		(end 200.636328 108.380008)
		(width 0.14)
		(layer "F.Cu")
		(net 519)
	)
	(segment
		(start 200.054137 109.673538)
		(end 199.986254 109.741421)
		(width 0.14)
		(layer "F.Cu")
		(net 519)
	)
	(segment
		(start 199.903472 110.156696)
		(end 199.935179 110.247309)
		(width 0.14)
		(layer "F.Cu")
		(net 519)
	)
	(segment
		(start 200.726734 111.721642)
		(end 200.749693 111.744601)
		(width 0.14)
		(layer "F.Cu")
		(net 519)
	)
	(segment
		(start 200.699241 111.704367)
		(end 200.726734 111.721642)
		(width 0.14)
		(layer "F.Cu")
		(net 519)
	)
	(segment
		(start 199.935179 109.822706)
		(end 199.903472 109.913319)
		(width 0.14)
		(layer "F.Cu")
		(net 519)
	)
	(segment
		(start 200.054137 110.396477)
		(end 200.135422 110.447552)
		(width 0.14)
		(layer "F.Cu")
		(net 519)
	)
	(segment
		(start 200.726734 108.348373)
		(end 200.699241 108.365648)
		(width 0.14)
		(layer "F.Cu")
		(net 519)
	)
	(segment
		(start 200.777692 110.667273)
		(end 200.766968 110.697921)
		(width 0.14)
		(layer "F.Cu")
		(net 519)
	)
	(segment
		(start 197.349271 112.645751)
		(end 197.338917 112.61616)
		(width 0.14)
		(layer "F.Cu")
		(net 520)
	)
	(segment
		(start 198.240785 114.632296)
		(end 198.257464 114.605751)
		(width 0.14)
		(layer "F.Cu")
		(net 520)
	)
	(segment
		(start 197.414663 113.018872)
		(end 197.444254 113.008518)
		(width 0.14)
		(layer "F.Cu")
		(net 520)
	)
	(segment
		(start 197.444254 113.568518)
		(end 197.475406 113.565008)
		(width 0.14)
		(layer "F.Cu")
		(net 520)
	)
	(segment
		(start 197.444254 114.401497)
		(end 197.414663 114.391143)
		(width 0.14)
		(layer "F.Cu")
		(net 520)
	)
	(segment
		(start 197.36595 113.617719)
		(end 197.388118 113.595551)
		(width 0.14)
		(layer "F.Cu")
		(net 520)
	)
	(segment
		(start 198.257464 112.365751)
		(end 198.267818 112.33616)
		(width 0.14)
		(layer "F.Cu")
		(net 520)
	)
	(segment
		(start 198.162481 112.728518)
		(end 198.131328 112.725008)
		(width 0.14)
		(layer "F.Cu")
		(net 520)
	)
	(segment
		(start 198.192072 113.298872)
		(end 198.162481 113.288518)
		(width 0.14)
		(layer "F.Cu")
		(net 520)
	)
	(segment
		(start 197.338917 113.73616)
		(end 197.335406 113.705008)
		(width 0.14)
		(layer "F.Cu")
		(net 520)
	)
	(segment
		(start 198.240785 113.337719)
		(end 198.218617 113.315551)
		(width 0.14)
		(layer "F.Cu")
		(net 520)
	)
	(segment
		(start 198.271328 113.985008)
		(end 198.267818 113.953855)
		(width 0.14)
		(layer "F.Cu")
		(net 520)
	)
	(segment
		(start 198.271328 112.305008)
		(end 198.271328 109.275804)
		(width 0.14)
		(layer "F.Cu")
		(net 520)
	)
	(segment
		(start 198.257464 114.605751)
		(end 198.267818 114.57616)
		(width 0.14)
		(layer "F.Cu")
		(net 520)
	)
	(segment
		(start 197.335406 114.265008)
		(end 197.338917 114.233855)
		(width 0.14)
		(layer "F.Cu")
		(net 520)
	)
	(segment
		(start 198.162481 113.848518)
		(end 198.131328 113.845008)
		(width 0.14)
		(layer "F.Cu")
		(net 520)
	)
	(segment
		(start 197.388118 113.814464)
		(end 197.36595 113.792296)
		(width 0.14)
		(layer "F.Cu")
		(net 520)
	)
	(segment
		(start 197.475406 112.445008)
		(end 198.131328 112.445008)
		(width 0.14)
		(layer "F.Cu")
		(net 520)
	)
	(segment
		(start 197.475406 114.965008)
		(end 197.444254 114.961497)
		(width 0.14)
		(layer "F.Cu")
		(net 520)
	)
	(segment
		(start 197.335406 113.705008)
		(end 197.338917 113.673855)
		(width 0.14)
		(layer "F.Cu")
		(net 520)
	)
	(segment
		(start 197.475406 114.405008)
		(end 197.444254 114.401497)
		(width 0.14)
		(layer "F.Cu")
		(net 520)
	)
	(segment
		(start 198.192072 114.671143)
		(end 198.218617 114.654464)
		(width 0.14)
		(layer "F.Cu")
		(net 520)
	)
	(segment
		(start 197.338917 114.793855)
		(end 197.349271 114.764264)
		(width 0.14)
		(layer "F.Cu")
		(net 520)
	)
	(segment
		(start 198.240785 115.017719)
		(end 198.218617 114.995551)
		(width 0.14)
		(layer "F.Cu")
		(net 520)
	)
	(segment
		(start 197.338917 114.29616)
		(end 197.335406 114.265008)
		(width 0.14)
		(layer "F.Cu")
		(net 520)
	)
	(segment
		(start 198.267818 112.89616)
		(end 198.271328 112.865008)
		(width 0.14)
		(layer "F.Cu")
		(net 520)
	)
	(segment
		(start 197.338917 113.673855)
		(end 197.349271 113.644264)
		(width 0.14)
		(layer "F.Cu")
		(net 520)
	)
	(segment
		(start 198.218617 113.315551)
		(end 198.192072 113.298872)
		(width 0.14)
		(layer "F.Cu")
		(net 520)
	)
	(segment
		(start 198.192072 112.738872)
		(end 198.162481 112.728518)
		(width 0.14)
		(layer "F.Cu")
		(net 520)
	)
	(segment
		(start 197.36595 112.497719)
		(end 197.388118 112.475551)
		(width 0.14)
		(layer "F.Cu")
		(net 520)
	)
	(segment
		(start 198.131328 113.005008)
		(end 198.162481 113.001497)
		(width 0.14)
		(layer "F.Cu")
		(net 520)
	)
	(segment
		(start 197.414663 114.698872)
		(end 197.444254 114.688518)
		(width 0.14)
		(layer "F.Cu")
		(net 520)
	)
	(segment
		(start 198.131328 112.445008)
		(end 198.162481 112.441497)
		(width 0.14)
		(layer "F.Cu")
		(net 520)
	)
	(segment
		(start 198.131328 113.565008)
		(end 198.162481 113.561497)
		(width 0.14)
		(layer "F.Cu")
		(net 520)
	)
	(segment
		(start 197.444254 113.841497)
		(end 197.414663 113.831143)
		(width 0.14)
		(layer "F.Cu")
		(net 520)
	)
	(segment
		(start 197.338917 113.113855)
		(end 197.349271 113.084264)
		(width 0.14)
		(layer "F.Cu")
		(net 520)
	)
	(segment
		(start 198.267818 112.33616)
		(end 198.271328 112.305008)
		(width 0.14)
		(layer "F.Cu")
		(net 520)
	)
	(segment
		(start 198.240785 114.457719)
		(end 198.218617 114.435551)
		(width 0.14)
		(layer "F.Cu")
		(net 520)
	)
	(segment
		(start 198.257464 113.485751)
		(end 198.267818 113.45616)
		(width 0.14)
		(layer "F.Cu")
		(net 520)
	)
	(segment
		(start 197.475406 113.285008)
		(end 197.444254 113.281497)
		(width 0.14)
		(layer "F.Cu")
		(net 520)
	)
	(segment
		(start 197.349271 114.764264)
		(end 197.36595 114.737719)
		(width 0.14)
		(layer "F.Cu")
		(net 520)
	)
	(segment
		(start 197.335406 113.145008)
		(end 197.338917 113.113855)
		(width 0.14)
		(layer "F.Cu")
		(net 520)
	)
	(segment
		(start 198.271328 116.047157)
		(end 198.271328 115.105008)
		(width 0.14)
		(layer "F.Cu")
		(net 520)
	)
	(segment
		(start 198.267818 112.833855)
		(end 198.257464 112.804264)
		(width 0.14)
		(layer "F.Cu")
		(net 520)
	)
	(segment
		(start 198.267818 114.513855)
		(end 198.257464 114.484264)
		(width 0.14)
		(layer "F.Cu")
		(net 520)
	)
	(segment
		(start 197.36595 112.672296)
		(end 197.349271 112.645751)
		(width 0.14)
		(layer "F.Cu")
		(net 520)
	)
	(segment
		(start 197.444254 112.448518)
		(end 197.475406 112.445008)
		(width 0.14)
		(layer "F.Cu")
		(net 520)
	)
	(segment
		(start 198.162481 114.121497)
		(end 198.192072 114.111143)
		(width 0.14)
		(layer "F.Cu")
		(net 520)
	)
	(segment
		(start 197.338917 112.553855)
		(end 197.349271 112.524264)
		(width 0.14)
		(layer "F.Cu")
		(net 520)
	)
	(segment
		(start 197.444254 114.688518)
		(end 197.475406 114.685008)
		(width 0.14)
		(layer "F.Cu")
		(net 520)
	)
	(segment
		(start 198.192072 113.551143)
		(end 198.218617 113.534464)
		(width 0.14)
		(layer "F.Cu")
		(net 520)
	)
	(segment
		(start 197.388118 114.934464)
		(end 197.36595 114.912296)
		(width 0.14)
		(layer "F.Cu")
		(net 520)
	)
	(segment
		(start 197.388118 114.155551)
		(end 197.414663 114.138872)
		(width 0.14)
		(layer "F.Cu")
		(net 520)
	)
	(segment
		(start 198.257464 114.484264)
		(end 198.240785 114.457719)
		(width 0.14)
		(layer "F.Cu")
		(net 520)
	)
	(segment
		(start 197.338917 114.85616)
		(end 197.335406 114.825008)
		(width 0.14)
		(layer "F.Cu")
		(net 520)
	)
	(segment
		(start 198.192072 113.858872)
		(end 198.162481 113.848518)
		(width 0.14)
		(layer "F.Cu")
		(net 520)
	)
	(segment
		(start 197.349271 113.644264)
		(end 197.36595 113.617719)
		(width 0.14)
		(layer "F.Cu")
		(net 520)
	)
	(segment
		(start 197.414663 114.951143)
		(end 197.388118 114.934464)
		(width 0.14)
		(layer "F.Cu")
		(net 520)
	)
	(segment
		(start 197.414663 113.271143)
		(end 197.388118 113.254464)
		(width 0.14)
		(layer "F.Cu")
		(net 520)
	)
	(segment
		(start 197.335406 112.585008)
		(end 197.338917 112.553855)
		(width 0.14)
		(layer "F.Cu")
		(net 520)
	)
	(segment
		(start 198.267818 113.953855)
		(end 198.257464 113.924264)
		(width 0.14)
		(layer "F.Cu")
		(net 520)
	)
	(segment
		(start 198.131328 114.685008)
		(end 198.162481 114.681497)
		(width 0.14)
		(layer "F.Cu")
		(net 520)
	)
	(segment
		(start 198.271328 109.275804)
		(end 199.781328 107.765804)
		(width 0.14)
		(layer "F.Cu")
		(net 520)
	)
	(segment
		(start 197.36595 114.177719)
		(end 197.388118 114.155551)
		(width 0.14)
		(layer "F.Cu")
		(net 520)
	)
	(segment
		(start 197.414663 114.391143)
		(end 197.388118 114.374464)
		(width 0.14)
		(layer "F.Cu")
		(net 520)
	)
	(segment
		(start 198.240785 112.952296)
		(end 198.257464 112.925751)
		(width 0.14)
		(layer "F.Cu")
		(net 520)
	)
	(segment
		(start 197.414663 112.458872)
		(end 197.444254 112.448518)
		(width 0.14)
		(layer "F.Cu")
		(net 520)
	)
	(segment
		(start 198.257464 112.804264)
		(end 198.240785 112.777719)
		(width 0.14)
		(layer "F.Cu")
		(net 520)
	)
	(segment
		(start 198.218617 114.995551)
		(end 198.192072 114.978872)
		(width 0.14)
		(layer "F.Cu")
		(net 520)
	)
	(segment
		(start 198.162481 114.968518)
		(end 198.131328 114.965008)
		(width 0.14)
		(layer "F.Cu")
		(net 520)
	)
	(segment
		(start 198.257464 113.364264)
		(end 198.240785 113.337719)
		(width 0.14)
		(layer "F.Cu")
		(net 520)
	)
	(segment
		(start 198.131328 112.725008)
		(end 197.475406 112.725008)
		(width 0.14)
		(layer "F.Cu")
		(net 520)
	)
	(segment
		(start 198.218617 114.435551)
		(end 198.192072 114.418872)
		(width 0.14)
		(layer "F.Cu")
		(net 520)
	)
	(segment
		(start 197.414663 113.831143)
		(end 197.388118 113.814464)
		(width 0.14)
		(layer "F.Cu")
		(net 520)
	)
	(segment
		(start 198.131328 114.405008)
		(end 197.475406 114.405008)
		(width 0.14)
		(layer "F.Cu")
		(net 520)
	)
	(segment
		(start 199.781328 107.765804)
		(end 199.781328 106.569306)
		(width 0.14)
		(layer "F.Cu")
		(net 520)
	)
	(segment
		(start 198.192072 112.991143)
		(end 198.218617 112.974464)
		(width 0.14)
		(layer "F.Cu")
		(net 520)
	)
	(segment
		(start 198.162481 112.441497)
		(end 198.192072 112.431143)
		(width 0.14)
		(layer "F.Cu")
		(net 520)
	)
	(segment
		(start 197.36595 114.352296)
		(end 197.349271 114.325751)
		(width 0.14)
		(layer "F.Cu")
		(net 520)
	)
	(segment
		(start 197.388118 113.595551)
		(end 197.414663 113.578872)
		(width 0.14)
		(layer "F.Cu")
		(net 520)
	)
	(segment
		(start 197.444254 114.128518)
		(end 197.475406 114.125008)
		(width 0.14)
		(layer "F.Cu")
		(net 520)
	)
	(segment
		(start 198.240785 114.072296)
		(end 198.257464 114.045751)
		(width 0.14)
		(layer "F.Cu")
		(net 520)
	)
	(segment
		(start 198.271328 113.425008)
		(end 198.267818 113.393855)
		(width 0.14)
		(layer "F.Cu")
		(net 520)
	)
	(segment
		(start 198.267818 113.393855)
		(end 198.257464 113.364264)
		(width 0.14)
		(layer "F.Cu")
		(net 520)
	)
	(segment
		(start 197.414663 114.138872)
		(end 197.444254 114.128518)
		(width 0.14)
		(layer "F.Cu")
		(net 520)
	)
	(segment
		(start 198.240785 113.897719)
		(end 198.218617 113.875551)
		(width 0.14)
		(layer "F.Cu")
		(net 520)
	)
	(segment
		(start 198.218617 114.654464)
		(end 198.240785 114.632296)
		(width 0.14)
		(layer "F.Cu")
		(net 520)
	)
	(segment
		(start 197.388118 113.254464)
		(end 197.36595 113.232296)
		(width 0.14)
		(layer "F.Cu")
		(net 520)
	)
	(segment
		(start 197.36595 114.912296)
		(end 197.349271 114.885751)
		(width 0.14)
		(layer "F.Cu")
		(net 520)
	)
	(segment
		(start 197.349271 113.765751)
		(end 197.338917 113.73616)
		(width 0.14)
		(layer "F.Cu")
		(net 520)
	)
	(segment
		(start 198.131328 114.125008)
		(end 198.162481 114.121497)
		(width 0.14)
		(layer "F.Cu")
		(net 520)
	)
	(segment
		(start 197.388118 113.035551)
		(end 197.414663 113.018872)
		(width 0.14)
		(layer "F.Cu")
		(net 520)
	)
	(segment
		(start 198.271328 114.545008)
		(end 198.267818 114.513855)
		(width 0.14)
		(layer "F.Cu")
		(net 520)
	)
	(segment
		(start 197.475406 113.845008)
		(end 197.444254 113.841497)
		(width 0.14)
		(layer "F.Cu")
		(net 520)
	)
	(segment
		(start 198.162481 114.681497)
		(end 198.192072 114.671143)
		(width 0.14)
		(layer "F.Cu")
		(net 520)
	)
	(segment
		(start 197.414663 113.578872)
		(end 197.444254 113.568518)
		(width 0.14)
		(layer "F.Cu")
		(net 520)
	)
	(segment
		(start 197.338917 112.61616)
		(end 197.335406 112.585008)
		(width 0.14)
		(layer "F.Cu")
		(net 520)
	)
	(segment
		(start 198.162481 113.001497)
		(end 198.192072 112.991143)
		(width 0.14)
		(layer "F.Cu")
		(net 520)
	)
	(segment
		(start 198.192072 114.111143)
		(end 198.218617 114.094464)
		(width 0.14)
		(layer "F.Cu")
		(net 520)
	)
	(segment
		(start 197.349271 112.524264)
		(end 197.36595 112.497719)
		(width 0.14)
		(layer "F.Cu")
		(net 520)
	)
	(segment
		(start 198.218617 113.875551)
		(end 198.192072 113.858872)
		(width 0.14)
		(layer "F.Cu")
		(net 520)
	)
	(segment
		(start 198.267818 113.45616)
		(end 198.271328 113.425008)
		(width 0.14)
		(layer "F.Cu")
		(net 520)
	)
	(segment
		(start 197.349271 114.885751)
		(end 197.338917 114.85616)
		(width 0.14)
		(layer "F.Cu")
		(net 520)
	)
	(segment
		(start 198.267818 115.073855)
		(end 198.257464 115.044264)
		(width 0.14)
		(layer "F.Cu")
		(net 520)
	)
	(segment
		(start 197.349271 114.325751)
		(end 197.338917 114.29616)
		(width 0.14)
		(layer "F.Cu")
		(net 520)
	)
	(segment
		(start 198.218617 112.755551)
		(end 198.192072 112.738872)
		(width 0.14)
		(layer "F.Cu")
		(net 520)
	)
	(segment
		(start 198.240785 112.777719)
		(end 198.218617 112.755551)
		(width 0.14)
		(layer "F.Cu")
		(net 520)
	)
	(segment
		(start 198.267818 114.57616)
		(end 198.271328 114.545008)
		(width 0.14)
		(layer "F.Cu")
		(net 520)
	)
	(segment
		(start 197.349271 113.084264)
		(end 197.36595 113.057719)
		(width 0.14)
		(layer "F.Cu")
		(net 520)
	)
	(segment
		(start 197.444254 113.008518)
		(end 197.475406 113.005008)
		(width 0.14)
		(layer "F.Cu")
		(net 520)
	)
	(segment
		(start 197.414663 112.711143)
		(end 197.388118 112.694464)
		(width 0.14)
		(layer "F.Cu")
		(net 520)
	)
	(segment
		(start 198.267818 114.01616)
		(end 198.271328 113.985008)
		(width 0.14)
		(layer "F.Cu")
		(net 520)
	)
	(segment
		(start 198.162481 114.408518)
		(end 198.131328 114.405008)
		(width 0.14)
		(layer "F.Cu")
		(net 520)
	)
	(segment
		(start 198.257464 115.044264)
		(end 198.240785 115.017719)
		(width 0.14)
		(layer "F.Cu")
		(net 520)
	)
	(segment
		(start 198.218617 113.534464)
		(end 198.240785 113.512296)
		(width 0.14)
		(layer "F.Cu")
		(net 520)
	)
	(segment
		(start 198.257464 113.924264)
		(end 198.240785 113.897719)
		(width 0.14)
		(layer "F.Cu")
		(net 520)
	)
	(segment
		(start 198.131328 113.285008)
		(end 197.475406 113.285008)
		(width 0.14)
		(layer "F.Cu")
		(net 520)
	)
	(segment
		(start 197.475406 113.565008)
		(end 198.131328 113.565008)
		(width 0.14)
		(layer "F.Cu")
		(net 520)
	)
	(segment
		(start 198.192072 114.978872)
		(end 198.162481 114.968518)
		(width 0.14)
		(layer "F.Cu")
		(net 520)
	)
	(segment
		(start 197.36595 113.057719)
		(end 197.388118 113.035551)
		(width 0.14)
		(layer "F.Cu")
		(net 520)
	)
	(segment
		(start 198.218617 112.974464)
		(end 198.240785 112.952296)
		(width 0.14)
		(layer "F.Cu")
		(net 520)
	)
	(segment
		(start 197.388118 112.475551)
		(end 197.414663 112.458872)
		(width 0.14)
		(layer "F.Cu")
		(net 520)
	)
	(segment
		(start 198.257464 114.045751)
		(end 198.267818 114.01616)
		(width 0.14)
		(layer "F.Cu")
		(net 520)
	)
	(segment
		(start 197.475406 114.685008)
		(end 198.131328 114.685008)
		(width 0.14)
		(layer "F.Cu")
		(net 520)
	)
	(segment
		(start 197.388118 114.715551)
		(end 197.414663 114.698872)
		(width 0.14)
		(layer "F.Cu")
		(net 520)
	)
	(segment
		(start 197.338917 114.233855)
		(end 197.349271 114.204264)
		(width 0.14)
		(layer "F.Cu")
		(net 520)
	)
	(segment
		(start 197.444254 112.721497)
		(end 197.414663 112.711143)
		(width 0.14)
		(layer "F.Cu")
		(net 520)
	)
	(segment
		(start 197.36595 113.232296)
		(end 197.349271 113.205751)
		(width 0.14)
		(layer "F.Cu")
		(net 520)
	)
	(segment
		(start 197.388118 114.374464)
		(end 197.36595 114.352296)
		(width 0.14)
		(layer "F.Cu")
		(net 520)
	)
	(segment
		(start 197.338917 113.17616)
		(end 197.335406 113.145008)
		(width 0.14)
		(layer "F.Cu")
		(net 520)
	)
	(segment
		(start 198.218617 112.414464)
		(end 198.240785 112.392296)
		(width 0.14)
		(layer "F.Cu")
		(net 520)
	)
	(segment
		(start 197.36595 113.792296)
		(end 197.349271 113.765751)
		(width 0.14)
		(layer "F.Cu")
		(net 520)
	)
	(segment
		(start 198.192072 114.418872)
		(end 198.162481 114.408518)
		(width 0.14)
		(layer "F.Cu")
		(net 520)
	)
	(segment
		(start 197.36595 114.737719)
		(end 197.388118 114.715551)
		(width 0.14)
		(layer "F.Cu")
		(net 520)
	)
	(segment
		(start 198.271328 115.105008)
		(end 198.267818 115.073855)
		(width 0.14)
		(layer "F.Cu")
		(net 520)
	)
	(segment
		(start 198.257464 112.925751)
		(end 198.267818 112.89616)
		(width 0.14)
		(layer "F.Cu")
		(net 520)
	)
	(segment
		(start 198.131328 113.845008)
		(end 197.475406 113.845008)
		(width 0.14)
		(layer "F.Cu")
		(net 520)
	)
	(segment
		(start 197.335406 114.825008)
		(end 197.338917 114.793855)
		(width 0.14)
		(layer "F.Cu")
		(net 520)
	)
	(segment
		(start 198.162481 113.561497)
		(end 198.192072 113.551143)
		(width 0.14)
		(layer "F.Cu")
		(net 520)
	)
	(segment
		(start 197.444254 114.961497)
		(end 197.414663 114.951143)
		(width 0.14)
		(layer "F.Cu")
		(net 520)
	)
	(segment
		(start 199.781328 106.569306)
		(end 199.686328 106.474306)
		(width 0.14)
		(layer "F.Cu")
		(net 520)
	)
	(segment
		(start 197.444254 113.281497)
		(end 197.414663 113.271143)
		(width 0.14)
		(layer "F.Cu")
		(net 520)
	)
	(segment
		(start 197.388118 112.694464)
		(end 197.36595 112.672296)
		(width 0.14)
		(layer "F.Cu")
		(net 520)
	)
	(segment
		(start 197.475406 114.125008)
		(end 198.131328 114.125008)
		(width 0.14)
		(layer "F.Cu")
		(net 520)
	)
	(segment
		(start 197.349271 114.204264)
		(end 197.36595 114.177719)
		(width 0.14)
		(layer "F.Cu")
		(net 520)
	)
	(segment
		(start 197.475406 112.725008)
		(end 197.444254 112.721497)
		(width 0.14)
		(layer "F.Cu")
		(net 520)
	)
	(segment
		(start 198.131328 114.965008)
		(end 197.475406 114.965008)
		(width 0.14)
		(layer "F.Cu")
		(net 520)
	)
	(segment
		(start 198.261328 116.057157)
		(end 198.271328 116.047157)
		(width 0.14)
		(layer "F.Cu")
		(net 520)
	)
	(segment
		(start 198.162481 113.288518)
		(end 198.131328 113.285008)
		(width 0.14)
		(layer "F.Cu")
		(net 520)
	)
	(segment
		(start 198.240785 113.512296)
		(end 198.257464 113.485751)
		(width 0.14)
		(layer "F.Cu")
		(net 520)
	)
	(segment
		(start 198.218617 114.094464)
		(end 198.240785 114.072296)
		(width 0.14)
		(layer "F.Cu")
		(net 520)
	)
	(segment
		(start 197.475406 113.005008)
		(end 198.131328 113.005008)
		(width 0.14)
		(layer "F.Cu")
		(net 520)
	)
	(segment
		(start 198.240785 112.392296)
		(end 198.257464 112.365751)
		(width 0.14)
		(layer "F.Cu")
		(net 520)
	)
	(segment
		(start 198.271328 112.865008)
		(end 198.267818 112.833855)
		(width 0.14)
		(layer "F.Cu")
		(net 520)
	)
	(segment
		(start 197.349271 113.205751)
		(end 197.338917 113.17616)
		(width 0.14)
		(layer "F.Cu")
		(net 520)
	)
	(segment
		(start 198.192072 112.431143)
		(end 198.218617 112.414464)
		(width 0.14)
		(layer "F.Cu")
		(net 520)
	)
	(segment
		(start 193.691328 121.897157)
		(end 209.181328 121.897157)
		(width 0.2)
		(layer "B.Cu")
		(net 521)
	)
	(segment
		(start 209.181328 121.897157)
		(end 213.063477 121.897157)
		(width 0.2)
		(layer "B.Cu")
		(net 521)
	)
	(segment
		(start 195.483298 110.228716)
		(end 195.483298 110.281299)
		(width 0.14)
		(layer "F.Cu")
		(net 522)
	)
	(segment
		(start 195.871514 113.689705)
		(end 195.903183 113.721374)
		(width 0.14)
		(layer "F.Cu")
		(net 522)
	)
	(segment
		(start 195.725996 109.842463)
		(end 195.644711 109.893538)
		(width 0.14)
		(layer "F.Cu")
		(net 522)
	)
	(segment
		(start 195.941104 112.945201)
		(end 195.983376 112.959993)
		(width 0.14)
		(layer "F.Cu")
		(net 522)
	)
	(segment
		(start 196.448104 112.984814)
		(end 196.486025 113.008641)
		(width 0.14)
		(layer "F.Cu")
		(net 522)
	)
	(segment
		(start 195.941104 113.745201)
		(end 195.983376 113.759993)
		(width 0.14)
		(layer "F.Cu")
		(net 522)
	)
	(segment
		(start 197.624999 110.917921)
		(end 197.607724 110.945414)
		(width 0.14)
		(layer "F.Cu")
		(net 522)
	)
	(segment
		(start 196.561328 113.165008)
		(end 196.556313 113.209512)
		(width 0.14)
		(layer "F.Cu")
		(net 522)
	)
	(segment
		(start 196.506734 111.941642)
		(end 196.529693 111.964601)
		(width 0.14)
		(layer "F.Cu")
		(net 522)
	)
	(segment
		(start 196.556313 113.209512)
		(end 196.541521 113.251784)
		(width 0.14)
		(layer "F.Cu")
		(net 522)
	)
	(segment
		(start 197.607724 110.945414)
		(end 197.584765 110.968373)
		(width 0.14)
		(layer "F.Cu")
		(net 522)
	)
	(segment
		(start 195.525753 111.667309)
		(end 195.576828 111.748594)
		(width 0.14)
		(layer "F.Cu")
		(net 522)
	)
	(segment
		(start 195.941104 112.584814)
		(end 195.903183 112.608641)
		(width 0.14)
		(layer "F.Cu")
		(net 522)
	)
	(segment
		(start 197.526624 110.713643)
		(end 197.557272 110.724367)
		(width 0.14)
		(layer "F.Cu")
		(net 522)
	)
	(segment
		(start 197.635723 110.887273)
		(end 197.624999 110.917921)
		(width 0.14)
		(layer "F.Cu")
		(net 522)
	)
	(segment
		(start 196.561328 109.655008)
		(end 196.557692 109.687273)
		(width 0.14)
		(layer "F.Cu")
		(net 522)
	)
	(segment
		(start 196.561328 113.965008)
		(end 196.561328 115.217157)
		(width 0.14)
		(layer "F.Cu")
		(net 522)
	)
	(segment
		(start 195.941104 113.384814)
		(end 195.903183 113.408641)
		(width 0.14)
		(layer "F.Cu")
		(net 522)
	)
	(segment
		(start 196.506734 109.768373)
		(end 196.479241 109.785648)
		(width 0.14)
		(layer "F.Cu")
		(net 522)
	)
	(segment
		(start 195.983376 112.959993)
		(end 196.027881 112.965008)
		(width 0.14)
		(layer "F.Cu")
		(net 522)
	)
	(segment
		(start 195.832895 112.809512)
		(end 195.847687 112.851784)
		(width 0.14)
		(layer "F.Cu")
		(net 522)
	)
	(segment
		(start 196.027881 112.565008)
		(end 195.983376 112.570022)
		(width 0.14)
		(layer "F.Cu")
		(net 522)
	)
	(segment
		(start 195.816609 111.010756)
		(end 195.725996 111.042463)
		(width 0.14)
		(layer "F.Cu")
		(net 522)
	)
	(segment
		(start 195.847687 112.851784)
		(end 195.871514 112.889705)
		(width 0.14)
		(layer "F.Cu")
		(net 522)
	)
	(segment
		(start 196.517694 113.84031)
		(end 196.541521 113.878231)
		(width 0.14)
		(layer "F.Cu")
		(net 522)
	)
	(segment
		(start 196.529693 111.964601)
		(end 196.546968 111.992094)
		(width 0.14)
		(layer "F.Cu")
		(net 522)
	)
	(segment
		(start 197.526624 110.996372)
		(end 197.494358 111.000008)
		(width 0.14)
		(layer "F.Cu")
		(net 522)
	)
	(segment
		(start 197.557272 110.724367)
		(end 197.584765 110.741642)
		(width 0.14)
		(layer "F.Cu")
		(net 522)
	)
	(segment
		(start 196.416328 111.910008)
		(end 196.448593 111.913643)
		(width 0.14)
		(layer "F.Cu")
		(net 522)
	)
	(segment
		(start 195.903183 113.721374)
		(end 195.941104 113.745201)
		(width 0.14)
		(layer "F.Cu")
		(net 522)
	)
	(segment
		(start 195.827881 112.765008)
		(end 195.832895 112.809512)
		(width 0.14)
		(layer "F.Cu")
		(net 522)
	)
	(segment
		(start 197.624999 110.792094)
		(end 197.635723 110.822742)
		(width 0.14)
		(layer "F.Cu")
		(net 522)
	)
	(segment
		(start 196.486025 113.808641)
		(end 196.517694 113.84031)
		(width 0.14)
		(layer "F.Cu")
		(net 522)
	)
	(segment
		(start 195.983376 113.370022)
		(end 195.941104 113.384814)
		(width 0.14)
		(layer "F.Cu")
		(net 522)
	)
	(segment
		(start 196.486025 113.008641)
		(end 196.517694 113.04031)
		(width 0.14)
		(layer "F.Cu")
		(net 522)
	)
	(segment
		(start 196.556313 113.920503)
		(end 196.561328 113.965008)
		(width 0.14)
		(layer "F.Cu")
		(net 522)
	)
	(segment
		(start 195.494046 111.333319)
		(end 195.483298 111.428716)
		(width 0.14)
		(layer "F.Cu")
		(net 522)
	)
	(segment
		(start 196.405832 113.359993)
		(end 196.361328 113.365008)
		(width 0.14)
		(layer "F.Cu")
		(net 522)
	)
	(segment
		(start 195.903183 113.408641)
		(end 195.871514 113.44031)
		(width 0.14)
		(layer "F.Cu")
		(net 522)
	)
	(segment
		(start 195.725996 111.042463)
		(end 195.644711 111.093538)
		(width 0.14)
		(layer "F.Cu")
		(net 522)
	)
	(segment
		(start 195.832895 113.520503)
		(end 195.827881 113.565008)
		(width 0.14)
		(layer "F.Cu")
		(net 522)
	)
	(segment
		(start 195.483298 110.281299)
		(end 195.494046 110.376696)
		(width 0.14)
		(layer "F.Cu")
		(net 522)
	)
	(segment
		(start 195.725996 110.667552)
		(end 195.816609 110.699259)
		(width 0.14)
		(layer "F.Cu")
		(net 522)
	)
	(segment
		(start 197.494358 111.000008)
		(end 195.912006 111.000008)
		(width 0.14)
		(layer "F.Cu")
		(net 522)
	)
	(segment
		(start 196.361328 112.565008)
		(end 196.027881 112.565008)
		(width 0.14)
		(layer "F.Cu")
		(net 522)
	)
	(segment
		(start 195.525753 110.042706)
		(end 195.494046 110.133319)
		(width 0.14)
		(layer "F.Cu")
		(net 522)
	)
	(segment
		(start 196.561328 112.055008)
		(end 196.561328 112.365008)
		(width 0.14)
		(layer "F.Cu")
		(net 522)
	)
	(segment
		(start 195.871514 112.64031)
		(end 195.847687 112.678231)
		(width 0.14)
		(layer "F.Cu")
		(net 522)
	)
	(segment
		(start 195.525753 110.467309)
		(end 195.576828 110.548594)
		(width 0.14)
		(layer "F.Cu")
		(net 522)
	)
	(segment
		(start 196.546968 109.717921)
		(end 196.529693 109.745414)
		(width 0.14)
		(layer "F.Cu")
		(net 522)
	)
	(segment
		(start 195.644711 111.093538)
		(end 195.576828 111.161421)
		(width 0.14)
		(layer "F.Cu")
		(net 522)
	)
	(segment
		(start 198.281328 107.665804)
		(end 196.561328 109.385804)
		(width 0.14)
		(layer "F.Cu")
		(net 522)
	)
	(segment
		(start 196.479241 109.785648)
		(end 196.448593 109.796372)
		(width 0.14)
		(layer "F.Cu")
		(net 522)
	)
	(segment
		(start 195.903183 112.921374)
		(end 195.941104 112.945201)
		(width 0.14)
		(layer "F.Cu")
		(net 522)
	)
	(segment
		(start 196.561328 115.217157)
		(end 195.721328 116.057157)
		(width 0.14)
		(layer "F.Cu")
		(net 522)
	)
	(segment
		(start 195.576828 111.748594)
		(end 195.644711 111.816477)
		(width 0.14)
		(layer "F.Cu")
		(net 522)
	)
	(segment
		(start 196.541521 113.251784)
		(end 196.517694 113.289705)
		(width 0.14)
		(layer "F.Cu")
		(net 522)
	)
	(segment
		(start 195.871514 113.44031)
		(end 195.847687 113.478231)
		(width 0.14)
		(layer "F.Cu")
		(net 522)
	)
	(segment
		(start 195.725996 111.867552)
		(end 195.816609 111.899259)
		(width 0.14)
		(layer "F.Cu")
		(net 522)
	)
	(segment
		(start 196.486025 112.521374)
		(end 196.448104 112.545201)
		(width 0.14)
		(layer "F.Cu")
		(net 522)
	)
	(segment
		(start 196.561328 109.385804)
		(end 196.561328 109.655008)
		(width 0.14)
		(layer "F.Cu")
		(net 522)
	)
	(segment
		(start 197.635723 110.822742)
		(end 197.639358 110.855008)
		(width 0.14)
		(layer "F.Cu")
		(net 522)
	)
	(segment
		(start 196.361328 113.765008)
		(end 196.405832 113.770022)
		(width 0.14)
		(layer "F.Cu")
		(net 522)
	)
	(segment
		(start 195.832895 113.609512)
		(end 195.847687 113.651784)
		(width 0.14)
		(layer "F.Cu")
		(net 522)
	)
	(segment
		(start 196.448104 112.545201)
		(end 196.405832 112.559993)
		(width 0.14)
		(layer "F.Cu")
		(net 522)
	)
	(segment
		(start 196.546968 111.992094)
		(end 196.557692 112.022742)
		(width 0.14)
		(layer "F.Cu")
		(net 522)
	)
	(segment
		(start 196.517694 113.04031)
		(end 196.541521 113.078231)
		(width 0.14)
		(layer "F.Cu")
		(net 522)
	)
	(segment
		(start 196.361328 113.365008)
		(end 196.027881 113.365008)
		(width 0.14)
		(layer "F.Cu")
		(net 522)
	)
	(segment
		(start 195.483298 111.481299)
		(end 195.494046 111.576696)
		(width 0.14)
		(layer "F.Cu")
		(net 522)
	)
	(segment
		(start 195.912006 111.000008)
		(end 195.816609 111.010756)
		(width 0.14)
		(layer "F.Cu")
		(net 522)
	)
	(segment
		(start 196.541521 113.078231)
		(end 196.556313 113.120503)
		(width 0.14)
		(layer "F.Cu")
		(net 522)
	)
	(segment
		(start 195.847687 113.478231)
		(end 195.832895 113.520503)
		(width 0.14)
		(layer "F.Cu")
		(net 522)
	)
	(segment
		(start 197.607724 110.764601)
		(end 197.624999 110.792094)
		(width 0.14)
		(layer "F.Cu")
		(net 522)
	)
	(segment
		(start 196.541521 112.451784)
		(end 196.517694 112.489705)
		(width 0.14)
		(layer "F.Cu")
		(net 522)
	)
	(segment
		(start 195.644711 110.616477)
		(end 195.725996 110.667552)
		(width 0.14)
		(layer "F.Cu")
		(net 522)
	)
	(segment
		(start 197.584765 110.968373)
		(end 197.557272 110.985648)
		(width 0.14)
		(layer "F.Cu")
		(net 522)
	)
	(segment
		(start 196.448593 111.913643)
		(end 196.479241 111.924367)
		(width 0.14)
		(layer "F.Cu")
		(net 522)
	)
	(segment
		(start 196.405832 112.559993)
		(end 196.361328 112.565008)
		(width 0.14)
		(layer "F.Cu")
		(net 522)
	)
	(segment
		(start 197.584765 110.741642)
		(end 197.607724 110.764601)
		(width 0.14)
		(layer "F.Cu")
		(net 522)
	)
	(segment
		(start 195.816609 110.699259)
		(end 195.912006 110.710008)
		(width 0.14)
		(layer "F.Cu")
		(net 522)
	)
	(segment
		(start 196.361328 112.965008)
		(end 196.405832 112.970022)
		(width 0.14)
		(layer "F.Cu")
		(net 522)
	)
	(segment
		(start 195.525753 111.242706)
		(end 195.494046 111.333319)
		(width 0.14)
		(layer "F.Cu")
		(net 522)
	)
	(segment
		(start 195.983376 113.759993)
		(end 196.027881 113.765008)
		(width 0.14)
		(layer "F.Cu")
		(net 522)
	)
	(segment
		(start 196.541521 113.878231)
		(end 196.556313 113.920503)
		(width 0.14)
		(layer "F.Cu")
		(net 522)
	)
	(segment
		(start 195.983376 112.570022)
		(end 195.941104 112.584814)
		(width 0.14)
		(layer "F.Cu")
		(net 522)
	)
	(segment
		(start 196.448593 109.796372)
		(end 196.416328 109.800008)
		(width 0.14)
		(layer "F.Cu")
		(net 522)
	)
	(segment
		(start 195.816609 109.810756)
		(end 195.725996 109.842463)
		(width 0.14)
		(layer "F.Cu")
		(net 522)
	)
	(segment
		(start 195.912006 110.710008)
		(end 197.494358 110.710008)
		(width 0.14)
		(layer "F.Cu")
		(net 522)
	)
	(segment
		(start 196.486025 113.321374)
		(end 196.448104 113.345201)
		(width 0.14)
		(layer "F.Cu")
		(net 522)
	)
	(segment
		(start 196.479241 111.924367)
		(end 196.506734 111.941642)
		(width 0.14)
		(layer "F.Cu")
		(net 522)
	)
	(segment
		(start 195.832895 112.720503)
		(end 195.827881 112.765008)
		(width 0.14)
		(layer "F.Cu")
		(net 522)
	)
	(segment
		(start 196.405832 112.970022)
		(end 196.448104 112.984814)
		(width 0.14)
		(layer "F.Cu")
		(net 522)
	)
	(segment
		(start 195.847687 112.678231)
		(end 195.832895 112.720503)
		(width 0.14)
		(layer "F.Cu")
		(net 522)
	)
	(segment
		(start 197.557272 110.985648)
		(end 197.526624 110.996372)
		(width 0.14)
		(layer "F.Cu")
		(net 522)
	)
	(segment
		(start 196.556313 112.409512)
		(end 196.541521 112.451784)
		(width 0.14)
		(layer "F.Cu")
		(net 522)
	)
	(segment
		(start 195.576828 110.548594)
		(end 195.644711 110.616477)
		(width 0.14)
		(layer "F.Cu")
		(net 522)
	)
	(segment
		(start 196.027881 113.365008)
		(end 195.983376 113.370022)
		(width 0.14)
		(layer "F.Cu")
		(net 522)
	)
	(segment
		(start 196.448104 113.784814)
		(end 196.486025 113.808641)
		(width 0.14)
		(layer "F.Cu")
		(net 522)
	)
	(segment
		(start 196.416328 109.800008)
		(end 195.912006 109.800008)
		(width 0.14)
		(layer "F.Cu")
		(net 522)
	)
	(segment
		(start 195.871514 112.889705)
		(end 195.903183 112.921374)
		(width 0.14)
		(layer "F.Cu")
		(net 522)
	)
	(segment
		(start 195.912006 111.910008)
		(end 196.416328 111.910008)
		(width 0.14)
		(layer "F.Cu")
		(net 522)
	)
	(segment
		(start 195.912006 109.800008)
		(end 195.816609 109.810756)
		(width 0.14)
		(layer "F.Cu")
		(net 522)
	)
	(segment
		(start 196.556313 113.120503)
		(end 196.561328 113.165008)
		(width 0.14)
		(layer "F.Cu")
		(net 522)
	)
	(segment
		(start 196.027881 113.765008)
		(end 196.361328 113.765008)
		(width 0.14)
		(layer "F.Cu")
		(net 522)
	)
	(segment
		(start 195.494046 111.576696)
		(end 195.525753 111.667309)
		(width 0.14)
		(layer "F.Cu")
		(net 522)
	)
	(segment
		(start 195.644711 111.816477)
		(end 195.725996 111.867552)
		(width 0.14)
		(layer "F.Cu")
		(net 522)
	)
	(segment
		(start 196.517694 112.489705)
		(end 196.486025 112.521374)
		(width 0.14)
		(layer "F.Cu")
		(net 522)
	)
	(segment
		(start 195.576828 109.961421)
		(end 195.525753 110.042706)
		(width 0.14)
		(layer "F.Cu")
		(net 522)
	)
	(segment
		(start 196.517694 113.289705)
		(end 196.486025 113.321374)
		(width 0.14)
		(layer "F.Cu")
		(net 522)
	)
	(segment
		(start 196.561328 112.365008)
		(end 196.556313 112.409512)
		(width 0.14)
		(layer "F.Cu")
		(net 522)
	)
	(segment
		(start 197.639358 110.855008)
		(end 197.635723 110.887273)
		(width 0.14)
		(layer "F.Cu")
		(net 522)
	)
	(segment
		(start 195.827881 113.565008)
		(end 195.832895 113.609512)
		(width 0.14)
		(layer "F.Cu")
		(net 522)
	)
	(segment
		(start 196.027881 112.965008)
		(end 196.361328 112.965008)
		(width 0.14)
		(layer "F.Cu")
		(net 522)
	)
	(segment
		(start 195.903183 112.608641)
		(end 195.871514 112.64031)
		(width 0.14)
		(layer "F.Cu")
		(net 522)
	)
	(segment
		(start 196.448104 113.345201)
		(end 196.405832 113.359993)
		(width 0.14)
		(layer "F.Cu")
		(net 522)
	)
	(segment
		(start 195.644711 109.893538)
		(end 195.576828 109.961421)
		(width 0.14)
		(layer "F.Cu")
		(net 522)
	)
	(segment
		(start 196.557692 109.687273)
		(end 196.546968 109.717921)
		(width 0.14)
		(layer "F.Cu")
		(net 522)
	)
	(segment
		(start 195.494046 110.376696)
		(end 195.525753 110.467309)
		(width 0.14)
		(layer "F.Cu")
		(net 522)
	)
	(segment
		(start 195.483298 111.428716)
		(end 195.483298 111.481299)
		(width 0.14)
		(layer "F.Cu")
		(net 522)
	)
	(segment
		(start 198.186328 106.474306)
		(end 198.281328 106.569306)
		(width 0.14)
		(layer "F.Cu")
		(net 522)
	)
	(segment
		(start 198.281328 106.569306)
		(end 198.281328 107.665804)
		(width 0.14)
		(layer "F.Cu")
		(net 522)
	)
	(segment
		(start 195.816609 111.899259)
		(end 195.912006 111.910008)
		(width 0.14)
		(layer "F.Cu")
		(net 522)
	)
	(segment
		(start 197.494358 110.710008)
		(end 197.526624 110.713643)
		(width 0.14)
		(layer "F.Cu")
		(net 522)
	)
	(segment
		(start 195.847687 113.651784)
		(end 195.871514 113.689705)
		(width 0.14)
		(layer "F.Cu")
		(net 522)
	)
	(segment
		(start 196.557692 112.022742)
		(end 196.561328 112.055008)
		(width 0.14)
		(layer "F.Cu")
		(net 522)
	)
	(segment
		(start 195.576828 111.161421)
		(end 195.525753 111.242706)
		(width 0.14)
		(layer "F.Cu")
		(net 522)
	)
	(segment
		(start 196.529693 109.745414)
		(end 196.506734 109.768373)
		(width 0.14)
		(layer "F.Cu")
		(net 522)
	)
	(segment
		(start 196.405832 113.770022)
		(end 196.448104 113.784814)
		(width 0.14)
		(layer "F.Cu")
		(net 522)
	)
	(segment
		(start 195.494046 110.133319)
		(end 195.483298 110.228716)
		(width 0.14)
		(layer "F.Cu")
		(net 522)
	)
	(segment
		(start 203.885833 114.369993)
		(end 203.928105 114.355201)
		(width 0.14)
		(layer "F.Cu")
		(net 523)
	)
	(segment
		(start 203.404432 110.270008)
		(end 203.896328 110.270008)
		(width 0.14)
		(layer "F.Cu")
		(net 523)
	)
	(segment
		(start 204.021522 113.461784)
		(end 204.036314 113.419512)
		(width 0.14)
		(layer "F.Cu")
		(net 523)
	)
	(segment
		(start 203.39211 114.394814)
		(end 203.434382 114.380022)
		(width 0.14)
		(layer "F.Cu")
		(net 523)
	)
	(segment
		(start 203.997695 114.05031)
		(end 203.966026 114.018641)
		(width 0.14)
		(layer "F.Cu")
		(net 523)
	)
	(segment
		(start 204.961932 111.180008)
		(end 203.404432 111.180008)
		(width 0.14)
		(layer "F.Cu")
		(net 523)
	)
	(segment
		(start 203.434382 113.580022)
		(end 203.478886 113.575008)
		(width 0.14)
		(layer "F.Cu")
		(net 523)
	)
	(segment
		(start 203.959241 112.394367)
		(end 203.928593 112.383643)
		(width 0.14)
		(layer "F.Cu")
		(net 523)
	)
	(segment
		(start 203.986734 112.411642)
		(end 203.959241 112.394367)
		(width 0.14)
		(layer "F.Cu")
		(net 523)
	)
	(segment
		(start 202.986472 110.846696)
		(end 202.975724 110.751299)
		(width 0.14)
		(layer "F.Cu")
		(net 523)
	)
	(segment
		(start 203.298693 114.661784)
		(end 203.283901 114.619512)
		(width 0.14)
		(layer "F.Cu")
		(net 523)
	)
	(segment
		(start 205.092573 111.262094)
		(end 205.075298 111.234601)
		(width 0.14)
		(layer "F.Cu")
		(net 523)
	)
	(segment
		(start 203.298693 113.861784)
		(end 203.283901 113.819512)
		(width 0.14)
		(layer "F.Cu")
		(net 523)
	)
	(segment
		(start 205.024846 111.194367)
		(end 204.994198 111.183643)
		(width 0.14)
		(layer "F.Cu")
		(net 523)
	)
	(segment
		(start 203.018179 111.712706)
		(end 203.069254 111.631421)
		(width 0.14)
		(layer "F.Cu")
		(net 523)
	)
	(segment
		(start 204.041328 112.525008)
		(end 204.037692 112.492742)
		(width 0.14)
		(layer "F.Cu")
		(net 523)
	)
	(segment
		(start 203.404432 111.470008)
		(end 204.961932 111.470008)
		(width 0.14)
		(layer "F.Cu")
		(net 523)
	)
	(segment
		(start 204.041328 114.975008)
		(end 204.036314 114.930503)
		(width 0.14)
		(layer "F.Cu")
		(net 523)
	)
	(segment
		(start 204.026968 110.187921)
		(end 204.037692 110.157273)
		(width 0.14)
		(layer "F.Cu")
		(net 523)
	)
	(segment
		(start 203.018179 110.937309)
		(end 202.986472 110.846696)
		(width 0.14)
		(layer "F.Cu")
		(net 523)
	)
	(segment
		(start 205.103297 111.292742)
		(end 205.092573 111.262094)
		(width 0.14)
		(layer "F.Cu")
		(net 523)
	)
	(segment
		(start 203.404432 112.380008)
		(end 203.309035 112.369259)
		(width 0.14)
		(layer "F.Cu")
		(net 523)
	)
	(segment
		(start 203.841328 113.575008)
		(end 203.885833 113.569993)
		(width 0.14)
		(layer "F.Cu")
		(net 523)
	)
	(segment
		(start 203.341328 116.057157)
		(end 203.341328 115.925008)
		(width 0.14)
		(layer "F.Cu")
		(net 523)
	)
	(segment
		(start 205.052339 111.438373)
		(end 205.075298 111.415414)
		(width 0.14)
		(layer "F.Cu")
		(net 523)
	)
	(segment
		(start 203.354189 114.418641)
		(end 203.39211 114.394814)
		(width 0.14)
		(layer "F.Cu")
		(net 523)
	)
	(segment
		(start 203.069254 112.218594)
		(end 203.018179 112.137309)
		(width 0.14)
		(layer "F.Cu")
		(net 523)
	)
	(segment
		(start 202.986472 112.046696)
		(end 202.975724 111.951299)
		(width 0.14)
		(layer "F.Cu")
		(net 523)
	)
	(segment
		(start 203.986734 110.238373)
		(end 204.009693 110.215414)
		(width 0.14)
		(layer "F.Cu")
		(net 523)
	)
	(segment
		(start 203.354189 114.731374)
		(end 203.32252 114.699705)
		(width 0.14)
		(layer "F.Cu")
		(net 523)
	)
	(segment
		(start 203.478886 113.575008)
		(end 203.841328 113.575008)
		(width 0.14)
		(layer "F.Cu")
		(net 523)
	)
	(segment
		(start 204.041328 114.175008)
		(end 204.036314 114.130503)
		(width 0.14)
		(layer "F.Cu")
		(net 523)
	)
	(segment
		(start 203.137137 111.086477)
		(end 203.069254 111.018594)
		(width 0.14)
		(layer "F.Cu")
		(net 523)
	)
	(segment
		(start 204.037692 110.157273)
		(end 204.041328 110.125008)
		(width 0.14)
		(layer "F.Cu")
		(net 523)
	)
	(segment
		(start 203.32252 113.65031)
		(end 203.354189 113.618641)
		(width 0.14)
		(layer "F.Cu")
		(net 523)
	)
	(segment
		(start 203.354189 113.618641)
		(end 203.39211 113.594814)
		(width 0.14)
		(layer "F.Cu")
		(net 523)
	)
	(segment
		(start 203.896328 110.270008)
		(end 203.928593 110.266372)
		(width 0.14)
		(layer "F.Cu")
		(net 523)
	)
	(segment
		(start 203.278886 114.575008)
		(end 203.283901 114.530503)
		(width 0.14)
		(layer "F.Cu")
		(net 523)
	)
	(segment
		(start 204.036314 114.219512)
		(end 204.041328 114.175008)
		(width 0.14)
		(layer "F.Cu")
		(net 523)
	)
	(segment
		(start 203.137137 110.363538)
		(end 203.218422 110.312463)
		(width 0.14)
		(layer "F.Cu")
		(net 523)
	)
	(segment
		(start 203.32252 114.45031)
		(end 203.354189 114.418641)
		(width 0.14)
		(layer "F.Cu")
		(net 523)
	)
	(segment
		(start 203.39211 114.755201)
		(end 203.354189 114.731374)
		(width 0.14)
		(layer "F.Cu")
		(net 523)
	)
	(segment
		(start 203.309035 110.280756)
		(end 203.404432 110.270008)
		(width 0.14)
		(layer "F.Cu")
		(net 523)
	)
	(segment
		(start 204.021522 114.261784)
		(end 204.036314 114.219512)
		(width 0.14)
		(layer "F.Cu")
		(net 523)
	)
	(segment
		(start 203.298693 114.488231)
		(end 203.32252 114.45031)
		(width 0.14)
		(layer "F.Cu")
		(net 523)
	)
	(segment
		(start 203.841328 114.775008)
		(end 203.478886 114.775008)
		(width 0.14)
		(layer "F.Cu")
		(net 523)
	)
	(segment
		(start 202.986472 110.603319)
		(end 203.018179 110.512706)
		(width 0.14)
		(layer "F.Cu")
		(net 523)
	)
	(segment
		(start 203.928593 110.266372)
		(end 203.959241 110.255648)
		(width 0.14)
		(layer "F.Cu")
		(net 523)
	)
	(segment
		(start 203.928105 113.555201)
		(end 203.966026 113.531374)
		(width 0.14)
		(layer "F.Cu")
		(net 523)
	)
	(segment
		(start 203.966026 114.018641)
		(end 203.928105 113.994814)
		(width 0.14)
		(layer "F.Cu")
		(net 523)
	)
	(segment
		(start 205.075298 111.415414)
		(end 205.092573 111.387921)
		(width 0.14)
		(layer "F.Cu")
		(net 523)
	)
	(segment
		(start 204.041328 113.375008)
		(end 204.041328 112.525008)
		(width 0.14)
		(layer "F.Cu")
		(net 523)
	)
	(segment
		(start 205.103297 111.357273)
		(end 205.106932 111.325008)
		(width 0.14)
		(layer "F.Cu")
		(net 523)
	)
	(segment
		(start 204.036314 113.419512)
		(end 204.041328 113.375008)
		(width 0.14)
		(layer "F.Cu")
		(net 523)
	)
	(segment
		(start 203.896328 112.380008)
		(end 203.404432 112.380008)
		(width 0.14)
		(layer "F.Cu")
		(net 523)
	)
	(segment
		(start 204.036314 114.930503)
		(end 204.021522 114.888231)
		(width 0.14)
		(layer "F.Cu")
		(net 523)
	)
	(segment
		(start 203.434382 114.380022)
		(end 203.478886 114.375008)
		(width 0.14)
		(layer "F.Cu")
		(net 523)
	)
	(segment
		(start 203.309035 112.369259)
		(end 203.218422 112.337552)
		(width 0.14)
		(layer "F.Cu")
		(net 523)
	)
	(segment
		(start 203.218422 112.337552)
		(end 203.137137 112.286477)
		(width 0.14)
		(layer "F.Cu")
		(net 523)
	)
	(segment
		(start 203.218422 111.512463)
		(end 203.309035 111.480756)
		(width 0.14)
		(layer "F.Cu")
		(net 523)
	)
	(segment
		(start 203.434382 114.769993)
		(end 203.39211 114.755201)
		(width 0.14)
		(layer "F.Cu")
		(net 523)
	)
	(segment
		(start 202.975724 111.951299)
		(end 202.975724 111.898716)
		(width 0.14)
		(layer "F.Cu")
		(net 523)
	)
	(segment
		(start 203.069254 110.431421)
		(end 203.137137 110.363538)
		(width 0.14)
		(layer "F.Cu")
		(net 523)
	)
	(segment
		(start 203.928593 112.383643)
		(end 203.896328 112.380008)
		(width 0.14)
		(layer "F.Cu")
		(net 523)
	)
	(segment
		(start 203.885833 113.569993)
		(end 203.928105 113.555201)
		(width 0.14)
		(layer "F.Cu")
		(net 523)
	)
	(segment
		(start 203.997695 114.299705)
		(end 204.021522 114.261784)
		(width 0.14)
		(layer "F.Cu")
		(net 523)
	)
	(segment
		(start 204.009693 112.434601)
		(end 203.986734 112.411642)
		(width 0.14)
		(layer "F.Cu")
		(net 523)
	)
	(segment
		(start 203.309035 111.169259)
		(end 203.218422 111.137552)
		(width 0.14)
		(layer "F.Cu")
		(net 523)
	)
	(segment
		(start 203.32252 114.699705)
		(end 203.298693 114.661784)
		(width 0.14)
		(layer "F.Cu")
		(net 523)
	)
	(segment
		(start 203.841328 113.975008)
		(end 203.478886 113.975008)
		(width 0.14)
		(layer "F.Cu")
		(net 523)
	)
	(segment
		(start 203.966026 114.818641)
		(end 203.928105 114.794814)
		(width 0.14)
		(layer "F.Cu")
		(net 523)
	)
	(segment
		(start 203.341328 115.925008)
		(end 204.041328 115.225008)
		(width 0.14)
		(layer "F.Cu")
		(net 523)
	)
	(segment
		(start 203.069254 111.631421)
		(end 203.137137 111.563538)
		(width 0.14)
		(layer "F.Cu")
		(net 523)
	)
	(segment
		(start 204.037692 112.492742)
		(end 204.026968 112.462094)
		(width 0.14)
		(layer "F.Cu")
		(net 523)
	)
	(segment
		(start 203.997695 114.85031)
		(end 203.966026 114.818641)
		(width 0.14)
		(layer "F.Cu")
		(net 523)
	)
	(segment
		(start 203.32252 113.899705)
		(end 203.298693 113.861784)
		(width 0.14)
		(layer "F.Cu")
		(net 523)
	)
	(segment
		(start 203.841328 114.375008)
		(end 203.885833 114.369993)
		(width 0.14)
		(layer "F.Cu")
		(net 523)
	)
	(segment
		(start 203.997695 113.499705)
		(end 204.021522 113.461784)
		(width 0.14)
		(layer "F.Cu")
		(net 523)
	)
	(segment
		(start 202.975724 110.698716)
		(end 202.986472 110.603319)
		(width 0.14)
		(layer "F.Cu")
		(net 523)
	)
	(segment
		(start 203.478886 114.375008)
		(end 203.841328 114.375008)
		(width 0.14)
		(layer "F.Cu")
		(net 523)
	)
	(segment
		(start 203.283901 114.619512)
		(end 203.278886 114.575008)
		(width 0.14)
		(layer "F.Cu")
		(net 523)
	)
	(segment
		(start 203.928105 114.794814)
		(end 203.885833 114.780022)
		(width 0.14)
		(layer "F.Cu")
		(net 523)
	)
	(segment
		(start 204.041328 115.225008)
		(end 204.041328 114.975008)
		(width 0.14)
		(layer "F.Cu")
		(net 523)
	)
	(segment
		(start 203.283901 113.730503)
		(end 203.298693 113.688231)
		(width 0.14)
		(layer "F.Cu")
		(net 523)
	)
	(segment
		(start 204.961932 111.470008)
		(end 204.994198 111.466372)
		(width 0.14)
		(layer "F.Cu")
		(net 523)
	)
	(segment
		(start 203.39211 113.955201)
		(end 203.354189 113.931374)
		(width 0.14)
		(layer "F.Cu")
		(net 523)
	)
	(segment
		(start 204.994198 111.466372)
		(end 205.024846 111.455648)
		(width 0.14)
		(layer "F.Cu")
		(net 523)
	)
	(segment
		(start 202.281328 108.035008)
		(end 202.281328 106.569306)
		(width 0.14)
		(layer "F.Cu")
		(net 523)
	)
	(segment
		(start 203.478886 114.775008)
		(end 203.434382 114.769993)
		(width 0.14)
		(layer "F.Cu")
		(net 523)
	)
	(segment
		(start 205.092573 111.387921)
		(end 205.103297 111.357273)
		(width 0.14)
		(layer "F.Cu")
		(net 523)
	)
	(segment
		(start 203.137137 112.286477)
		(end 203.069254 112.218594)
		(width 0.14)
		(layer "F.Cu")
		(net 523)
	)
	(segment
		(start 204.041328 110.125008)
		(end 204.041328 109.795008)
		(width 0.14)
		(layer "F.Cu")
		(net 523)
	)
	(segment
		(start 202.975724 111.898716)
		(end 202.986472 111.803319)
		(width 0.14)
		(layer "F.Cu")
		(net 523)
	)
	(segment
		(start 203.39211 113.594814)
		(end 203.434382 113.580022)
		(width 0.14)
		(layer "F.Cu")
		(net 523)
	)
	(segment
		(start 204.041328 109.795008)
		(end 202.281328 108.035008)
		(width 0.14)
		(layer "F.Cu")
		(net 523)
	)
	(segment
		(start 204.009693 110.215414)
		(end 204.026968 110.187921)
		(width 0.14)
		(layer "F.Cu")
		(net 523)
	)
	(segment
		(start 202.986472 111.803319)
		(end 203.018179 111.712706)
		(width 0.14)
		(layer "F.Cu")
		(net 523)
	)
	(segment
		(start 203.354189 113.931374)
		(end 203.32252 113.899705)
		(width 0.14)
		(layer "F.Cu")
		(net 523)
	)
	(segment
		(start 203.885833 113.980022)
		(end 203.841328 113.975008)
		(width 0.14)
		(layer "F.Cu")
		(net 523)
	)
	(segment
		(start 203.966026 113.531374)
		(end 203.997695 113.499705)
		(width 0.14)
		(layer "F.Cu")
		(net 523)
	)
	(segment
		(start 203.018179 110.512706)
		(end 203.069254 110.431421)
		(width 0.14)
		(layer "F.Cu")
		(net 523)
	)
	(segment
		(start 205.024846 111.455648)
		(end 205.052339 111.438373)
		(width 0.14)
		(layer "F.Cu")
		(net 523)
	)
	(segment
		(start 204.994198 111.183643)
		(end 204.961932 111.180008)
		(width 0.14)
		(layer "F.Cu")
		(net 523)
	)
	(segment
		(start 203.218422 110.312463)
		(end 203.309035 110.280756)
		(width 0.14)
		(layer "F.Cu")
		(net 523)
	)
	(segment
		(start 203.283901 114.530503)
		(end 203.298693 114.488231)
		(width 0.14)
		(layer "F.Cu")
		(net 523)
	)
	(segment
		(start 203.218422 111.137552)
		(end 203.137137 111.086477)
		(width 0.14)
		(layer "F.Cu")
		(net 523)
	)
	(segment
		(start 205.052339 111.211642)
		(end 205.024846 111.194367)
		(width 0.14)
		(layer "F.Cu")
		(net 523)
	)
	(segment
		(start 203.928105 113.994814)
		(end 203.885833 113.980022)
		(width 0.14)
		(layer "F.Cu")
		(net 523)
	)
	(segment
		(start 203.928105 114.355201)
		(end 203.966026 114.331374)
		(width 0.14)
		(layer "F.Cu")
		(net 523)
	)
	(segment
		(start 203.137137 111.563538)
		(end 203.218422 111.512463)
		(width 0.14)
		(layer "F.Cu")
		(net 523)
	)
	(segment
		(start 203.069254 111.018594)
		(end 203.018179 110.937309)
		(width 0.14)
		(layer "F.Cu")
		(net 523)
	)
	(segment
		(start 204.021522 114.088231)
		(end 203.997695 114.05031)
		(width 0.14)
		(layer "F.Cu")
		(net 523)
	)
	(segment
		(start 203.404432 111.180008)
		(end 203.309035 111.169259)
		(width 0.14)
		(layer "F.Cu")
		(net 523)
	)
	(segment
		(start 205.106932 111.325008)
		(end 205.103297 111.292742)
		(width 0.14)
		(layer "F.Cu")
		(net 523)
	)
	(segment
		(start 203.434382 113.969993)
		(end 203.39211 113.955201)
		(width 0.14)
		(layer "F.Cu")
		(net 523)
	)
	(segment
		(start 203.966026 114.331374)
		(end 203.997695 114.299705)
		(width 0.14)
		(layer "F.Cu")
		(net 523)
	)
	(segment
		(start 203.298693 113.688231)
		(end 203.32252 113.65031)
		(width 0.14)
		(layer "F.Cu")
		(net 523)
	)
	(segment
		(start 202.281328 106.569306)
		(end 202.186328 106.474306)
		(width 0.14)
		(layer "F.Cu")
		(net 523)
	)
	(segment
		(start 203.478886 113.975008)
		(end 203.434382 113.969993)
		(width 0.14)
		(layer "F.Cu")
		(net 523)
	)
	(segment
		(start 203.283901 113.819512)
		(end 203.278886 113.775008)
		(width 0.14)
		(layer "F.Cu")
		(net 523)
	)
	(segment
		(start 203.309035 111.480756)
		(end 203.404432 111.470008)
		(width 0.14)
		(layer "F.Cu")
		(net 523)
	)
	(segment
		(start 204.026968 112.462094)
		(end 204.009693 112.434601)
		(width 0.14)
		(layer "F.Cu")
		(net 523)
	)
	(segment
		(start 202.975724 110.751299)
		(end 202.975724 110.698716)
		(width 0.14)
		(layer "F.Cu")
		(net 523)
	)
	(segment
		(start 203.018179 112.137309)
		(end 202.986472 112.046696)
		(width 0.14)
		(layer "F.Cu")
		(net 523)
	)
	(segment
		(start 205.075298 111.234601)
		(end 205.052339 111.211642)
		(width 0.14)
		(layer "F.Cu")
		(net 523)
	)
	(segment
		(start 203.278886 113.775008)
		(end 203.283901 113.730503)
		(width 0.14)
		(layer "F.Cu")
		(net 523)
	)
	(segment
		(start 203.959241 110.255648)
		(end 203.986734 110.238373)
		(width 0.14)
		(layer "F.Cu")
		(net 523)
	)
	(segment
		(start 203.885833 114.780022)
		(end 203.841328 114.775008)
		(width 0.14)
		(layer "F.Cu")
		(net 523)
	)
	(segment
		(start 204.021522 114.888231)
		(end 203.997695 114.85031)
		(width 0.14)
		(layer "F.Cu")
		(net 523)
	)
	(segment
		(start 204.036314 114.130503)
		(end 204.021522 114.088231)
		(width 0.14)
		(layer "F.Cu")
		(net 523)
	)
	(segment
		(start 201.129179 118.597157)
		(end 200.006328 119.720008)
		(width 0.14)
		(layer "F.Cu")
		(net 524)
	)
	(segment
		(start 199.186328 115.380008)
		(end 198.581328 114.775008)
		(width 0.14)
		(layer "F.Cu")
		(net 524)
	)
	(segment
		(start 202.071328 118.597157)
		(end 201.129179 118.597157)
		(width 0.14)
		(layer "F.Cu")
		(net 524)
	)
	(segment
		(start 200.006328 119.720008)
		(end 199.116328 119.720008)
		(width 0.14)
		(layer "F.Cu")
		(net 524)
	)
	(segment
		(start 199.186328 116.990008)
		(end 199.186328 115.380008)
		(width 0.14)
		(layer "F.Cu")
		(net 524)
	)
	(segment
		(start 198.216328 118.820008)
		(end 198.216328 117.960008)
		(width 0.14)
		(layer "F.Cu")
		(net 524)
	)
	(segment
		(start 198.216328 117.960008)
		(end 199.186328 116.990008)
		(width 0.14)
		(layer "F.Cu")
		(net 524)
	)
	(segment
		(start 199.116328 119.720008)
		(end 198.216328 118.820008)
		(width 0.14)
		(layer "F.Cu")
		(net 524)
	)
	(segment
		(start 200.091328 106.569306)
		(end 200.186328 106.474306)
		(width 0.14)
		(layer "F.Cu")
		(net 524)
	)
	(segment
		(start 200.091328 107.894212)
		(end 200.091328 106.569306)
		(width 0.14)
		(layer "F.Cu")
		(net 524)
	)
	(segment
		(start 198.581328 109.404212)
		(end 200.091328 107.894212)
		(width 0.14)
		(layer "F.Cu")
		(net 524)
	)
	(segment
		(start 198.581328 114.775008)
		(end 198.581328 109.404212)
		(width 0.14)
		(layer "F.Cu")
		(net 524)
	)
	(segment
		(start 195.807657 111.392094)
		(end 195.796933 111.422742)
		(width 0.14)
		(layer "F.Cu")
		(net 525)
	)
	(segment
		(start 195.875384 111.585648)
		(end 195.906032 111.596372)
		(width 0.14)
		(layer "F.Cu")
		(net 525)
	)
	(segment
		(start 196.991328 115.315008)
		(end 196.991328 118.597157)
		(width 0.14)
		(layer "F.Cu")
		(net 525)
	)
	(segment
		(start 195.938298 110.400008)
		(end 197.52065 110.400008)
		(width 0.14)
		(layer "F.Cu")
		(net 525)
	)
	(segment
		(start 195.938298 111.600008)
		(end 196.442619 111.600008)
		(width 0.14)
		(layer "F.Cu")
		(net 525)
	)
	(segment
		(start 197.616047 110.410756)
		(end 197.70666 110.442463)
		(width 0.14)
		(layer "F.Cu")
		(net 525)
	)
	(segment
		(start 195.824932 111.545414)
		(end 195.847891 111.568373)
		(width 0.14)
		(layer "F.Cu")
		(net 525)
	)
	(segment
		(start 195.807657 110.192094)
		(end 195.796933 110.222742)
		(width 0.14)
		(layer "F.Cu")
		(net 525)
	)
	(segment
		(start 196.709914 110.016477)
		(end 196.628629 110.067552)
		(width 0.14)
		(layer "F.Cu")
		(net 525)
	)
	(segment
		(start 195.906032 110.396372)
		(end 195.938298 110.400008)
		(width 0.14)
		(layer "F.Cu")
		(net 525)
	)
	(segment
		(start 196.538016 110.099259)
		(end 196.442619 110.110008)
		(width 0.14)
		(layer "F.Cu")
		(net 525)
	)
	(segment
		(start 197.52065 110.400008)
		(end 197.616047 110.410756)
		(width 0.14)
		(layer "F.Cu")
		(net 525)
	)
	(segment
		(start 197.70666 111.267552)
		(end 197.616047 111.299259)
		(width 0.14)
		(layer "F.Cu")
		(net 525)
	)
	(segment
		(start 195.875384 111.324367)
		(end 195.847891 111.341642)
		(width 0.14)
		(layer "F.Cu")
		(net 525)
	)
	(segment
		(start 195.847891 110.368373)
		(end 195.875384 110.385648)
		(width 0.14)
		(layer "F.Cu")
		(net 525)
	)
	(segment
		(start 196.777797 109.948594)
		(end 196.709914 110.016477)
		(width 0.14)
		(layer "F.Cu")
		(net 525)
	)
	(segment
		(start 197.949358 110.828716)
		(end 197.949358 110.881299)
		(width 0.14)
		(layer "F.Cu")
		(net 525)
	)
	(segment
		(start 198.686328 106.474306)
		(end 198.591328 106.569306)
		(width 0.14)
		(layer "F.Cu")
		(net 525)
	)
	(segment
		(start 197.93861 110.976696)
		(end 197.906903 111.067309)
		(width 0.14)
		(layer "F.Cu")
		(net 525)
	)
	(segment
		(start 195.938298 111.310008)
		(end 195.906032 111.313643)
		(width 0.14)
		(layer "F.Cu")
		(net 525)
	)
	(segment
		(start 196.442619 111.600008)
		(end 196.538016 111.610756)
		(width 0.14)
		(layer "F.Cu")
		(net 525)
	)
	(segment
		(start 195.847891 110.141642)
		(end 195.824932 110.164601)
		(width 0.14)
		(layer "F.Cu")
		(net 525)
	)
	(segment
		(start 197.855828 110.561421)
		(end 197.906903 110.642706)
		(width 0.14)
		(layer "F.Cu")
		(net 525)
	)
	(segment
		(start 197.906903 110.642706)
		(end 197.93861 110.733319)
		(width 0.14)
		(layer "F.Cu")
		(net 525)
	)
	(segment
		(start 195.824932 111.364601)
		(end 195.807657 111.392094)
		(width 0.14)
		(layer "F.Cu")
		(net 525)
	)
	(segment
		(start 197.616047 111.299259)
		(end 197.52065 111.310008)
		(width 0.14)
		(layer "F.Cu")
		(net 525)
	)
	(segment
		(start 195.807657 110.317921)
		(end 195.824932 110.345414)
		(width 0.14)
		(layer "F.Cu")
		(net 525)
	)
	(segment
		(start 195.793298 111.455008)
		(end 195.796933 111.487273)
		(width 0.14)
		(layer "F.Cu")
		(net 525)
	)
	(segment
		(start 196.871328 112.028716)
		(end 196.871328 115.195008)
		(width 0.14)
		(layer "F.Cu")
		(net 525)
	)
	(segment
		(start 196.777797 111.761421)
		(end 196.828872 111.842706)
		(width 0.14)
		(layer "F.Cu")
		(net 525)
	)
	(segment
		(start 196.828872 109.867309)
		(end 196.777797 109.948594)
		(width 0.14)
		(layer "F.Cu")
		(net 525)
	)
	(segment
		(start 195.847891 111.341642)
		(end 195.824932 111.364601)
		(width 0.14)
		(layer "F.Cu")
		(net 525)
	)
	(segment
		(start 195.796933 110.287273)
		(end 195.807657 110.317921)
		(width 0.14)
		(layer "F.Cu")
		(net 525)
	)
	(segment
		(start 197.949358 110.881299)
		(end 197.93861 110.976696)
		(width 0.14)
		(layer "F.Cu")
		(net 525)
	)
	(segment
		(start 195.906032 111.596372)
		(end 195.938298 111.600008)
		(width 0.14)
		(layer "F.Cu")
		(net 525)
	)
	(segment
		(start 197.906903 111.067309)
		(end 197.855828 111.148594)
		(width 0.14)
		(layer "F.Cu")
		(net 525)
	)
	(segment
		(start 197.787945 110.493538)
		(end 197.855828 110.561421)
		(width 0.14)
		(layer "F.Cu")
		(net 525)
	)
	(segment
		(start 195.793298 110.255008)
		(end 195.796933 110.287273)
		(width 0.14)
		(layer "F.Cu")
		(net 525)
	)
	(segment
		(start 195.824932 110.164601)
		(end 195.807657 110.192094)
		(width 0.14)
		(layer "F.Cu")
		(net 525)
	)
	(segment
		(start 196.860579 111.933319)
		(end 196.871328 112.028716)
		(width 0.14)
		(layer "F.Cu")
		(net 525)
	)
	(segment
		(start 196.628629 111.642463)
		(end 196.709914 111.693538)
		(width 0.14)
		(layer "F.Cu")
		(net 525)
	)
	(segment
		(start 195.796933 111.422742)
		(end 195.793298 111.455008)
		(width 0.14)
		(layer "F.Cu")
		(net 525)
	)
	(segment
		(start 197.93861 110.733319)
		(end 197.949358 110.828716)
		(width 0.14)
		(layer "F.Cu")
		(net 525)
	)
	(segment
		(start 198.591328 106.569306)
		(end 198.591328 107.794212)
		(width 0.14)
		(layer "F.Cu")
		(net 525)
	)
	(segment
		(start 196.871328 115.195008)
		(end 196.991328 115.315008)
		(width 0.14)
		(layer "F.Cu")
		(net 525)
	)
	(segment
		(start 196.860579 109.776696)
		(end 196.828872 109.867309)
		(width 0.14)
		(layer "F.Cu")
		(net 525)
	)
	(segment
		(start 195.847891 111.568373)
		(end 195.875384 111.585648)
		(width 0.14)
		(layer "F.Cu")
		(net 525)
	)
	(segment
		(start 196.709914 111.693538)
		(end 196.777797 111.761421)
		(width 0.14)
		(layer "F.Cu")
		(net 525)
	)
	(segment
		(start 195.875384 110.385648)
		(end 195.906032 110.396372)
		(width 0.14)
		(layer "F.Cu")
		(net 525)
	)
	(segment
		(start 195.824932 110.345414)
		(end 195.847891 110.368373)
		(width 0.14)
		(layer "F.Cu")
		(net 525)
	)
	(segment
		(start 196.628629 110.067552)
		(end 196.538016 110.099259)
		(width 0.14)
		(layer "F.Cu")
		(net 525)
	)
	(segment
		(start 197.787945 111.216477)
		(end 197.70666 111.267552)
		(width 0.14)
		(layer "F.Cu")
		(net 525)
	)
	(segment
		(start 196.871328 109.514212)
		(end 196.871328 109.681299)
		(width 0.14)
		(layer "F.Cu")
		(net 525)
	)
	(segment
		(start 195.906032 111.313643)
		(end 195.875384 111.324367)
		(width 0.14)
		(layer "F.Cu")
		(net 525)
	)
	(segment
		(start 195.796933 111.487273)
		(end 195.807657 111.517921)
		(width 0.14)
		(layer "F.Cu")
		(net 525)
	)
	(segment
		(start 195.875384 110.124367)
		(end 195.847891 110.141642)
		(width 0.14)
		(layer "F.Cu")
		(net 525)
	)
	(segment
		(start 195.906032 110.113643)
		(end 195.875384 110.124367)
		(width 0.14)
		(layer "F.Cu")
		(net 525)
	)
	(segment
		(start 195.796933 110.222742)
		(end 195.793298 110.255008)
		(width 0.14)
		(layer "F.Cu")
		(net 525)
	)
	(segment
		(start 197.52065 111.310008)
		(end 195.938298 111.310008)
		(width 0.14)
		(layer "F.Cu")
		(net 525)
	)
	(segment
		(start 198.591328 107.794212)
		(end 196.871328 109.514212)
		(width 0.14)
		(layer "F.Cu")
		(net 525)
	)
	(segment
		(start 197.70666 110.442463)
		(end 197.787945 110.493538)
		(width 0.14)
		(layer "F.Cu")
		(net 525)
	)
	(segment
		(start 195.807657 111.517921)
		(end 195.824932 111.545414)
		(width 0.14)
		(layer "F.Cu")
		(net 525)
	)
	(segment
		(start 195.938298 110.110008)
		(end 195.906032 110.113643)
		(width 0.14)
		(layer "F.Cu")
		(net 525)
	)
	(segment
		(start 197.855828 111.148594)
		(end 197.787945 111.216477)
		(width 0.14)
		(layer "F.Cu")
		(net 525)
	)
	(segment
		(start 196.538016 111.610756)
		(end 196.628629 111.642463)
		(width 0.14)
		(layer "F.Cu")
		(net 525)
	)
	(segment
		(start 196.442619 110.110008)
		(end 195.938298 110.110008)
		(width 0.14)
		(layer "F.Cu")
		(net 525)
	)
	(segment
		(start 196.828872 111.842706)
		(end 196.860579 111.933319)
		(width 0.14)
		(layer "F.Cu")
		(net 525)
	)
	(segment
		(start 196.871328 109.681299)
		(end 196.860579 109.776696)
		(width 0.14)
		(layer "F.Cu")
		(net 525)
	)
	(segment
		(start 201.091328 114.570008)
		(end 201.776229 114.570008)
		(width 0.14)
		(layer "F.Cu")
		(net 526)
	)
	(segment
		(start 202.029932 109.408716)
		(end 202.019184 109.313319)
		(width 0.14)
		(layer "F.Cu")
		(net 526)
	)
	(segment
		(start 201.776229 114.570008)
		(end 201.812944 114.565871)
		(width 0.14)
		(layer "F.Cu")
		(net 526)
	)
	(segment
		(start 200.365458 108.976372)
		(end 200.33481 108.965648)
		(width 0.14)
		(layer "F.Cu")
		(net 526)
	)
	(segment
		(start 201.847819 113.596348)
		(end 201.812944 113.584144)
		(width 0.14)
		(layer "F.Cu")
		(net 526)
	)
	(segment
		(start 200.257317 109.921642)
		(end 200.28481 109.904367)
		(width 0.14)
		(layer "F.Cu")
		(net 526)
	)
	(segment
		(start 201.127325 113.972132)
		(end 201.153452 113.946005)
		(width 0.14)
		(layer "F.Cu")
		(net 526)
	)
	(segment
		(start 200.206359 110.002742)
		(end 200.217083 109.972094)
		(width 0.14)
		(layer "F.Cu")
		(net 526)
	)
	(segment
		(start 201.936402 109.728594)
		(end 201.987477 109.647309)
		(width 0.14)
		(layer "F.Cu")
		(net 526)
	)
	(segment
		(start 201.072503 114.985916)
		(end 201.063023 114.979959)
		(width 0.14)
		(layer "F.Cu")
		(net 526)
	)
	(segment
		(start 201.937092 113.708292)
		(end 201.924888 113.673417)
		(width 0.14)
		(layer "F.Cu")
		(net 526)
	)
	(segment
		(start 200.99628 114.673313)
		(end 201.002237 114.663833)
		(width 0.14)
		(layer "F.Cu")
		(net 526)
	)
	(segment
		(start 201.879104 113.87401)
		(end 201.905231 113.847883)
		(width 0.14)
		(layer "F.Cu")
		(net 526)
	)
	(segment
		(start 202.019184 109.556696)
		(end 202.029932 109.461299)
		(width 0.14)
		(layer "F.Cu")
		(net 526)
	)
	(segment
		(start 200.992582 114.936134)
		(end 200.991328 114.925008)
		(width 0.14)
		(layer "F.Cu")
		(net 526)
	)
	(segment
		(start 201.937092 113.781723)
		(end 201.941229 113.745008)
		(width 0.14)
		(layer "F.Cu")
		(net 526)
	)
	(segment
		(start 200.206359 110.067273)
		(end 200.202724 110.035008)
		(width 0.14)
		(layer "F.Cu")
		(net 526)
	)
	(segment
		(start 201.127325 113.517883)
		(end 201.107668 113.486598)
		(width 0.14)
		(layer "F.Cu")
		(net 526)
	)
	(segment
		(start 201.868519 109.073538)
		(end 201.787234 109.022463)
		(width 0.14)
		(layer "F.Cu")
		(net 526)
	)
	(segment
		(start 201.091328 111.808716)
		(end 201.080579 111.713319)
		(width 0.14)
		(layer "F.Cu")
		(net 526)
	)
	(segment
		(start 201.091328 110.608716)
		(end 201.080579 110.513319)
		(width 0.14)
		(layer "F.Cu")
		(net 526)
	)
	(segment
		(start 201.696621 108.990756)
		(end 201.601224 108.980008)
		(width 0.14)
		(layer "F.Cu")
		(net 526)
	)
	(segment
		(start 200.347724 109.890008)
		(end 201.601224 109.890008)
		(width 0.14)
		(layer "F.Cu")
		(net 526)
	)
	(segment
		(start 201.219612 113.575871)
		(end 201.184737 113.563667)
		(width 0.14)
		(layer "F.Cu")
		(net 526)
	)
	(segment
		(start 201.091328 113.415008)
		(end 201.091328 111.808716)
		(width 0.14)
		(layer "F.Cu")
		(net 526)
	)
	(segment
		(start 201.041328 114.645008)
		(end 201.091328 114.645008)
		(width 0.14)
		(layer "F.Cu")
		(net 526)
	)
	(segment
		(start 201.868519 109.796477)
		(end 201.936402 109.728594)
		(width 0.14)
		(layer "F.Cu")
		(net 526)
	)
	(segment
		(start 201.696621 109.879259)
		(end 201.787234 109.847552)
		(width 0.14)
		(layer "F.Cu")
		(net 526)
	)
	(segment
		(start 201.153452 113.946005)
		(end 201.184737 113.926348)
		(width 0.14)
		(layer "F.Cu")
		(net 526)
	)
	(segment
		(start 201.107668 114.146598)
		(end 201.095464 114.111723)
		(width 0.14)
		(layer "F.Cu")
		(net 526)
	)
	(segment
		(start 200.265458 111.093643)
		(end 200.297724 111.090008)
		(width 0.14)
		(layer "F.Cu")
		(net 526)
	)
	(segment
		(start 201.787234 109.847552)
		(end 201.868519 109.796477)
		(width 0.14)
		(layer "F.Cu")
		(net 526)
	)
	(segment
		(start 200.33481 108.704367)
		(end 200.365458 108.693643)
		(width 0.14)
		(layer "F.Cu")
		(net 526)
	)
	(segment
		(start 201.184737 114.223667)
		(end 201.153452 114.20401)
		(width 0.14)
		(layer "F.Cu")
		(net 526)
	)
	(segment
		(start 201.063023 114.979959)
		(end 201.052455 114.976261)
		(width 0.14)
		(layer "F.Cu")
		(net 526)
	)
	(segment
		(start 200.99628 114.946702)
		(end 200.992582 114.936134)
		(width 0.14)
		(layer "F.Cu")
		(net 526)
	)
	(segment
		(start 200.184358 111.144601)
		(end 200.207317 111.121642)
		(width 0.14)
		(layer "F.Cu")
		(net 526)
	)
	(segment
		(start 200.365458 108.693643)
		(end 200.397724 108.690008)
		(width 0.14)
		(layer "F.Cu")
		(net 526)
	)
	(segment
		(start 200.347724 110.180008)
		(end 200.315458 110.176372)
		(width 0.14)
		(layer "F.Cu")
		(net 526)
	)
	(segment
		(start 201.905231 113.642132)
		(end 201.879104 113.616005)
		(width 0.14)
		(layer "F.Cu")
		(net 526)
	)
	(segment
		(start 201.052455 114.976261)
		(end 201.030202 114.973754)
		(width 0.14)
		(layer "F.Cu")
		(net 526)
	)
	(segment
		(start 201.095464 114.038292)
		(end 201.107668 114.003417)
		(width 0.14)
		(layer "F.Cu")
		(net 526)
	)
	(segment
		(start 200.929914 110.273538)
		(end 200.848629 110.222463)
		(width 0.14)
		(layer "F.Cu")
		(net 526)
	)
	(segment
		(start 200.256359 108.802742)
		(end 200.267083 108.772094)
		(width 0.14)
		(layer "F.Cu")
		(net 526)
	)
	(segment
		(start 201.776229 113.580008)
		(end 201.256328 113.580008)
		(width 0.14)
		(layer "F.Cu")
		(net 526)
	)
	(segment
		(start 201.091328 115.767157)
		(end 201.091328 115.025008)
		(width 0.14)
		(layer "F.Cu")
		(net 526)
	)
	(segment
		(start 200.397724 108.980008)
		(end 200.365458 108.976372)
		(width 0.14)
		(layer "F.Cu")
		(net 526)
	)
	(segment
		(start 200.307317 108.721642)
		(end 200.33481 108.704367)
		(width 0.14)
		(layer "F.Cu")
		(net 526)
	)
	(segment
		(start 201.812944 113.584144)
		(end 201.776229 113.580008)
		(width 0.14)
		(layer "F.Cu")
		(net 526)
	)
	(segment
		(start 200.284358 108.925414)
		(end 200.267083 108.897921)
		(width 0.14)
		(layer "F.Cu")
		(net 526)
	)
	(segment
		(start 201.091328 115.025008)
		(end 201.090075 115.013881)
		(width 0.14)
		(layer "F.Cu")
		(net 526)
	)
	(segment
		(start 200.207317 111.121642)
		(end 200.23481 111.104367)
		(width 0.14)
		(layer "F.Cu")
		(net 526)
	)
	(segment
		(start 201.787234 109.022463)
		(end 201.696621 108.990756)
		(width 0.14)
		(layer "F.Cu")
		(net 526)
	)
	(segment
		(start 201.002237 114.956182)
		(end 200.99628 114.946702)
		(width 0.14)
		(layer "F.Cu")
		(net 526)
	)
	(segment
		(start 200.33481 108.965648)
		(end 200.307317 108.948373)
		(width 0.14)
		(layer "F.Cu")
		(net 526)
	)
	(segment
		(start 201.095464 114.111723)
		(end 201.091328 114.075008)
		(width 0.14)
		(layer "F.Cu")
		(net 526)
	)
	(segment
		(start 201.010154 114.964099)
		(end 201.002237 114.956182)
		(width 0.14)
		(layer "F.Cu")
		(net 526)
	)
	(segment
		(start 200.758016 108.679259)
		(end 200.848629 108.647552)
		(width 0.14)
		(layer "F.Cu")
		(net 526)
	)
	(segment
		(start 201.091328 114.075008)
		(end 201.095464 114.038292)
		(width 0.14)
		(layer "F.Cu")
		(net 526)
	)
	(segment
		(start 200.997797 110.928594)
		(end 201.048872 110.847309)
		(width 0.14)
		(layer "F.Cu")
		(net 526)
	)
	(segment
		(start 201.030202 114.646261)
		(end 201.041328 114.645008)
		(width 0.14)
		(layer "F.Cu")
		(net 526)
	)
	(segment
		(start 201.030202 114.973754)
		(end 201.019634 114.970056)
		(width 0.14)
		(layer "F.Cu")
		(net 526)
	)
	(segment
		(start 201.080579 110.513319)
		(end 201.048872 110.422706)
		(width 0.14)
		(layer "F.Cu")
		(net 526)
	)
	(segment
		(start 201.091328 110.661299)
		(end 201.091328 110.608716)
		(width 0.14)
		(layer "F.Cu")
		(net 526)
	)
	(segment
		(start 200.397724 108.690008)
		(end 200.662619 108.690008)
		(width 0.14)
		(layer "F.Cu")
		(net 526)
	)
	(segment
		(start 201.219612 113.914144)
		(end 201.256328 113.910008)
		(width 0.14)
		(layer "F.Cu")
		(net 526)
	)
	(segment
		(start 200.848629 110.222463)
		(end 200.758016 110.190756)
		(width 0.14)
		(layer "F.Cu")
		(net 526)
	)
	(segment
		(start 201.812944 114.565871)
		(end 201.847819 114.553667)
		(width 0.14)
		(layer "F.Cu")
		(net 526)
	)
	(segment
		(start 201.080579 108.356696)
		(end 201.091328 108.261299)
		(width 0.14)
		(layer "F.Cu")
		(net 526)
	)
	(segment
		(start 200.315458 110.176372)
		(end 200.28481 110.165648)
		(width 0.14)
		(layer "F.Cu")
		(net 526)
	)
	(segment
		(start 201.924888 114.476598)
		(end 201.937092 114.441723)
		(width 0.14)
		(layer "F.Cu")
		(net 526)
	)
	(segment
		(start 200.284358 108.744601)
		(end 200.307317 108.721642)
		(width 0.14)
		(layer "F.Cu")
		(net 526)
	)
	(segment
		(start 201.847819 113.893667)
		(end 201.879104 113.87401)
		(width 0.14)
		(layer "F.Cu")
		(net 526)
	)
	(segment
		(start 200.257317 110.148373)
		(end 200.234358 110.125414)
		(width 0.14)
		(layer "F.Cu")
		(net 526)
	)
	(segment
		(start 200.217083 109.972094)
		(end 200.234358 109.944601)
		(width 0.14)
		(layer "F.Cu")
		(net 526)
	)
	(segment
		(start 200.184358 111.325414)
		(end 200.167083 111.297921)
		(width 0.14)
		(layer "F.Cu")
		(net 526)
	)
	(segment
		(start 201.091328 108.261299)
		(end 201.091328 106.569306)
		(width 0.14)
		(layer "F.Cu")
		(net 526)
	)
	(segment
		(start 201.905231 113.847883)
		(end 201.924888 113.816598)
		(width 0.14)
		(layer "F.Cu")
		(net 526)
	)
	(segment
		(start 201.941229 113.745008)
		(end 201.937092 113.708292)
		(width 0.14)
		(layer "F.Cu")
		(net 526)
	)
	(segment
		(start 200.758016 111.079259)
		(end 200.848629 111.047552)
		(width 0.14)
		(layer "F.Cu")
		(net 526)
	)
	(segment
		(start 201.847819 114.256348)
		(end 201.812944 114.244144)
		(width 0.14)
		(layer "F.Cu")
		(net 526)
	)
	(segment
		(start 200.202724 110.035008)
		(end 200.206359 110.002742)
		(width 0.14)
		(layer "F.Cu")
		(net 526)
	)
	(segment
		(start 201.048872 108.447309)
		(end 201.080579 108.356696)
		(width 0.14)
		(layer "F.Cu")
		(net 526)
	)
	(segment
		(start 201.107668 114.003417)
		(end 201.127325 113.972132)
		(width 0.14)
		(layer "F.Cu")
		(net 526)
	)
	(segment
		(start 201.924888 113.816598)
		(end 201.937092 113.781723)
		(width 0.14)
		(layer "F.Cu")
		(net 526)
	)
	(segment
		(start 200.929914 111.473538)
		(end 200.848629 111.422463)
		(width 0.14)
		(layer "F.Cu")
		(net 526)
	)
	(segment
		(start 201.010154 114.655916)
		(end 201.019634 114.649959)
		(width 0.14)
		(layer "F.Cu")
		(net 526)
	)
	(segment
		(start 200.758016 110.190756)
		(end 200.662619 110.180008)
		(width 0.14)
		(layer "F.Cu")
		(net 526)
	)
	(segment
		(start 200.156359 111.267273)
		(end 200.152724 111.235008)
		(width 0.14)
		(layer "F.Cu")
		(net 526)
	)
	(segment
		(start 201.987477 109.222706)
		(end 201.936402 109.141421)
		(width 0.14)
		(layer "F.Cu")
		(net 526)
	)
	(segment
		(start 200.252724 108.835008)
		(end 200.256359 108.802742)
		(width 0.14)
		(layer "F.Cu")
		(net 526)
	)
	(segment
		(start 201.987477 109.647309)
		(end 202.019184 109.556696)
		(width 0.14)
		(layer "F.Cu")
		(net 526)
	)
	(segment
		(start 200.28481 110.165648)
		(end 200.257317 110.148373)
		(width 0.14)
		(layer "F.Cu")
		(net 526)
	)
	(segment
		(start 200.167083 111.172094)
		(end 200.184358 111.144601)
		(width 0.14)
		(layer "F.Cu")
		(net 526)
	)
	(segment
		(start 200.265458 111.376372)
		(end 200.23481 111.365648)
		(width 0.14)
		(layer "F.Cu")
		(net 526)
	)
	(segment
		(start 200.991328 114.695008)
		(end 200.992582 114.683881)
		(width 0.14)
		(layer "F.Cu")
		(net 526)
	)
	(segment
		(start 201.905231 114.507883)
		(end 201.924888 114.476598)
		(width 0.14)
		(layer "F.Cu")
		(net 526)
	)
	(segment
		(start 201.256328 114.240008)
		(end 201.219612 114.235871)
		(width 0.14)
		(layer "F.Cu")
		(net 526)
	)
	(segment
		(start 200.992582 114.683881)
		(end 200.99628 114.673313)
		(width 0.14)
		(layer "F.Cu")
		(net 526)
	)
	(segment
		(start 201.153452 114.20401)
		(end 201.127325 114.177883)
		(width 0.14)
		(layer "F.Cu")
		(net 526)
	)
	(segment
		(start 201.601224 109.890008)
		(end 201.696621 109.879259)
		(width 0.14)
		(layer "F.Cu")
		(net 526)
	)
	(segment
		(start 201.219612 114.235871)
		(end 201.184737 114.223667)
		(width 0.14)
		(layer "F.Cu")
		(net 526)
	)
	(segment
		(start 201.879104 114.276005)
		(end 201.847819 114.256348)
		(width 0.14)
		(layer "F.Cu")
		(net 526)
	)
	(segment
		(start 201.095464 113.451723)
		(end 201.091328 113.415008)
		(width 0.14)
		(layer "F.Cu")
		(net 526)
	)
	(segment
		(start 202.029932 109.461299)
		(end 202.029932 109.408716)
		(width 0.14)
		(layer "F.Cu")
		(net 526)
	)
	(segment
		(start 201.924888 114.333417)
		(end 201.905231 114.302132)
		(width 0.14)
		(layer "F.Cu")
		(net 526)
	)
	(segment
		(start 200.297724 111.090008)
		(end 200.662619 111.090008)
		(width 0.14)
		(layer "F.Cu")
		(net 526)
	)
	(segment
		(start 200.28481 109.904367)
		(end 200.315458 109.893643)
		(width 0.14)
		(layer "F.Cu")
		(net 526)
	)
	(segment
		(start 200.662619 110.180008)
		(end 200.347724 110.180008)
		(width 0.14)
		(layer "F.Cu")
		(net 526)
	)
	(segment
		(start 200.207317 111.348373)
		(end 200.184358 111.325414)
		(width 0.14)
		(layer "F.Cu")
		(net 526)
	)
	(segment
		(start 201.924888 113.673417)
		(end 201.905231 113.642132)
		(width 0.14)
		(layer "F.Cu")
		(net 526)
	)
	(segment
		(start 201.08042 114.993833)
		(end 201.072503 114.985916)
		(width 0.14)
		(layer "F.Cu")
		(net 526)
	)
	(segment
		(start 201.879104 114.53401)
		(end 201.905231 114.507883)
		(width 0.14)
		(layer "F.Cu")
		(net 526)
	)
	(segment
		(start 201.153452 113.54401)
		(end 201.127325 113.517883)
		(width 0.14)
		(layer "F.Cu")
		(net 526)
	)
	(segment
		(start 201.601224 108.980008)
		(end 200.397724 108.980008)
		(width 0.14)
		(layer "F.Cu")
		(net 526)
	)
	(segment
		(start 201.048872 111.622706)
		(end 200.997797 111.541421)
		(width 0.14)
		(layer "F.Cu")
		(net 526)
	)
	(segment
		(start 201.937092 114.441723)
		(end 201.941229 114.405008)
		(width 0.14)
		(layer "F.Cu")
		(net 526)
	)
	(segment
		(start 200.662619 111.090008)
		(end 200.758016 111.079259)
		(width 0.14)
		(layer "F.Cu")
		(net 526)
	)
	(segment
		(start 200.256359 108.867273)
		(end 200.252724 108.835008)
		(width 0.14)
		(layer "F.Cu")
		(net 526)
	)
	(segment
		(start 201.091328 114.645008)
		(end 201.091328 114.570008)
		(width 0.14)
		(layer "F.Cu")
		(net 526)
	)
	(segment
		(start 200.997797 111.541421)
		(end 200.929914 111.473538)
		(width 0.14)
		(layer "F.Cu")
		(net 526)
	)
	(segment
		(start 201.812944 113.905871)
		(end 201.847819 113.893667)
		(width 0.14)
		(layer "F.Cu")
		(net 526)
	)
	(segment
		(start 200.315458 109.893643)
		(end 200.347724 109.890008)
		(width 0.14)
		(layer "F.Cu")
		(net 526)
	)
	(segment
		(start 200.991328 114.925008)
		(end 200.991328 114.695008)
		(width 0.14)
		(layer "F.Cu")
		(net 526)
	)
	(segment
		(start 201.080579 111.713319)
		(end 201.048872 111.622706)
		(width 0.14)
		(layer "F.Cu")
		(net 526)
	)
	(segment
		(start 200.267083 108.897921)
		(end 200.256359 108.867273)
		(width 0.14)
		(layer "F.Cu")
		(net 526)
	)
	(segment
		(start 201.086377 115.003313)
		(end 201.08042 114.993833)
		(width 0.14)
		(layer "F.Cu")
		(net 526)
	)
	(segment
		(start 201.936402 109.141421)
		(end 201.868519 109.073538)
		(width 0.14)
		(layer "F.Cu")
		(net 526)
	)
	(segment
		(start 200.152724 111.235008)
		(end 200.156359 111.202742)
		(width 0.14)
		(layer "F.Cu")
		(net 526)
	)
	(segment
		(start 201.256328 113.580008)
		(end 201.219612 113.575871)
		(width 0.14)
		(layer "F.Cu")
		(net 526)
	)
	(segment
		(start 200.217083 110.097921)
		(end 200.206359 110.067273)
		(width 0.14)
		(layer "F.Cu")
		(net 526)
	)
	(segment
		(start 201.905231 114.302132)
		(end 201.879104 114.276005)
		(width 0.14)
		(layer "F.Cu")
		(net 526)
	)
	(segment
		(start 201.776229 114.240008)
		(end 201.256328 114.240008)
		(width 0.14)
		(layer "F.Cu")
		(net 526)
	)
	(segment
		(start 200.662619 111.380008)
		(end 200.297724 111.380008)
		(width 0.14)
		(layer "F.Cu")
		(net 526)
	)
	(segment
		(start 200.307317 108.948373)
		(end 200.284358 108.925414)
		(width 0.14)
		(layer "F.Cu")
		(net 526)
	)
	(segment
		(start 200.297724 111.380008)
		(end 200.265458 111.376372)
		(width 0.14)
		(layer "F.Cu")
		(net 526)
	)
	(segment
		(start 201.937092 114.368292)
		(end 201.924888 114.333417)
		(width 0.14)
		(layer "F.Cu")
		(net 526)
	)
	(segment
		(start 201.256328 113.910008)
		(end 201.776229 113.910008)
		(width 0.14)
		(layer "F.Cu")
		(net 526)
	)
	(segment
		(start 201.776229 113.910008)
		(end 201.812944 113.905871)
		(width 0.14)
		(layer "F.Cu")
		(net 526)
	)
	(segment
		(start 201.812944 114.244144)
		(end 201.776229 114.240008)
		(width 0.14)
		(layer "F.Cu")
		(net 526)
	)
	(segment
		(start 201.048872 110.422706)
		(end 200.997797 110.341421)
		(width 0.14)
		(layer "F.Cu")
		(net 526)
	)
	(segment
		(start 201.847819 114.553667)
		(end 201.879104 114.53401)
		(width 0.14)
		(layer "F.Cu")
		(net 526)
	)
	(segment
		(start 200.929914 108.596477)
		(end 200.997797 108.528594)
		(width 0.14)
		(layer "F.Cu")
		(net 526)
	)
	(segment
		(start 201.184737 113.926348)
		(end 201.219612 113.914144)
		(width 0.14)
		(layer "F.Cu")
		(net 526)
	)
	(segment
		(start 200.848629 111.422463)
		(end 200.758016 111.390756)
		(width 0.14)
		(layer "F.Cu")
		(net 526)
	)
	(segment
		(start 200.156359 111.202742)
		(end 200.167083 111.172094)
		(width 0.14)
		(layer "F.Cu")
		(net 526)
	)
	(segment
		(start 200.234358 109.944601)
		(end 200.257317 109.921642)
		(width 0.14)
		(layer "F.Cu")
		(net 526)
	)
	(segment
		(start 201.019634 114.970056)
		(end 201.010154 114.964099)
		(width 0.14)
		(layer "F.Cu")
		(net 526)
	)
	(segment
		(start 201.184737 113.563667)
		(end 201.153452 113.54401)
		(width 0.14)
		(layer "F.Cu")
		(net 526)
	)
	(segment
		(start 201.048872 110.847309)
		(end 201.080579 110.756696)
		(width 0.14)
		(layer "F.Cu")
		(net 526)
	)
	(segment
		(start 200.234358 110.125414)
		(end 200.217083 110.097921)
		(width 0.14)
		(layer "F.Cu")
		(net 526)
	)
	(segment
		(start 201.107668 113.486598)
		(end 201.095464 113.451723)
		(width 0.14)
		(layer "F.Cu")
		(net 526)
	)
	(segment
		(start 201.941229 114.405008)
		(end 201.937092 114.368292)
		(width 0.14)
		(layer "F.Cu")
		(net 526)
	)
	(segment
		(start 200.267083 108.772094)
		(end 200.284358 108.744601)
		(width 0.14)
		(layer "F.Cu")
		(net 526)
	)
	(segment
		(start 200.662619 108.690008)
		(end 200.758016 108.679259)
		(width 0.14)
		(layer "F.Cu")
		(net 526)
	)
	(segment
		(start 200.848629 108.647552)
		(end 200.929914 108.596477)
		(width 0.14)
		(layer "F.Cu")
		(net 526)
	)
	(segment
		(start 200.997797 108.528594)
		(end 201.048872 108.447309)
		(width 0.14)
		(layer "F.Cu")
		(net 526)
	)
	(segment
		(start 200.997797 110.341421)
		(end 200.929914 110.273538)
		(width 0.14)
		(layer "F.Cu")
		(net 526)
	)
	(segment
		(start 200.929914 110.996477)
		(end 200.997797 110.928594)
		(width 0.14)
		(layer "F.Cu")
		(net 526)
	)
	(segment
		(start 202.019184 109.313319)
		(end 201.987477 109.222706)
		(width 0.14)
		(layer "F.Cu")
		(net 526)
	)
	(segment
		(start 200.23481 111.104367)
		(end 200.265458 111.093643)
		(width 0.14)
		(layer "F.Cu")
		(net 526)
	)
	(segment
		(start 201.091328 106.569306)
		(end 201.186328 106.474306)
		(width 0.14)
		(layer "F.Cu")
		(net 526)
	)
	(segment
		(start 201.127325 114.177883)
		(end 201.107668 114.146598)
		(width 0.14)
		(layer "F.Cu")
		(net 526)
	)
	(segment
		(start 200.801328 116.057157)
		(end 201.091328 115.767157)
		(width 0.14)
		(layer "F.Cu")
		(net 526)
	)
	(segment
		(start 201.879104 113.616005)
		(end 201.847819 113.596348)
		(width 0.14)
		(layer "F.Cu")
		(net 526)
	)
	(segment
		(start 200.848629 111.047552)
		(end 200.929914 110.996477)
		(width 0.14)
		(layer "F.Cu")
		(net 526)
	)
	(segment
		(start 201.002237 114.663833)
		(end 201.010154 114.655916)
		(width 0.14)
		(layer "F.Cu")
		(net 526)
	)
	(segment
		(start 200.758016 111.390756)
		(end 200.662619 111.380008)
		(width 0.14)
		(layer "F.Cu")
		(net 526)
	)
	(segment
		(start 201.080579 110.756696)
		(end 201.091328 110.661299)
		(width 0.14)
		(layer "F.Cu")
		(net 526)
	)
	(segment
		(start 201.019634 114.649959)
		(end 201.030202 114.646261)
		(width 0.14)
		(layer "F.Cu")
		(net 526)
	)
	(segment
		(start 200.23481 111.365648)
		(end 200.207317 111.348373)
		(width 0.14)
		(layer "F.Cu")
		(net 526)
	)
	(segment
		(start 200.167083 111.297921)
		(end 200.156359 111.267273)
		(width 0.14)
		(layer "F.Cu")
		(net 526)
	)
	(segment
		(start 201.090075 115.013881)
		(end 201.086377 115.003313)
		(width 0.14)
		(layer "F.Cu")
		(net 526)
	)
	(segment
		(start 203.398458 110.583643)
		(end 203.36781 110.594367)
		(width 0.14)
		(layer "F.Cu")
		(net 527)
	)
	(segment
		(start 203.36781 112.055648)
		(end 203.398458 112.066372)
		(width 0.14)
		(layer "F.Cu")
		(net 527)
	)
	(segment
		(start 204.988224 111.780008)
		(end 203.430724 111.780008)
		(width 0.14)
		(layer "F.Cu")
		(net 527)
	)
	(segment
		(start 204.189914 110.486477)
		(end 204.108629 110.537552)
		(width 0.14)
		(layer "F.Cu")
		(net 527)
	)
	(segment
		(start 203.922619 110.580008)
		(end 203.430724 110.580008)
		(width 0.14)
		(layer "F.Cu")
		(net 527)
	)
	(segment
		(start 205.255519 111.686477)
		(end 205.174234 111.737552)
		(width 0.14)
		(layer "F.Cu")
		(net 527)
	)
	(segment
		(start 204.108629 112.112463)
		(end 204.189914 112.163538)
		(width 0.14)
		(layer "F.Cu")
		(net 527)
	)
	(segment
		(start 203.289359 110.692742)
		(end 203.285724 110.725008)
		(width 0.14)
		(layer "F.Cu")
		(net 527)
	)
	(segment
		(start 203.36781 110.594367)
		(end 203.340317 110.611642)
		(width 0.14)
		(layer "F.Cu")
		(net 527)
	)
	(segment
		(start 203.36781 111.794367)
		(end 203.340317 111.811642)
		(width 0.14)
		(layer "F.Cu")
		(net 527)
	)
	(segment
		(start 205.174234 110.912463)
		(end 205.255519 110.963538)
		(width 0.14)
		(layer "F.Cu")
		(net 527)
	)
	(segment
		(start 205.323402 111.618594)
		(end 205.255519 111.686477)
		(width 0.14)
		(layer "F.Cu")
		(net 527)
	)
	(segment
		(start 204.108629 110.537552)
		(end 204.018016 110.569259)
		(width 0.14)
		(layer "F.Cu")
		(net 527)
	)
	(segment
		(start 203.300083 111.862094)
		(end 203.289359 111.892742)
		(width 0.14)
		(layer "F.Cu")
		(net 527)
	)
	(segment
		(start 203.398458 112.066372)
		(end 203.430724 112.070008)
		(width 0.14)
		(layer "F.Cu")
		(net 527)
	)
	(segment
		(start 205.406184 111.446696)
		(end 205.374477 111.537309)
		(width 0.14)
		(layer "F.Cu")
		(net 527)
	)
	(segment
		(start 204.018016 112.080756)
		(end 204.108629 112.112463)
		(width 0.14)
		(layer "F.Cu")
		(net 527)
	)
	(segment
		(start 205.174234 111.737552)
		(end 205.083621 111.769259)
		(width 0.14)
		(layer "F.Cu")
		(net 527)
	)
	(segment
		(start 203.36781 110.855648)
		(end 203.398458 110.866372)
		(width 0.14)
		(layer "F.Cu")
		(net 527)
	)
	(segment
		(start 203.340317 110.611642)
		(end 203.317358 110.634601)
		(width 0.14)
		(layer "F.Cu")
		(net 527)
	)
	(segment
		(start 203.398458 111.783643)
		(end 203.36781 111.794367)
		(width 0.14)
		(layer "F.Cu")
		(net 527)
	)
	(segment
		(start 204.351328 118.337157)
		(end 204.611328 118.597157)
		(width 0.14)
		(layer "F.Cu")
		(net 527)
	)
	(segment
		(start 204.351328 112.498716)
		(end 204.351328 118.337157)
		(width 0.14)
		(layer "F.Cu")
		(net 527)
	)
	(segment
		(start 202.686328 106.474306)
		(end 202.591328 106.569306)
		(width 0.14)
		(layer "F.Cu")
		(net 527)
	)
	(segment
		(start 203.317358 110.634601)
		(end 203.300083 110.662094)
		(width 0.14)
		(layer "F.Cu")
		(net 527)
	)
	(segment
		(start 203.285724 111.925008)
		(end 203.289359 111.957273)
		(width 0.14)
		(layer "F.Cu")
		(net 527)
	)
	(segment
		(start 204.257797 112.231421)
		(end 204.308872 112.312706)
		(width 0.14)
		(layer "F.Cu")
		(net 527)
	)
	(segment
		(start 204.018016 110.569259)
		(end 203.922619 110.580008)
		(width 0.14)
		(layer "F.Cu")
		(net 527)
	)
	(segment
		(start 203.340317 111.811642)
		(end 203.317358 111.834601)
		(width 0.14)
		(layer "F.Cu")
		(net 527)
	)
	(segment
		(start 203.289359 111.957273)
		(end 203.300083 111.987921)
		(width 0.14)
		(layer "F.Cu")
		(net 527)
	)
	(segment
		(start 205.083621 111.769259)
		(end 204.988224 111.780008)
		(width 0.14)
		(layer "F.Cu")
		(net 527)
	)
	(segment
		(start 203.300083 111.987921)
		(end 203.317358 112.015414)
		(width 0.14)
		(layer "F.Cu")
		(net 527)
	)
	(segment
		(start 205.374477 111.537309)
		(end 205.323402 111.618594)
		(width 0.14)
		(layer "F.Cu")
		(net 527)
	)
	(segment
		(start 204.351328 109.665008)
		(end 204.351328 110.151299)
		(width 0.14)
		(layer "F.Cu")
		(net 527)
	)
	(segment
		(start 205.416932 111.351299)
		(end 205.406184 111.446696)
		(width 0.14)
		(layer "F.Cu")
		(net 527)
	)
	(segment
		(start 203.430724 110.580008)
		(end 203.398458 110.583643)
		(width 0.14)
		(layer "F.Cu")
		(net 527)
	)
	(segment
		(start 204.308872 110.337309)
		(end 204.257797 110.418594)
		(width 0.14)
		(layer "F.Cu")
		(net 527)
	)
	(segment
		(start 203.285724 110.725008)
		(end 203.289359 110.757273)
		(width 0.14)
		(layer "F.Cu")
		(net 527)
	)
	(segment
		(start 204.257797 110.418594)
		(end 204.189914 110.486477)
		(width 0.14)
		(layer "F.Cu")
		(net 527)
	)
	(segment
		(start 205.416932 111.298716)
		(end 205.416932 111.351299)
		(width 0.14)
		(layer "F.Cu")
		(net 527)
	)
	(segment
		(start 204.340579 110.246696)
		(end 204.308872 110.337309)
		(width 0.14)
		(layer "F.Cu")
		(net 527)
	)
	(segment
		(start 203.430724 112.070008)
		(end 203.922619 112.070008)
		(width 0.14)
		(layer "F.Cu")
		(net 527)
	)
	(segment
		(start 205.323402 111.031421)
		(end 205.374477 111.112706)
		(width 0.14)
		(layer "F.Cu")
		(net 527)
	)
	(segment
		(start 204.189914 112.163538)
		(end 204.257797 112.231421)
		(width 0.14)
		(layer "F.Cu")
		(net 527)
	)
	(segment
		(start 204.308872 112.312706)
		(end 204.340579 112.403319)
		(width 0.14)
		(layer "F.Cu")
		(net 527)
	)
	(segment
		(start 203.300083 110.787921)
		(end 203.317358 110.815414)
		(width 0.14)
		(layer "F.Cu")
		(net 527)
	)
	(segment
		(start 203.340317 110.838373)
		(end 203.36781 110.855648)
		(width 0.14)
		(layer "F.Cu")
		(net 527)
	)
	(segment
		(start 203.317358 110.815414)
		(end 203.340317 110.838373)
		(width 0.14)
		(layer "F.Cu")
		(net 527)
	)
	(segment
		(start 205.255519 110.963538)
		(end 205.323402 111.031421)
		(width 0.14)
		(layer "F.Cu")
		(net 527)
	)
	(segment
		(start 203.289359 110.757273)
		(end 203.300083 110.787921)
		(width 0.14)
		(layer "F.Cu")
		(net 527)
	)
	(segment
		(start 204.351328 110.151299)
		(end 204.340579 110.246696)
		(width 0.14)
		(layer "F.Cu")
		(net 527)
	)
	(segment
		(start 203.398458 110.866372)
		(end 203.430724 110.870008)
		(width 0.14)
		(layer "F.Cu")
		(net 527)
	)
	(segment
		(start 203.317358 111.834601)
		(end 203.300083 111.862094)
		(width 0.14)
		(layer "F.Cu")
		(net 527)
	)
	(segment
		(start 202.591328 106.569306)
		(end 202.591328 107.905008)
		(width 0.14)
		(layer "F.Cu")
		(net 527)
	)
	(segment
		(start 203.922619 112.070008)
		(end 204.018016 112.080756)
		(width 0.14)
		(layer "F.Cu")
		(net 527)
	)
	(segment
		(start 203.340317 112.038373)
		(end 203.36781 112.055648)
		(width 0.14)
		(layer "F.Cu")
		(net 527)
	)
	(segment
		(start 205.406184 111.203319)
		(end 205.416932 111.298716)
		(width 0.14)
		(layer "F.Cu")
		(net 527)
	)
	(segment
		(start 203.300083 110.662094)
		(end 203.289359 110.692742)
		(width 0.14)
		(layer "F.Cu")
		(net 527)
	)
	(segment
		(start 203.289359 111.892742)
		(end 203.285724 111.925008)
		(width 0.14)
		(layer "F.Cu")
		(net 527)
	)
	(segment
		(start 203.317358 112.015414)
		(end 203.340317 112.038373)
		(width 0.14)
		(layer "F.Cu")
		(net 527)
	)
	(segment
		(start 205.374477 111.112706)
		(end 205.406184 111.203319)
		(width 0.14)
		(layer "F.Cu")
		(net 527)
	)
	(segment
		(start 204.988224 110.870008)
		(end 205.083621 110.880756)
		(width 0.14)
		(layer "F.Cu")
		(net 527)
	)
	(segment
		(start 202.591328 107.905008)
		(end 204.351328 109.665008)
		(width 0.14)
		(layer "F.Cu")
		(net 527)
	)
	(segment
		(start 203.430724 111.780008)
		(end 203.398458 111.783643)
		(width 0.14)
		(layer "F.Cu")
		(net 527)
	)
	(segment
		(start 204.340579 112.403319)
		(end 204.351328 112.498716)
		(width 0.14)
		(layer "F.Cu")
		(net 527)
	)
	(segment
		(start 203.430724 110.870008)
		(end 204.988224 110.870008)
		(width 0.14)
		(layer "F.Cu")
		(net 527)
	)
	(segment
		(start 205.083621 110.880756)
		(end 205.174234 110.912463)
		(width 0.14)
		(layer "F.Cu")
		(net 527)
	)
	(segment
		(start 201.686328 106.474306)
		(end 201.686328 107.374306)
		(width 0.15)
		(layer "F.Cu")
		(net 529)
	)
	(segment
		(start 199.186328 106.474306)
		(end 199.186328 107.374306)
		(width 0.15)
		(layer "F.Cu")
		(net 529)
	)
	(via
		(at 201.686328 107.374306)
		(size 0.5)
		(drill 0.2)
		(layers "F.Cu" "B.Cu")
		(net 529)
	)
	(via
		(at 199.186328 107.374306)
		(size 0.5)
		(drill 0.2)
		(layers "F.Cu" "B.Cu")
		(net 529)
	)
	(segment
		(start 200.486328 107.418)
		(end 200.486328 107.889306)
		(width 0.15)
		(layer "B.Cu")
		(net 529)
	)
	(segment
		(start 200.071328 108.304306)
		(end 200.086328 108.289306)
		(width 0.15)
		(layer "B.Cu")
		(net 529)
	)
	(segment
		(start 201.686328 107.374306)
		(end 201.786328 107.374306)
		(width 0.15)
		(layer "B.Cu")
		(net 529)
	)
	(segment
		(start 200.086328 108.289306)
		(end 201.086328 108.289306)
		(width 0.15)
		(layer "B.Cu")
		(net 529)
	)
	(segment
		(start 202.086328 107.674306)
		(end 202.086328 108.289306)
		(width 0.15)
		(layer "B.Cu")
		(net 529)
	)
	(segment
		(start 201.786328 107.374306)
		(end 202.086328 107.674306)
		(width 0.15)
		(layer "B.Cu")
		(net 529)
	)
	(segment
		(start 199.086328 108.304306)
		(end 200.071328 108.304306)
		(width 0.15)
		(layer "B.Cu")
		(net 529)
	)
	(segment
		(start 199.086328 107.474306)
		(end 199.186328 107.374306)
		(width 0.15)
		(layer "B.Cu")
		(net 529)
	)
	(segment
		(start 200.486328 107.889306)
		(end 200.086328 108.289306)
		(width 0.15)
		(layer "B.Cu")
		(net 529)
	)
	(segment
		(start 201.086328 108.289306)
		(end 202.086328 108.289306)
		(width 0.15)
		(layer "B.Cu")
		(net 529)
	)
	(segment
		(start 199.086328 108.304306)
		(end 199.086328 107.474306)
		(width 0.15)
		(layer "B.Cu")
		(net 529)
	)
	(segment
		(start 192.486328 101.859306)
		(end 193.586328 101.859306)
		(width 0.2)
		(layer "F.Cu")
		(net 530)
	)
	(segment
		(start 195.463477 103.797157)
		(end 193.586328 101.920008)
		(width 0.2)
		(layer "F.Cu")
		(net 530)
	)
	(segment
		(start 197.009179 103.797157)
		(end 195.463477 103.797157)
		(width 0.2)
		(layer "F.Cu")
		(net 530)
	)
	(segment
		(start 189.286328 101.874306)
		(end 191.371328 101.874306)
		(width 0.2)
		(layer "F.Cu")
		(net 530)
	)
	(segment
		(start 191.386328 101.859306)
		(end 192.486328 101.859306)
		(width 0.2)
		(layer "F.Cu")
		(net 530)
	)
	(segment
		(start 191.371328 101.874306)
		(end 191.386328 101.859306)
		(width 0.2)
		(layer "F.Cu")
		(net 530)
	)
	(segment
		(start 193.586328 101.920008)
		(end 193.586328 101.859306)
		(width 0.2)
		(layer "F.Cu")
		(net 530)
	)
	(segment
		(start 203.186328 106.474306)
		(end 203.186328 107.374306)
		(width 0.15)
		(layer "F.Cu")
		(net 531)
	)
	(segment
		(start 197.686328 106.474306)
		(end 197.686328 107.374306)
		(width 0.15)
		(layer "F.Cu")
		(net 531)
	)
	(via
		(at 197.686328 107.374306)
		(size 0.5)
		(drill 0.2)
		(layers "F.Cu" "B.Cu")
		(net 531)
	)
	(via
		(at 203.186328 107.374306)
		(size 0.5)
		(drill 0.2)
		(layers "F.Cu" "B.Cu")
		(net 531)
	)
	(segment
		(start 197.686328 108.289306)
		(end 197.686328 107.374306)
		(width 0.15)
		(layer "B.Cu")
		(net 531)
	)
	(segment
		(start 198.032775 106.674306)
		(end 202.786328 106.674306)
		(width 0.15)
		(layer "B.Cu")
		(net 531)
	)
	(segment
		(start 202.786328 106.674306)
		(end 203.186328 107.074306)
		(width 0.15)
		(layer "B.Cu")
		(net 531)
	)
	(segment
		(start 197.671328 108.274306)
		(end 197.686328 108.289306)
		(width 0.15)
		(layer "B.Cu")
		(net 531)
	)
	(segment
		(start 196.486328 108.274306)
		(end 197.671328 108.274306)
		(width 0.15)
		(layer "B.Cu")
		(net 531)
	)
	(segment
		(start 203.186328 107.074306)
		(end 203.186328 107.374306)
		(width 0.15)
		(layer "B.Cu")
		(net 531)
	)
	(segment
		(start 197.686328 107.020753)
		(end 198.032775 106.674306)
		(width 0.15)
		(layer "B.Cu")
		(net 531)
	)
	(segment
		(start 203.186328 108.289306)
		(end 204.186328 108.289306)
		(width 0.2)
		(layer "B.Cu")
		(net 531)
	)
	(segment
		(start 203.186328 108.289306)
		(end 203.186328 107.374306)
		(width 0.15)
		(layer "B.Cu")
		(net 531)
	)
	(segment
		(start 197.686328 107.374306)
		(end 197.686328 107.020753)
		(width 0.15)
		(layer "B.Cu")
		(net 531)
	)
	(segment
		(start 197.009179 100.797157)
		(end 196.009179 100.797157)
		(width 0.1)
		(layer "F.Cu")
		(net 541)
	)
	(segment
		(start 177.536329 99.497156)
		(end 178.036329 99.997156)
		(width 0.15)
		(layer "F.Cu")
		(net 541)
	)
	(segment
		(start 196.009179 100.797157)
		(end 195.986328 100.774306)
		(width 0.1)
		(layer "F.Cu")
		(net 541)
	)
	(via
		(at 195.986328 100.774306)
		(size 0.5)
		(drill 0.2)
		(layers "F.Cu" "B.Cu")
		(net 541)
	)
	(via blind
		(at 178.036329 99.997156)
		(size 0.5)
		(drill 0.2)
		(layers "F.Cu" "In2.Cu")
		(net 541)
	)
	(segment
		(start 178.059179 99.974306)
		(end 178.036329 99.997156)
		(width 0.1)
		(layer "In2.Cu")
		(net 541)
	)
	(segment
		(start 195.986328 100.774306)
		(end 187.113477 100.774306)
		(width 0.1)
		(layer "In2.Cu")
		(net 541)
	)
	(segment
		(start 186.313477 99.974306)
		(end 178.059179 99.974306)
		(width 0.1)
		(layer "In2.Cu")
		(net 541)
	)
	(segment
		(start 187.113477 100.774306)
		(end 186.313477 99.974306)
		(width 0.1)
		(layer "In2.Cu")
		(net 541)
	)
	(segment
		(start 124.767157 54.167167)
		(end 124.69999 54.1)
		(width 0.15)
		(layer "F.Cu")
		(net 550)
	)
	(segment
		(start 124.767157 55.017672)
		(end 124.767157 54.167167)
		(width 0.15)
		(layer "F.Cu")
		(net 550)
	)
	(via
		(at 126.925 54.1)
		(size 0.5)
		(drill 0.2)
		(layers "F.Cu" "B.Cu")
		(net 550)
	)
	(via
		(at 124.69999 54.1)
		(size 0.5)
		(drill 0.2)
		(layers "F.Cu" "B.Cu")
		(net 550)
	)
	(segment
		(start 126.3 54.725)
		(end 125.32499 54.725)
		(width 0.15)
		(layer "B.Cu")
		(net 550)
	)
	(segment
		(start 126.925 54.1)
		(end 126.3 54.725)
		(width 0.15)
		(layer "B.Cu")
		(net 550)
	)
	(segment
		(start 124.69999 54.1)
		(end 125.32499 54.725)
		(width 0.15)
		(layer "B.Cu")
		(net 550)
	)
	(segment
		(start 125.267157 58.575)
		(end 125.242157 58.6)
		(width 0.15)
		(layer "F.Cu")
		(net 551)
	)
	(segment
		(start 125.267157 57.817672)
		(end 125.267157 58.570135)
		(width 0.25)
		(layer "F.Cu")
		(net 551)
	)
	(segment
		(start 125.267157 58.570135)
		(end 125.267157 58.575)
		(width 0.15)
		(layer "F.Cu")
		(net 551)
	)
	(segment
		(start 130.293 64.5)
		(end 130.3 64.507)
		(width 0.2)
		(layer "F.Cu")
		(net 551)
	)
	(segment
		(start 128.4 64.5)
		(end 130.293 64.5)
		(width 0.2)
		(layer "F.Cu")
		(net 551)
	)
	(via
		(at 128.4 64.5)
		(size 0.5)
		(drill 0.2)
		(layers "F.Cu" "B.Cu")
		(net 551)
	)
	(via
		(at 125.242157 58.6)
		(size 0.5)
		(drill 0.2)
		(layers "F.Cu" "B.Cu")
		(net 551)
	)
	(segment
		(start 127.425 59.316515)
		(end 127.425 64.225)
		(width 0.2)
		(layer "B.Cu")
		(net 551)
	)
	(segment
		(start 125.242157 58.6)
		(end 125.492156 58.849999)
		(width 0.2)
		(layer "B.Cu")
		(net 551)
	)
	(segment
		(start 127.425 64.225)
		(end 127.7 64.5)
		(width 0.2)
		(layer "B.Cu")
		(net 551)
	)
	(segment
		(start 126.958484 58.849999)
		(end 127.425 59.316515)
		(width 0.2)
		(layer "B.Cu")
		(net 551)
	)
	(segment
		(start 125.492156 58.849999)
		(end 126.958484 58.849999)
		(width 0.2)
		(layer "B.Cu")
		(net 551)
	)
	(segment
		(start 127.7 64.5)
		(end 128.4 64.5)
		(width 0.2)
		(layer "B.Cu")
		(net 551)
	)
	(segment
		(start 115.111478 87.661328)
		(end 115.882806 86.89)
		(width 0.125)
		(layer "F.Cu")
		(net 552)
	)
	(segment
		(start 115.111478 87.954992)
		(end 115.111478 87.661328)
		(width 0.125)
		(layer "F.Cu")
		(net 552)
	)
	(segment
		(start 115.882806 86.89)
		(end 115.882806 86.825)
		(width 0.125)
		(layer "F.Cu")
		(net 552)
	)
	(segment
		(start 139.6975 89.6)
		(end 138.5325 89.6)
		(width 0.2)
		(layer "F.Cu")
		(net 553)
	)
	(segment
		(start 139.6975 92.1)
		(end 138.5325 92.1)
		(width 0.2)
		(layer "F.Cu")
		(net 555)
	)
	(segment
		(start 139.6975 87.1)
		(end 138.5325 87.1)
		(width 0.2)
		(layer "F.Cu")
		(net 556)
	)
	(segment
		(start 139.6975 84.7)
		(end 138.5325 84.7)
		(width 0.2)
		(layer "F.Cu")
		(net 557)
	)
	(segment
		(start 115.688672 99.429992)
		(end 115.688672 99.136328)
		(width 0.125)
		(layer "F.Cu")
		(net 574)
	)
	(segment
		(start 115.688672 99.136328)
		(end 116.46 98.365)
		(width 0.125)
		(layer "F.Cu")
		(net 574)
	)
	(segment
		(start 116.46 98.365)
		(end 116.46 98.3)
		(width 0.125)
		(layer "F.Cu")
		(net 574)
	)
	(segment
		(start 111.455 102.45)
		(end 110.775 102.45)
		(width 0.2)
		(layer "F.Cu")
		(net 576)
	)
	(segment
		(start 112.21 97.25)
		(end 112.775 97.25)
		(width 0.2)
		(layer "F.Cu")
		(net 576)
	)
	(via
		(at 112.775 97.25)
		(size 0.5)
		(drill 0.2)
		(layers "F.Cu" "B.Cu")
		(net 576)
	)
	(via
		(at 110.775 102.45)
		(size 0.5)
		(drill 0.2)
		(layers "F.Cu" "B.Cu")
		(net 576)
	)
	(segment
		(start 110.775 102.45)
		(end 110.765 102.44)
		(width 0.2)
		(layer "B.Cu")
		(net 576)
	)
	(segment
		(start 110.765 97.625)
		(end 111.14 97.25)
		(width 0.2)
		(layer "B.Cu")
		(net 576)
	)
	(segment
		(start 110.765 102.44)
		(end 110.765 97.625)
		(width 0.2)
		(layer "B.Cu")
		(net 576)
	)
	(segment
		(start 111.14 97.25)
		(end 112.775 97.25)
		(width 0.2)
		(layer "B.Cu")
		(net 576)
	)
	(segment
		(start 116.638672 101.129992)
		(end 117.369992 101.129992)
		(width 0.2)
		(layer "F.Cu")
		(net 577)
	)
	(segment
		(start 117.369992 101.129992)
		(end 117.79 101.55)
		(width 0.2)
		(layer "F.Cu")
		(net 577)
	)
	(segment
		(start 112.745008 101.129992)
		(end 112.425 101.45)
		(width 0.2)
		(layer "F.Cu")
		(net 578)
	)
	(segment
		(start 113.738672 101.129992)
		(end 112.745008 101.129992)
		(width 0.2)
		(layer "F.Cu")
		(net 578)
	)
	(segment
		(start 112.425 102.45)
		(end 112.425 101.45)
		(width 0.2)
		(layer "F.Cu")
		(net 578)
	)
	(segment
		(start 127.363672 87.711328)
		(end 127.4 87.675)
		(width 0.2)
		(layer "F.Cu")
		(net 580)
	)
	(segment
		(start 128.435 87.29)
		(end 128.435 86.875)
		(width 0.2)
		(layer "F.Cu")
		(net 580)
	)
	(segment
		(start 127.363672 87.954992)
		(end 127.363672 87.711328)
		(width 0.2)
		(layer "F.Cu")
		(net 580)
	)
	(segment
		(start 127.4 87.675)
		(end 128.05 87.675)
		(width 0.2)
		(layer "F.Cu")
		(net 580)
	)
	(segment
		(start 127.363672 87.954992)
		(end 127.363672 87.661328)
		(width 0.125)
		(layer "F.Cu")
		(net 580)
	)
	(segment
		(start 128.05 87.675)
		(end 128.435 87.29)
		(width 0.2)
		(layer "F.Cu")
		(net 580)
	)
	(segment
		(start 128.1675 98.365)
		(end 128.1675 98.3)
		(width 0.125)
		(layer "F.Cu")
		(net 581)
	)
	(segment
		(start 127.396172 99.429992)
		(end 127.396172 99.136328)
		(width 0.125)
		(layer "F.Cu")
		(net 581)
	)
	(segment
		(start 127.396172 99.136328)
		(end 128.1675 98.365)
		(width 0.125)
		(layer "F.Cu")
		(net 581)
	)
	(segment
		(start 111.632806 85.775)
		(end 112.197806 85.775)
		(width 0.2)
		(layer "F.Cu")
		(net 583)
	)
	(segment
		(start 110.877806 90.975)
		(end 110.197806 90.975)
		(width 0.2)
		(layer "F.Cu")
		(net 583)
	)
	(via
		(at 112.197806 85.775)
		(size 0.5)
		(drill 0.2)
		(layers "F.Cu" "B.Cu")
		(net 583)
	)
	(via
		(at 110.197806 90.975)
		(size 0.5)
		(drill 0.2)
		(layers "F.Cu" "B.Cu")
		(net 583)
	)
	(segment
		(start 110.562806 85.775)
		(end 112.197806 85.775)
		(width 0.2)
		(layer "B.Cu")
		(net 583)
	)
	(segment
		(start 110.187806 90.965)
		(end 110.187806 86.15)
		(width 0.2)
		(layer "B.Cu")
		(net 583)
	)
	(segment
		(start 110.197806 90.975)
		(end 110.187806 90.965)
		(width 0.2)
		(layer "B.Cu")
		(net 583)
	)
	(segment
		(start 110.187806 86.15)
		(end 110.562806 85.775)
		(width 0.2)
		(layer "B.Cu")
		(net 583)
	)
	(segment
		(start 188.185 116.37)
		(end 188.25 116.37)
		(width 0.125)
		(layer "F.Cu")
		(net 585)
	)
	(segment
		(start 187.413672 115.598672)
		(end 188.185 116.37)
		(width 0.125)
		(layer "F.Cu")
		(net 585)
	)
	(segment
		(start 187.120008 115.598672)
		(end 187.413672 115.598672)
		(width 0.125)
		(layer "F.Cu")
		(net 585)
	)
	(segment
		(start 123.165 90.975)
		(end 122.485 90.975)
		(width 0.2)
		(layer "F.Cu")
		(net 587)
	)
	(segment
		(start 123.92 85.775)
		(end 124.24 85.775)
		(width 0.2)
		(layer "F.Cu")
		(net 587)
	)
	(via
		(at 122.485 90.975)
		(size 0.5)
		(drill 0.2)
		(layers "F.Cu" "B.Cu")
		(net 587)
	)
	(via
		(at 124.24 85.775)
		(size 0.5)
		(drill 0.2)
		(layers "F.Cu" "B.Cu")
		(net 587)
	)
	(segment
		(start 122.475 86.15)
		(end 122.475 90.965)
		(width 0.2)
		(layer "B.Cu")
		(net 587)
	)
	(segment
		(start 124.24 85.775)
		(end 122.85 85.775)
		(width 0.2)
		(layer "B.Cu")
		(net 587)
	)
	(segment
		(start 122.475 90.965)
		(end 122.485 90.975)
		(width 0.2)
		(layer "B.Cu")
		(net 587)
	)
	(segment
		(start 122.85 85.775)
		(end 122.475 86.15)
		(width 0.2)
		(layer "B.Cu")
		(net 587)
	)
	(segment
		(start 123.9175 97.25)
		(end 124.4825 97.25)
		(width 0.2)
		(layer "F.Cu")
		(net 588)
	)
	(segment
		(start 123.1625 102.45)
		(end 122.4825 102.45)
		(width 0.2)
		(layer "F.Cu")
		(net 588)
	)
	(via
		(at 122.4825 102.45)
		(size 0.5)
		(drill 0.2)
		(layers "F.Cu" "B.Cu")
		(net 588)
	)
	(via
		(at 124.4825 97.25)
		(size 0.5)
		(drill 0.2)
		(layers "F.Cu" "B.Cu")
		(net 588)
	)
	(segment
		(start 122.4725 102.44)
		(end 122.4725 97.625)
		(width 0.2)
		(layer "B.Cu")
		(net 588)
	)
	(segment
		(start 122.4825 102.45)
		(end 122.4725 102.44)
		(width 0.2)
		(layer "B.Cu")
		(net 588)
	)
	(segment
		(start 122.4725 97.625)
		(end 122.8475 97.25)
		(width 0.2)
		(layer "B.Cu")
		(net 588)
	)
	(segment
		(start 122.8475 97.25)
		(end 124.4825 97.25)
		(width 0.2)
		(layer "B.Cu")
		(net 588)
	)
	(segment
		(start 184.1 111.365)
		(end 184.1 110.685)
		(width 0.2)
		(layer "F.Cu")
		(net 589)
	)
	(segment
		(start 189.3 112.12)
		(end 189.3 112.685)
		(width 0.2)
		(layer "F.Cu")
		(net 589)
	)
	(via
		(at 184.1 110.685)
		(size 0.5)
		(drill 0.2)
		(layers "F.Cu" "B.Cu")
		(net 589)
	)
	(via
		(at 189.3 112.685)
		(size 0.5)
		(drill 0.2)
		(layers "F.Cu" "B.Cu")
		(net 589)
	)
	(segment
		(start 188.925 110.675)
		(end 189.3 111.05)
		(width 0.2)
		(layer "B.Cu")
		(net 589)
	)
	(segment
		(start 184.11 110.675)
		(end 188.925 110.675)
		(width 0.2)
		(layer "B.Cu")
		(net 589)
	)
	(segment
		(start 184.1 110.685)
		(end 184.11 110.675)
		(width 0.2)
		(layer "B.Cu")
		(net 589)
	)
	(segment
		(start 189.3 111.05)
		(end 189.3 112.685)
		(width 0.2)
		(layer "B.Cu")
		(net 589)
	)
	(segment
		(start 128.313672 89.654992)
		(end 129.044992 89.654992)
		(width 0.2)
		(layer "F.Cu")
		(net 590)
	)
	(segment
		(start 129.044992 89.654992)
		(end 129.465 90.075)
		(width 0.2)
		(layer "F.Cu")
		(net 590)
	)
	(segment
		(start 124.7 88.125)
		(end 124.829992 88.154992)
		(width 0.2)
		(layer "F.Cu")
		(net 591)
	)
	(segment
		(start 124.285 88.125)
		(end 124.135 87.975)
		(width 0.2)
		(layer "F.Cu")
		(net 591)
	)
	(segment
		(start 130.435 88.075)
		(end 131.09 88.075)
		(width 0.2)
		(layer "F.Cu")
		(net 591)
	)
	(segment
		(start 124.829992 88.154992)
		(end 125.413672 88.154992)
		(width 0.2)
		(layer "F.Cu")
		(net 591)
	)
	(segment
		(start 124.7 88.125)
		(end 124.285 88.125)
		(width 0.2)
		(layer "F.Cu")
		(net 591)
	)
	(via
		(at 131.09 88.075)
		(size 0.5)
		(drill 0.2)
		(layers "F.Cu" "B.Cu")
		(net 591)
	)
	(via
		(at 124.7 88.125)
		(size 0.5)
		(drill 0.2)
		(layers "F.Cu" "B.Cu")
		(net 591)
	)
	(segment
		(start 131.09 88.075)
		(end 124.75 88.075)
		(width 0.2)
		(layer "B.Cu")
		(net 591)
	)
	(segment
		(start 124.75 88.075)
		(end 124.7 88.125)
		(width 0.2)
		(layer "B.Cu")
		(net 591)
	)
	(segment
		(start 129.077492 101.129992)
		(end 129.4975 101.55)
		(width 0.2)
		(layer "F.Cu")
		(net 592)
	)
	(segment
		(start 128.346172 101.129992)
		(end 129.077492 101.129992)
		(width 0.2)
		(layer "F.Cu")
		(net 592)
	)
	(segment
		(start 130.4675 99.55)
		(end 131.0825 99.55)
		(width 0.2)
		(layer "F.Cu")
		(net 593)
	)
	(segment
		(start 124.752508 99.629992)
		(end 124.312492 99.629992)
		(width 0.2)
		(layer "F.Cu")
		(net 593)
	)
	(segment
		(start 125.446172 99.629992)
		(end 124.752508 99.629992)
		(width 0.2)
		(layer "F.Cu")
		(net 593)
	)
	(segment
		(start 124.312492 99.629992)
		(end 124.1325 99.45)
		(width 0.2)
		(layer "F.Cu")
		(net 593)
	)
	(via
		(at 131.0825 99.55)
		(size 0.5)
		(drill 0.2)
		(layers "F.Cu" "B.Cu")
		(net 593)
	)
	(via
		(at 124.752508 99.629992)
		(size 0.5)
		(drill 0.2)
		(layers "F.Cu" "B.Cu")
		(net 593)
	)
	(segment
		(start 124.752508 99.629992)
		(end 131.002508 99.629992)
		(width 0.2)
		(layer "B.Cu")
		(net 593)
	)
	(segment
		(start 131.002508 99.629992)
		(end 131.0825 99.55)
		(width 0.2)
		(layer "B.Cu")
		(net 593)
	)
	(segment
		(start 124.760735 57.814265)
		(end 124.760735 58.339265)
		(width 0.15)
		(layer "F.Cu")
		(net 594)
	)
	(segment
		(start 117.4 90.8)
		(end 119.5 90.8)
		(width 0.15)
		(layer "F.Cu")
		(net 594)
	)
	(segment
		(start 119.5 90.8)
		(end 119.7 90.6)
		(width 0.15)
		(layer "F.Cu")
		(net 594)
	)
	(segment
		(start 116.792798 89.654992)
		(end 117.212806 90.075)
		(width 0.2)
		(layer "F.Cu")
		(net 594)
	)
	(segment
		(start 119.7 90.6)
		(end 119.7 90)
		(width 0.15)
		(layer "F.Cu")
		(net 594)
	)
	(segment
		(start 117.2 90.087806)
		(end 117.2 90.6)
		(width 0.15)
		(layer "F.Cu")
		(net 594)
	)
	(segment
		(start 124.767157 58.267672)
		(end 124.767157 57.817672)
		(width 0.15)
		(layer "F.Cu")
		(net 594)
	)
	(segment
		(start 117.2 90.6)
		(end 117.4 90.8)
		(width 0.15)
		(layer "F.Cu")
		(net 594)
	)
	(segment
		(start 116.061478 89.654992)
		(end 116.792798 89.654992)
		(width 0.2)
		(layer "F.Cu")
		(net 594)
	)
	(segment
		(start 124.760735 58.339265)
		(end 124.4 58.7)
		(width 0.15)
		(layer "F.Cu")
		(net 594)
	)
	(segment
		(start 117.212806 90.075)
		(end 117.2 90.087806)
		(width 0.15)
		(layer "F.Cu")
		(net 594)
	)
	(via
		(at 124.4 58.7)
		(size 0.5)
		(drill 0.2)
		(layers "F.Cu" "B.Cu")
		(net 594)
	)
	(via
		(at 119.7 90)
		(size 0.5)
		(drill 0.2)
		(layers "F.Cu" "B.Cu")
		(net 594)
	)
	(segment
		(start 124.4 58.7)
		(end 124.4 59.2)
		(width 0.15)
		(layer "B.Cu")
		(net 594)
	)
	(segment
		(start 124.4 59.2)
		(end 119.7 63.9)
		(width 0.15)
		(layer "B.Cu")
		(net 594)
	)
	(segment
		(start 119.7 63.9)
		(end 119.7 90)
		(width 0.15)
		(layer "B.Cu")
		(net 594)
	)
	(segment
		(start 118.182806 88.075)
		(end 118.182806 87.052194)
		(width 0.15)
		(layer "F.Cu")
		(net 595)
	)
	(segment
		(start 112.467814 88.154992)
		(end 112.027798 88.154992)
		(width 0.2)
		(layer "F.Cu")
		(net 595)
	)
	(segment
		(start 113.161478 88.154992)
		(end 112.467814 88.154992)
		(width 0.2)
		(layer "F.Cu")
		(net 595)
	)
	(segment
		(start 118.182806 88.075)
		(end 118.797806 88.075)
		(width 0.2)
		(layer "F.Cu")
		(net 595)
	)
	(segment
		(start 118.182806 87.052194)
		(end 118.185 87.05)
		(width 0.15)
		(layer "F.Cu")
		(net 595)
	)
	(segment
		(start 112.027798 88.154992)
		(end 111.847806 87.975)
		(width 0.2)
		(layer "F.Cu")
		(net 595)
	)
	(via
		(at 118.797806 88.075)
		(size 0.5)
		(drill 0.2)
		(layers "F.Cu" "B.Cu")
		(net 595)
	)
	(via
		(at 112.467814 88.154992)
		(size 0.5)
		(drill 0.2)
		(layers "F.Cu" "B.Cu")
		(net 595)
	)
	(segment
		(start 112.467814 88.154992)
		(end 118.717814 88.154992)
		(width 0.2)
		(layer "B.Cu")
		(net 595)
	)
	(segment
		(start 118.717814 88.154992)
		(end 118.797806 88.075)
		(width 0.2)
		(layer "B.Cu")
		(net 595)
	)
	(segment
		(start 185.420008 116.548672)
		(end 185.420008 117.279992)
		(width 0.2)
		(layer "F.Cu")
		(net 596)
	)
	(segment
		(start 185.420008 117.279992)
		(end 185 117.7)
		(width 0.2)
		(layer "F.Cu")
		(net 596)
	)
	(segment
		(start 186.920008 112.955008)
		(end 186.920008 112.514992)
		(width 0.2)
		(layer "F.Cu")
		(net 597)
	)
	(segment
		(start 186.920008 112.514992)
		(end 187.1 112.335)
		(width 0.2)
		(layer "F.Cu")
		(net 597)
	)
	(segment
		(start 186.920008 113.648672)
		(end 186.920008 112.955008)
		(width 0.2)
		(layer "F.Cu")
		(net 597)
	)
	(segment
		(start 187 118.67)
		(end 187 119.285)
		(width 0.2)
		(layer "F.Cu")
		(net 597)
	)
	(via
		(at 186.920008 112.955008)
		(size 0.5)
		(drill 0.2)
		(layers "F.Cu" "B.Cu")
		(net 597)
	)
	(via
		(at 187 119.285)
		(size 0.5)
		(drill 0.2)
		(layers "F.Cu" "B.Cu")
		(net 597)
	)
	(segment
		(start 186.920008 119.205008)
		(end 187 119.285)
		(width 0.2)
		(layer "B.Cu")
		(net 597)
	)
	(segment
		(start 186.920008 112.955008)
		(end 186.920008 119.205008)
		(width 0.2)
		(layer "B.Cu")
		(net 597)
	)
	(segment
		(start 124.455008 89.654992)
		(end 125.413672 89.654992)
		(width 0.2)
		(layer "F.Cu")
		(net 598)
	)
	(segment
		(start 124.135 90.975)
		(end 124.135 89.975)
		(width 0.2)
		(layer "F.Cu")
		(net 598)
	)
	(segment
		(start 124.455008 89.654992)
		(end 124.135 89.975)
		(width 0.2)
		(layer "F.Cu")
		(net 598)
	)
	(segment
		(start 124.1325 102.45)
		(end 124.1325 101.45)
		(width 0.2)
		(layer "F.Cu")
		(net 599)
	)
	(segment
		(start 125.446172 101.129992)
		(end 124.452508 101.129992)
		(width 0.2)
		(layer "F.Cu")
		(net 599)
	)
	(segment
		(start 124.452508 101.129992)
		(end 124.1325 101.45)
		(width 0.2)
		(layer "F.Cu")
		(net 599)
	)
	(segment
		(start 113.161478 89.654992)
		(end 112.167814 89.654992)
		(width 0.2)
		(layer "F.Cu")
		(net 600)
	)
	(segment
		(start 112.167814 89.654992)
		(end 111.847806 89.975)
		(width 0.2)
		(layer "F.Cu")
		(net 600)
	)
	(segment
		(start 111.847806 90.975)
		(end 111.847806 89.975)
		(width 0.2)
		(layer "F.Cu")
		(net 600)
	)
	(segment
		(start 185.420008 112.655008)
		(end 185.1 112.335)
		(width 0.2)
		(layer "F.Cu")
		(net 601)
	)
	(segment
		(start 185.420008 113.648672)
		(end 185.420008 112.655008)
		(width 0.2)
		(layer "F.Cu")
		(net 601)
	)
	(segment
		(start 184.1 112.335)
		(end 185.1 112.335)
		(width 0.2)
		(layer "F.Cu")
		(net 601)
	)
	(segment
		(start 203.863477 103.297157)
		(end 203.323477 103.297157)
		(width 0.15)
		(layer "F.Cu")
		(net 602)
	)
	(segment
		(start 203.863477 100.797157)
		(end 206.524179 100.797157)
		(width 0.15)
		(layer "F.Cu")
		(net 602)
	)
	(segment
		(start 195.440627 101.274307)
		(end 194.040626 99.874306)
		(width 0.2)
		(layer "F.Cu")
		(net 602)
	)
	(segment
		(start 143.0325 90.1)
		(end 143.6825 90.1)
		(width 0.2)
		(layer "F.Cu")
		(net 602)
	)
	(segment
		(start 204.955626 105.689306)
		(end 206.586328 105.689306)
		(width 0.2)
		(layer "F.Cu")
		(net 602)
	)
	(segment
		(start 194.240626 98.874306)
		(end 194.286328 98.920008)
		(width 0.2)
		(layer "F.Cu")
		(net 602)
	)
	(segment
		(start 204.586328 105.320008)
		(end 204.955626 105.689306)
		(width 0.2)
		(layer "F.Cu")
		(net 602)
	)
	(segment
		(start 193.571328 98.874306)
		(end 194.240626 98.874306)
		(width 0.2)
		(layer "F.Cu")
		(net 602)
	)
	(segment
		(start 190.472709 99.320008)
		(end 190.480275 99.312442)
		(width 0.2)
		(layer "F.Cu")
		(net 602)
	)
	(segment
		(start 207.24703 100.859306)
		(end 207.286328 100.820008)
		(width 0.2)
		(layer "F.Cu")
		(net 602)
	)
	(segment
		(start 203.329179 100.797157)
		(end 203.863477 100.797157)
		(width 0.15)
		(layer "F.Cu")
		(net 602)
	)
	(segment
		(start 203.886328 105.320008)
		(end 204.586328 105.320008)
		(width 0.2)
		(layer "F.Cu")
		(net 602)
	)
	(segment
		(start 206.524179 100.797157)
		(end 206.586328 100.859306)
		(width 0.15)
		(layer "F.Cu")
		(net 602)
	)
	(segment
		(start 189.940626 99.320008)
		(end 190.472709 99.320008)
		(width 0.2)
		(layer "F.Cu")
		(net 602)
	)
	(segment
		(start 202.686328 99.620008)
		(end 202.686328 98.720008)
		(width 0.15)
		(layer "F.Cu")
		(net 602)
	)
	(segment
		(start 189.286328 100.474306)
		(end 189.286328 99.974306)
		(width 0.2)
		(layer "F.Cu")
		(net 602)
	)
	(segment
		(start 203.323477 103.297157)
		(end 203.066328 103.040008)
		(width 0.15)
		(layer "F.Cu")
		(net 602)
	)
	(segment
		(start 200.686328 99.620008)
		(end 200.686328 98.720008)
		(width 0.15)
		(layer "F.Cu")
		(net 602)
	)
	(segment
		(start 206.586328 100.859306)
		(end 207.24703 100.859306)
		(width 0.2)
		(layer "F.Cu")
		(net 602)
	)
	(segment
		(start 196.986329 101.274307)
		(end 195.440627 101.274307)
		(width 0.2)
		(layer "F.Cu")
		(net 602)
	)
	(segment
		(start 189.286328 99.974306)
		(end 189.940626 99.320008)
		(width 0.2)
		(layer "F.Cu")
		(net 602)
	)
	(segment
		(start 143.6825 90.1)
		(end 144.7 90.1)
		(width 0.15)
		(layer "F.Cu")
		(net 602)
	)
	(segment
		(start 207.155626 105.689306)
		(end 207.186328 105.720008)
		(width 0.2)
		(layer "F.Cu")
		(net 602)
	)
	(segment
		(start 203.066328 101.060008)
		(end 203.329179 100.797157)
		(width 0.15)
		(layer "F.Cu")
		(net 602)
	)
	(segment
		(start 193.571328 98.874306)
		(end 193.571328 99.874306)
		(width 0.2)
		(layer "F.Cu")
		(net 602)
	)
	(segment
		(start 194.040626 99.874306)
		(end 193.571328 99.874306)
		(width 0.2)
		(layer "F.Cu")
		(net 602)
	)
	(segment
		(start 206.586328 105.689306)
		(end 207.155626 105.689306)
		(width 0.2)
		(layer "F.Cu")
		(net 602)
	)
	(segment
		(start 203.066328 103.040008)
		(end 203.066328 101.060008)
		(width 0.15)
		(layer "F.Cu")
		(net 602)
	)
	(via
		(at 207.186328 105.720008)
		(size 0.5)
		(drill 0.2)
		(layers "F.Cu" "B.Cu")
		(net 602)
	)
	(via
		(at 194.286328 98.920008)
		(size 0.5)
		(drill 0.2)
		(layers "F.Cu" "B.Cu")
		(net 602)
	)
	(via
		(at 202.886328 105.320008)
		(size 0.5)
		(drill 0.2)
		(layers "F.Cu" "B.Cu")
		(net 602)
	)
	(via
		(at 193.2 108.5)
		(size 0.5)
		(drill 0.2)
		(layers "F.Cu" "B.Cu")
		(free yes)
		(net 602)
	)
	(via
		(at 207.286328 100.820008)
		(size 0.5)
		(drill 0.2)
		(layers "F.Cu" "B.Cu")
		(net 602)
	)
	(via
		(at 200.686328 98.720008)
		(size 0.5)
		(drill 0.2)
		(layers "F.Cu" "B.Cu")
		(net 602)
	)
	(via
		(at 192.8 109)
		(size 0.5)
		(drill 0.2)
		(layers "F.Cu" "B.Cu")
		(free yes)
		(net 602)
	)
	(via
		(at 193.2 109.4)
		(size 0.5)
		(drill 0.2)
		(layers "F.Cu" "B.Cu")
		(free yes)
		(net 602)
	)
	(via
		(at 143.6825 90.1)
		(size 0.5)
		(drill 0.2)
		(layers "F.Cu" "B.Cu")
		(net 602)
	)
	(via
		(at 202.686328 98.720008)
		(size 0.5)
		(drill 0.2)
		(layers "F.Cu" "B.Cu")
		(net 602)
	)
	(via
		(at 192.4 108.5)
		(size 0.5)
		(drill 0.2)
		(layers "F.Cu" "B.Cu")
		(free yes)
		(net 602)
	)
	(via
		(at 190.480275 99.312442)
		(size 0.5)
		(drill 0.2)
		(layers "F.Cu" "B.Cu")
		(net 602)
	)
	(via
		(at 192.4 109.4)
		(size 0.5)
		(drill 0.2)
		(layers "F.Cu" "B.Cu")
		(free yes)
		(net 602)
	)
	(segment
		(start 201.586328 99.535008)
		(end 202.686328 99.535008)
		(width 0.2)
		(layer "B.Cu")
		(net 602)
	)
	(segment
		(start 202.567336 105.639)
		(end 202.886328 105.320008)
		(width 0.2)
		(layer "B.Cu")
		(net 602)
	)
	(segment
		(start 199.486328 99.535008)
		(end 200.486328 99.535008)
		(width 0.2)
		(layer "B.Cu")
		(net 602)
	)
	(segment
		(start 202.686328 98.720008)
		(end 202.686328 99.535008)
		(width 0.2)
		(layer "B.Cu")
		(net 602)
	)
	(segment
		(start 200.686328 99.335008)
		(end 200.486328 99.535008)
		(width 0.2)
		(layer "B.Cu")
		(net 602)
	)
	(segment
		(start 200.486328 105.639)
		(end 202.567336 105.639)
		(width 0.2)
		(layer "B.Cu")
		(net 602)
	)
	(segment
		(start 200.686328 98.720008)
		(end 200.686328 99.335008)
		(width 0.2)
		(layer "B.Cu")
		(net 602)
	)
	(segment
		(start 185.6 109.4)
		(end 185.2 109.8)
		(width 0.15)
		(layer "In5.Cu")
		(net 602)
	)
	(segment
		(start 142.5 90.5)
		(end 142.5 121.8)
		(width 0.15)
		(layer "In5.Cu")
		(net 602)
	)
	(segment
		(start 192.4 109.4)
		(end 185.6 109.4)
		(width 0.15)
		(layer "In5.Cu")
		(net 602)
	)
	(segment
		(start 142.5 121.8)
		(end 143 122.3)
		(width 0.15)
		(layer "In5.Cu")
		(net 602)
	)
	(segment
		(start 181.2 122.3)
		(end 185.2 118.3)
		(width 0.15)
		(layer "In5.Cu")
		(net 602)
	)
	(segment
		(start 142.9 90.1)
		(end 142.5 90.5)
		(width 0.15)
		(layer "In5.Cu")
		(net 602)
	)
	(segment
		(start 143.6825 90.1)
		(end 142.9 90.1)
		(width 0.15)
		(layer "In5.Cu")
		(net 602)
	)
	(segment
		(start 185.2 109.8)
		(end 185.2 118.3)
		(width 0.15)
		(layer "In5.Cu")
		(net 602)
	)
	(segment
		(start 143 122.3)
		(end 181.2 122.3)
		(width 0.15)
		(layer "In5.Cu")
		(net 602)
	)
	(segment
		(start 116.061478 87.838522)
		(end 116.061478 88.154992)
		(width 0.15)
		(layer "F.Cu")
		(net 605)
	)
	(segment
		(start 117.215 87.05)
		(end 116.85 87.05)
		(width 0.15)
		(layer "F.Cu")
		(net 605)
	)
	(segment
		(start 117.215 86.415)
		(end 117.2 86.4)
		(width 0.15)
		(layer "F.Cu")
		(net 605)
	)
	(segment
		(start 131.075 90.075)
		(end 131.1 90.05)
		(width 0.15)
		(layer "F.Cu")
		(net 605)
	)
	(segment
		(start 117.215 87.05)
		(end 117.215 86.415)
		(width 0.15)
		(layer "F.Cu")
		(net 605)
	)
	(segment
		(start 116.85 87.05)
		(end 116.061478 87.838522)
		(width 0.15)
		(layer "F.Cu")
		(net 605)
	)
	(segment
		(start 130.435 90.075)
		(end 131.075 90.075)
		(width 0.15)
		(layer "F.Cu")
		(net 605)
	)
	(via
		(at 117.2 86.4)
		(size 0.5)
		(drill 0.2)
		(layers "F.Cu" "B.Cu")
		(net 605)
	)
	(via
		(at 131.1 90.05)
		(size 0.5)
		(drill 0.2)
		(layers "F.Cu" "B.Cu")
		(net 605)
	)
	(segment
		(start 129.4 89.1)
		(end 122.7 89.1)
		(width 0.15)
		(layer "In5.Cu")
		(net 605)
	)
	(segment
		(start 122.7 89.1)
		(end 120 86.4)
		(width 0.15)
		(layer "In5.Cu")
		(net 605)
	)
	(segment
		(start 120 86.4)
		(end 117.2 86.4)
		(width 0.15)
		(layer "In5.Cu")
		(net 605)
	)
	(segment
		(start 130.35 90.05)
		(end 129.4 89.1)
		(width 0.15)
		(layer "In5.Cu")
		(net 605)
	)
	(segment
		(start 131.1 90.05)
		(end 130.35 90.05)
		(width 0.15)
		(layer "In5.Cu")
		(net 605)
	)
	(segment
		(start 112.604992 99.629992)
		(end 112.425 99.45)
		(width 0.2)
		(layer "F.Cu")
		(net 609)
	)
	(segment
		(start 113.045008 99.629992)
		(end 112.604992 99.629992)
		(width 0.2)
		(layer "F.Cu")
		(net 609)
	)
	(segment
		(start 113.738672 99.629992)
		(end 113.045008 99.629992)
		(width 0.2)
		(layer "F.Cu")
		(net 609)
	)
	(segment
		(start 118.76 99.55)
		(end 119.375 99.55)
		(width 0.2)
		(layer "F.Cu")
		(net 609)
	)
	(via
		(at 119.375 99.55)
		(size 0.5)
		(drill 0.2)
		(layers "F.Cu" "B.Cu")
		(net 609)
	)
	(via
		(at 113.045008 99.629992)
		(size 0.5)
		(drill 0.2)
		(layers "F.Cu" "B.Cu")
		(net 609)
	)
	(segment
		(start 113.045008 99.629992)
		(end 119.295008 99.629992)
		(width 0.2)
		(layer "B.Cu")
		(net 609)
	)
	(segment
		(start 119.295008 99.629992)
		(end 119.375 99.55)
		(width 0.2)
		(layer "B.Cu")
		(net 609)
	)
	(segment
		(start 117.210008 100.129992)
		(end 117.79 99.55)
		(width 0.2)
		(layer "F.Cu")
		(net 610)
	)
	(segment
		(start 116.638672 100.129992)
		(end 117.210008 100.129992)
		(width 0.2)
		(layer "F.Cu")
		(net 610)
	)
	(segment
		(start 128.917508 100.129992)
		(end 129.4975 99.55)
		(width 0.2)
		(layer "F.Cu")
		(net 611)
	)
	(segment
		(start 128.346172 100.129992)
		(end 128.917508 100.129992)
		(width 0.2)
		(layer "F.Cu")
		(net 611)
	)
	(segment
		(start 129.417508 100.629992)
		(end 129.4975 100.55)
		(width 0.2)
		(layer "F.Cu")
		(net 612)
	)
	(segment
		(start 128.346172 100.629992)
		(end 129.417508 100.629992)
		(width 0.2)
		(layer "F.Cu")
		(net 612)
	)
	(segment
		(start 125.446172 100.129992)
		(end 124.452508 100.129992)
		(width 0.2)
		(layer "F.Cu")
		(net 613)
	)
	(segment
		(start 124.452508 100.129992)
		(end 124.1325 100.45)
		(width 0.2)
		(layer "F.Cu")
		(net 613)
	)
	(segment
		(start 116.061478 88.654992)
		(end 116.632814 88.654992)
		(width 0.2)
		(layer "F.Cu")
		(net 614)
	)
	(segment
		(start 116.632814 88.654992)
		(end 117.212806 88.075)
		(width 0.2)
		(layer "F.Cu")
		(net 614)
	)
	(segment
		(start 128.885008 88.654992)
		(end 129.465 88.075)
		(width 0.2)
		(layer "F.Cu")
		(net 615)
	)
	(segment
		(start 128.313672 88.654992)
		(end 128.885008 88.654992)
		(width 0.2)
		(layer "F.Cu")
		(net 615)
	)
	(segment
		(start 186.420008 116.548672)
		(end 186.420008 117.120008)
		(width 0.2)
		(layer "F.Cu")
		(net 616)
	)
	(segment
		(start 186.420008 117.120008)
		(end 187 117.7)
		(width 0.2)
		(layer "F.Cu")
		(net 616)
	)
	(segment
		(start 116.638672 100.629992)
		(end 117.710008 100.629992)
		(width 0.2)
		(layer "F.Cu")
		(net 617)
	)
	(segment
		(start 117.710008 100.629992)
		(end 117.79 100.55)
		(width 0.2)
		(layer "F.Cu")
		(net 617)
	)
	(segment
		(start 113.738672 100.129992)
		(end 112.745008 100.129992)
		(width 0.2)
		(layer "F.Cu")
		(net 618)
	)
	(segment
		(start 112.745008 100.129992)
		(end 112.425 100.45)
		(width 0.2)
		(layer "F.Cu")
		(net 618)
	)
	(segment
		(start 117.132814 89.154992)
		(end 117.212806 89.075)
		(width 0.2)
		(layer "F.Cu")
		(net 619)
	)
	(segment
		(start 116.061478 89.154992)
		(end 117.132814 89.154992)
		(width 0.2)
		(layer "F.Cu")
		(net 619)
	)
	(segment
		(start 112.167814 88.654992)
		(end 111.847806 88.975)
		(width 0.2)
		(layer "F.Cu")
		(net 620)
	)
	(segment
		(start 113.161478 88.654992)
		(end 112.167814 88.654992)
		(width 0.2)
		(layer "F.Cu")
		(net 620)
	)
	(segment
		(start 129.385008 89.154992)
		(end 129.465 89.075)
		(width 0.2)
		(layer "F.Cu")
		(net 621)
	)
	(segment
		(start 128.313672 89.154992)
		(end 129.385008 89.154992)
		(width 0.2)
		(layer "F.Cu")
		(net 621)
	)
	(segment
		(start 124.455008 88.654992)
		(end 125.413672 88.654992)
		(width 0.2)
		(layer "F.Cu")
		(net 622)
	)
	(segment
		(start 124.455008 88.654992)
		(end 124.135 88.975)
		(width 0.2)
		(layer "F.Cu")
		(net 622)
	)
	(segment
		(start 185.920008 117.620008)
		(end 186 117.7)
		(width 0.2)
		(layer "F.Cu")
		(net 623)
	)
	(segment
		(start 185.920008 116.548672)
		(end 185.920008 117.620008)
		(width 0.2)
		(layer "F.Cu")
		(net 623)
	)
	(segment
		(start 186.420008 113.648672)
		(end 186.420008 112.655008)
		(width 0.2)
		(layer "F.Cu")
		(net 624)
	)
	(segment
		(start 186.420008 112.655008)
		(end 186.1 112.335)
		(width 0.2)
		(layer "F.Cu")
		(net 624)
	)
	(segment
		(start 126.107157 56.417672)
		(end 127.882672 56.417672)
		(width 0.15)
		(layer "F.Cu")
		(net 625)
	)
	(segment
		(start 127.882672 56.417672)
		(end 128.19 56.725)
		(width 0.15)
		(layer "F.Cu")
		(net 625)
	)
	(segment
		(start 124.267157 54.517672)
		(end 124.175 54.425515)
		(width 0.2)
		(layer "F.Cu")
		(net 626)
	)
	(segment
		(start 124.175 54.425515)
		(end 124.175 52.96)
		(width 0.2)
		(layer "F.Cu")
		(net 626)
	)
	(segment
		(start 124.267157 55.017672)
		(end 124.267157 54.517672)
		(width 0.2)
		(layer "F.Cu")
		(net 626)
	)
	(segment
		(start 126.295002 54.439827)
		(end 126.295002 53.050002)
		(width 0.25)
		(layer "F.Cu")
		(net 627)
	)
	(segment
		(start 126.267157 54.467672)
		(end 126.295002 54.439827)
		(width 0.25)
		(layer "F.Cu")
		(net 627)
	)
	(segment
		(start 126.267157 55.017672)
		(end 126.267157 54.467672)
		(width 0.25)
		(layer "F.Cu")
		(net 627)
	)
	(segment
		(start 128.147328 55.767672)
		(end 128.19 55.725)
		(width 0.15)
		(layer "F.Cu")
		(net 629)
	)
	(segment
		(start 126.927157 55.767672)
		(end 128.147328 55.767672)
		(width 0.15)
		(layer "F.Cu")
		(net 629)
	)
	(segment
		(start 124.157157 56.417672)
		(end 123.377157 56.417672)
		(width 0.15)
		(layer "F.Cu")
		(net 630)
	)
	(via
		(at 123.377157 56.417672)
		(size 0.5)
		(drill 0.2)
		(layers "F.Cu" "B.Cu")
		(net 630)
	)
	(segment
		(start 123.075 57.910828)
		(end 123.075 58.975)
		(width 0.2)
		(layer "B.Cu")
		(net 630)
	)
	(segment
		(start 123.377157 56.417672)
		(end 123.377157 57.608672)
		(width 0.2)
		(layer "B.Cu")
		(net 630)
	)
	(segment
		(start 122.65 59.4)
		(end 123.075 58.975)
		(width 0.2)
		(layer "B.Cu")
		(net 630)
	)
	(segment
		(start 121.485 59.4)
		(end 122.65 59.4)
		(width 0.2)
		(layer "B.Cu")
		(net 630)
	)
	(segment
		(start 123.377157 57.608672)
		(end 123.075 57.910828)
		(width 0.2)
		(layer "B.Cu")
		(net 630)
	)
	(segment
		(start 125.267157 55.017672)
		(end 125.267157 54.35)
		(width 0.15)
		(layer "F.Cu")
		(net 631)
	)
	(segment
		(start 125.19 54.272843)
		(end 125.19 53.520829)
		(width 0.15)
		(layer "F.Cu")
		(net 631)
	)
	(segment
		(start 125.267157 54.35)
		(end 125.19 54.272843)
		(width 0.15)
		(layer "F.Cu")
		(net 631)
	)
	(segment
		(start 125.19 53.520829)
		(end 125.19 53.225)
		(width 0.15)
		(layer "F.Cu")
		(net 631)
	)
	(segment
		(start 114.45 107.35)
		(end 115.485 108.385)
		(width 0.2)
		(layer "F.Cu")
		(net 632)
	)
	(segment
		(start 114.45 106.4)
		(end 114.45 107.35)
		(width 0.2)
		(layer "F.Cu")
		(net 632)
	)
	(segment
		(start 115.485 108.385)
		(end 115.485 109)
		(width 0.2)
		(layer "F.Cu")
		(net 632)
	)
	(segment
		(start 136.615 64.7)
		(end 136.51 64.7)
		(width 0.1)
		(layer "F.Cu")
		(net 635)
	)
	(segment
		(start 136.5 64.69)
		(end 136.5 65.585)
		(width 0.2)
		(layer "F.Cu")
		(net 635)
	)
	(segment
		(start 136.5 63.625)
		(end 136.5 64.69)
		(width 0.2)
		(layer "F.Cu")
		(net 635)
	)
	(segment
		(start 136.615 65.7)
		(end 136.5 65.585)
		(width 0.2)
		(layer "F.Cu")
		(net 635)
	)
	(segment
		(start 136.51 64.7)
		(end 136.5 64.69)
		(width 0.1)
		(layer "F.Cu")
		(net 635)
	)
	(segment
		(start 136 60.775)
		(end 136 59.785)
		(width 0.2)
		(layer "F.Cu")
		(net 636)
	)
	(segment
		(start 136 59.785)
		(end 136.085 59.7)
		(width 0.2)
		(layer "F.Cu")
		(net 636)
	)
	(segment
		(start 124.267157 58.132843)
		(end 124.175 58.225)
		(width 0.15)
		(layer "F.Cu")
		(net 636)
	)
	(segment
		(start 136 59.615)
		(end 136.085 59.7)
		(width 0.15)
		(layer "F.Cu")
		(net 636)
	)
	(segment
		(start 137.115 59.7)
		(end 136.085 59.7)
		(width 0.2)
		(layer "F.Cu")
		(net 636)
	)
	(segment
		(start 124.175 58.225)
		(end 123.55 58.225)
		(width 0.15)
		(layer "F.Cu")
		(net 636)
	)
	(segment
		(start 136 59.1)
		(end 136 59.615)
		(width 0.15)
		(layer "F.Cu")
		(net 636)
	)
	(segment
		(start 124.267157 57.817672)
		(end 124.267157 58.132843)
		(width 0.15)
		(layer "F.Cu")
		(net 636)
	)
	(via
		(at 123.55 58.225)
		(size 0.5)
		(drill 0.2)
		(layers "F.Cu" "B.Cu")
		(net 636)
	)
	(via
		(at 122.7 64.4)
		(size 0.5)
		(drill 0.2)
		(layers "F.Cu" "B.Cu")
		(net 636)
	)
	(via
		(at 136 59.1)
		(size 0.5)
		(drill 0.2)
		(layers "F.Cu" "B.Cu")
		(net 636)
	)
	(segment
		(start 122.7 65.5)
		(end 122.7 64.4)
		(width 0.15)
		(layer "B.Cu")
		(net 636)
	)
	(segment
		(start 123.45 63.65)
		(end 122.7 64.4)
		(width 0.15)
		(layer "In5.Cu")
		(net 636)
	)
	(segment
		(start 123.45 58.325)
		(end 123.45 63.65)
		(width 0.15)
		(layer "In5.Cu")
		(net 636)
	)
	(segment
		(start 123.925 57.85)
		(end 123.55 58.225)
		(width 0.15)
		(layer "In5.Cu")
		(net 636)
	)
	(segment
		(start 123.55 58.225)
		(end 123.45 58.325)
		(width 0.15)
		(layer "In5.Cu")
		(net 636)
	)
	(segment
		(start 130.1 59.1)
		(end 128.85 57.85)
		(width 0.15)
		(layer "In5.Cu")
		(net 636)
	)
	(segment
		(start 136 59.1)
		(end 130.1 59.1)
		(width 0.15)
		(layer "In5.Cu")
		(net 636)
	)
	(segment
		(start 128.85 57.85)
		(end 123.925 57.85)
		(width 0.15)
		(layer "In5.Cu")
		(net 636)
	)
	(segment
		(start 136 64.315)
		(end 135.6 64.715)
		(width 0.2)
		(layer "F.Cu")
		(net 639)
	)
	(segment
		(start 136 63.625)
		(end 136 64.315)
		(width 0.2)
		(layer "F.Cu")
		(net 639)
	)
	(via
		(at 182 67.8)
		(size 0.5)
		(drill 0.2)
		(layers "F.Cu" "B.Cu")
		(free yes)
		(net 641)
	)
	(via
		(at 183.8 68.2)
		(size 0.5)
		(drill 0.2)
		(layers "F.Cu" "B.Cu")
		(free yes)
		(net 641)
	)
	(via
		(at 183.8 67.4)
		(size 0.5)
		(drill 0.2)
		(layers "F.Cu" "B.Cu")
		(free yes)
		(net 641)
	)
	(via
		(at 183.8 69)
		(size 0.5)
		(drill 0.2)
		(layers "F.Cu" "B.Cu")
		(free yes)
		(net 641)
	)
	(via
		(at 182.6 67.4)
		(size 0.5)
		(drill 0.2)
		(layers "F.Cu" "B.Cu")
		(free yes)
		(net 641)
	)
	(via
		(at 146.5 68.2)
		(size 0.5)
		(drill 0.2)
		(layers "F.Cu" "B.Cu")
		(free yes)
		(net 641)
	)
	(via
		(at 147.7 68.2)
		(size 0.5)
		(drill 0.2)
		(layers "F.Cu" "B.Cu")
		(free yes)
		(net 641)
	)
	(via
		(at 182.6 68.2)
		(size 0.5)
		(drill 0.2)
		(layers "F.Cu" "B.Cu")
		(free yes)
		(net 641)
	)
	(via
		(at 147.1 68.6)
		(size 0.5)
		(drill 0.2)
		(layers "F.Cu" "B.Cu")
		(free yes)
		(net 641)
	)
	(via
		(at 145.9 68.6)
		(size 0.5)
		(drill 0.2)
		(layers "F.Cu" "B.Cu")
		(free yes)
		(net 641)
	)
	(via
		(at 147.7 67.4)
		(size 0.5)
		(drill 0.2)
		(layers "F.Cu" "B.Cu")
		(free yes)
		(net 641)
	)
	(via
		(at 183.2 68.6)
		(size 0.5)
		(drill 0.2)
		(layers "F.Cu" "B.Cu")
		(free yes)
		(net 641)
	)
	(via
		(at 146.5 67.4)
		(size 0.5)
		(drill 0.2)
		(layers "F.Cu" "B.Cu")
		(free yes)
		(net 641)
	)
	(via
		(at 183.2 67.8)
		(size 0.5)
		(drill 0.2)
		(layers "F.Cu" "B.Cu")
		(free yes)
		(net 641)
	)
	(via
		(at 182.6 69)
		(size 0.5)
		(drill 0.2)
		(layers "F.Cu" "B.Cu")
		(free yes)
		(net 641)
	)
	(via
		(at 147.1 67.8)
		(size 0.5)
		(drill 0.2)
		(layers "F.Cu" "B.Cu")
		(free yes)
		(net 641)
	)
	(via
		(at 147.7 69)
		(size 0.5)
		(drill 0.2)
		(layers "F.Cu" "B.Cu")
		(free yes)
		(net 641)
	)
	(via
		(at 182 68.6)
		(size 0.5)
		(drill 0.2)
		(layers "F.Cu" "B.Cu")
		(free yes)
		(net 641)
	)
	(via
		(at 145.9 67.8)
		(size 0.5)
		(drill 0.2)
		(layers "F.Cu" "B.Cu")
		(free yes)
		(net 641)
	)
	(via
		(at 146.5 69)
		(size 0.5)
		(drill 0.2)
		(layers "F.Cu" "B.Cu")
		(free yes)
		(net 641)
	)
	(segment
		(start 154.7 106.2)
		(end 154.7 104.9)
		(width 0.15)
		(layer "F.Cu")
		(net 643)
	)
	(segment
		(start 154.997157 106.497157)
		(end 154.7 106.2)
		(width 0.15)
		(layer "F.Cu")
		(net 643)
	)
	(segment
		(start 158.536328 106.497157)
		(end 154.997157 106.497157)
		(width 0.15)
		(layer "F.Cu")
		(net 643)
	)
	(via
		(at 154.7 104.9)
		(size 0.5)
		(drill 0.2)
		(layers "F.Cu" "B.Cu")
		(net 643)
	)
	(segment
		(start 129.3 83.4)
		(end 128.8 82.9)
		(width 0.15)
		(layer "B.Cu")
		(net 643)
	)
	(segment
		(start 154.7 93)
		(end 149.5 87.8)
		(width 0.15)
		(layer "B.Cu")
		(net 643)
	)
	(segment
		(start 128.8 82.9)
		(end 128.8 71.7)
		(width 0.15)
		(layer "B.Cu")
		(net 643)
	)
	(segment
		(start 131.1 83.4)
		(end 129.3 83.4)
		(width 0.15)
		(layer "B.Cu")
		(net 643)
	)
	(segment
		(start 149.5 87.8)
		(end 135.5 87.8)
		(width 0.15)
		(layer "B.Cu")
		(net 643)
	)
	(segment
		(start 154.7 104.9)
		(end 154.7 93)
		(width 0.15)
		(layer "B.Cu")
		(net 643)
	)
	(segment
		(start 135.5 87.8)
		(end 131.1 83.4)
		(width 0.15)
		(layer "B.Cu")
		(net 643)
	)
	(segment
		(start 128.8 71.7)
		(end 126.085 68.985)
		(width 0.15)
		(layer "B.Cu")
		(net 643)
	)
	(segment
		(start 126.085 68.985)
		(end 126.085 67.65)
		(width 0.15)
		(layer "B.Cu")
		(net 643)
	)
	(segment
		(start 156.697157 105.497157)
		(end 156.4 105.2)
		(width 0.15)
		(layer "F.Cu")
		(net 644)
	)
	(segment
		(start 156.4 105.2)
		(end 156.4 104.9)
		(width 0.15)
		(layer "F.Cu")
		(net 644)
	)
	(segment
		(start 158.536328 105.497157)
		(end 156.697157 105.497157)
		(width 0.15)
		(layer "F.Cu")
		(net 644)
	)
	(via
		(at 156.4 104.9)
		(size 0.5)
		(drill 0.2)
		(layers "F.Cu" "B.Cu")
		(net 644)
	)
	(segment
		(start 132.75 78.5)
		(end 132.75 83.35)
		(width 0.15)
		(layer "B.Cu")
		(net 644)
	)
	(segment
		(start 136.2 86.8)
		(end 150.1 86.8)
		(width 0.15)
		(layer "B.Cu")
		(net 644)
	)
	(segment
		(start 156.4 93.1)
		(end 156.4 104.9)
		(width 0.15)
		(layer "B.Cu")
		(net 644)
	)
	(segment
		(start 133.715 78.4)
		(end 132.85 78.4)
		(width 0.15)
		(layer "B.Cu")
		(net 644)
	)
	(segment
		(start 132.85 78.4)
		(end 132.75 78.5)
		(width 0.15)
		(layer "B.Cu")
		(net 644)
	)
	(segment
		(start 132.75 83.35)
		(end 136.2 86.8)
		(width 0.15)
		(layer "B.Cu")
		(net 644)
	)
	(segment
		(start 150.1 86.8)
		(end 156.4 93.1)
		(width 0.15)
		(layer "B.Cu")
		(net 644)
	)
	(segment
		(start 155.942157 106.042157)
		(end 155.6 105.7)
		(width 0.15)
		(layer "F.Cu")
		(net 646)
	)
	(segment
		(start 158.991328 106.042157)
		(end 155.942157 106.042157)
		(width 0.15)
		(layer "F.Cu")
		(net 646)
	)
	(segment
		(start 159.536328 105.497157)
		(end 158.991328 106.042157)
		(width 0.15)
		(layer "F.Cu")
		(net 646)
	)
	(segment
		(start 155.6 105.7)
		(end 155.6 104.9)
		(width 0.15)
		(layer "F.Cu")
		(net 646)
	)
	(via
		(at 132.85 72.1)
		(size 0.5)
		(drill 0.2)
		(layers "F.Cu" "B.Cu")
		(net 646)
	)
	(via
		(at 155.6 104.9)
		(size 0.5)
		(drill 0.2)
		(layers "F.Cu" "B.Cu")
		(net 646)
	)
	(via
		(at 132.3 83.7)
		(size 0.5)
		(drill 0.2)
		(layers "F.Cu" "B.Cu")
		(net 646)
	)
	(segment
		(start 133.05 70)
		(end 132.85 70.2)
		(width 0.15)
		(layer "B.Cu")
		(net 646)
	)
	(segment
		(start 133.715 70)
		(end 133.05 70)
		(width 0.15)
		(layer "B.Cu")
		(net 646)
	)
	(segment
		(start 132.3 83.7)
		(end 135.9 87.3)
		(width 0.15)
		(layer "B.Cu")
		(net 646)
	)
	(segment
		(start 132.85 70.2)
		(end 132.85 72.1)
		(width 0.15)
		(layer "B.Cu")
		(net 646)
	)
	(segment
		(start 149.9 87.3)
		(end 155.6 93)
		(width 0.15)
		(layer "B.Cu")
		(net 646)
	)
	(segment
		(start 155.6 93)
		(end 155.6 104.9)
		(width 0.15)
		(layer "B.Cu")
		(net 646)
	)
	(segment
		(start 135.9 87.3)
		(end 149.9 87.3)
		(width 0.15)
		(layer "B.Cu")
		(net 646)
	)
	(segment
		(start 132.3 83.7)
		(end 132.3 72.65)
		(width 0.15)
		(layer "In5.Cu")
		(net 646)
	)
	(segment
		(start 132.3 72.65)
		(end 132.85 72.1)
		(width 0.15)
		(layer "In5.Cu")
		(net 646)
	)
	(segment
		(start 162.097328 81.364616)
		(end 162.938359 82.205647)
		(width 0.182)
		(layer "F.Cu")
		(net 648)
	)
	(segment
		(start 162.036328 78.847157)
		(end 162.036328 80.159658)
		(width 0.182)
		(layer "F.Cu")
		(net 648)
	)
	(segment
		(start 162.938359 82.644353)
		(end 162.036328 83.546384)
		(width 0.182)
		(layer "F.Cu")
		(net 648)
	)
	(segment
		(start 162.938359 82.205647)
		(end 162.938359 82.644353)
		(width 0.182)
		(layer "F.Cu")
		(net 648)
	)
	(segment
		(start 162.036328 80.159658)
		(end 162.097328 80.220658)
		(width 0.182)
		(layer "F.Cu")
		(net 648)
	)
	(segment
		(start 162.097328 80.220658)
		(end 162.097328 81.364616)
		(width 0.182)
		(layer "F.Cu")
		(net 648)
	)
	(segment
		(start 162.036328 83.546384)
		(end 162.036328 85.997157)
		(width 0.182)
		(layer "F.Cu")
		(net 648)
	)
	(segment
		(start 162.036328 85.997157)
		(end 162.536328 86.497157)
		(width 0.182)
		(layer "F.Cu")
		(net 648)
	)
	(segment
		(start 163.06 84.76)
		(end 163.058659 84.76)
		(width 0.182)
		(layer "F.Cu")
		(net 649)
	)
	(segment
		(start 163.316359 82.049071)
		(end 163.316359 82.800929)
		(width 0.182)
		(layer "F.Cu")
		(net 649)
	)
	(segment
		(start 162.475328 80.220658)
		(end 162.475328 81.20804)
		(width 0.182)
		(layer "F.Cu")
		(net 649)
	)
	(segment
		(start 162.433644 83.683644)
		(end 162.433644 84.134985)
		(width 0.182)
		(layer "F.Cu")
		(net 649)
	)
	(segment
		(start 163.316359 82.800929)
		(end 162.433644 83.683644)
		(width 0.182)
		(layer "F.Cu")
		(net 649)
	)
	(segment
		(start 162.536328 80.159658)
		(end 162.475328 80.220658)
		(width 0.182)
		(layer "F.Cu")
		(net 649)
	)
	(segment
		(start 163.536328 86.497157)
		(end 163.06 86.020829)
		(width 0.182)
		(layer "F.Cu")
		(net 649)
	)
	(segment
		(start 162.475328 81.20804)
		(end 163.316359 82.049071)
		(width 0.182)
		(layer "F.Cu")
		(net 649)
	)
	(segment
		(start 162.433644 84.134985)
		(end 163.058659 84.76)
		(width 0.182)
		(layer "F.Cu")
		(net 649)
	)
	(segment
		(start 162.536328 78.847157)
		(end 162.536328 80.159658)
		(width 0.182)
		(layer "F.Cu")
		(net 649)
	)
	(segment
		(start 163.06 86.020829)
		(end 163.06 84.76)
		(width 0.182)
		(layer "F.Cu")
		(net 649)
	)
	(segment
		(start 168.35 85.310829)
		(end 168.35 83.232712)
		(width 0.182)
		(layer "F.Cu")
		(net 650)
	)
	(segment
		(start 168.597328 79.993114)
		(end 168.597328 79.633157)
		(width 0.182)
		(layer "F.Cu")
		(net 650)
	)
	(segment
		(start 168.35 80.240442)
		(end 168.597328 79.993114)
		(width 0.182)
		(layer "F.Cu")
		(net 650)
	)
	(segment
		(start 168.503641 82.38412)
		(end 168.50364 82.384122)
		(width 0.182)
		(layer "F.Cu")
		(net 650)
	)
	(segment
		(start 168.597328 79.633157)
		(end 168.536328 79.572157)
		(width 0.182)
		(layer "F.Cu")
		(net 650)
	)
	(segment
		(start 168.512772 81.406745)
		(end 168.512773 81.406745)
		(width 0.182)
		(layer "F.Cu")
		(net 650)
	)
	(segment
		(start 168.536328 79.572157)
		(end 168.536328 78.847157)
		(width 0.182)
		(layer "F.Cu")
		(net 650)
	)
	(segment
		(start 168.616356 82.731598)
		(end 168.616357 82.731596)
		(width 0.182)
		(layer "F.Cu")
		(net 650)
	)
	(segment
		(start 168.536328 85.497157)
		(end 168.35 85.310829)
		(width 0.182)
		(layer "F.Cu")
		(net 650)
	)
	(segment
		(start 168.35 83.232712)
		(end 168.616356 82.966356)
		(width 0.182)
		(layer "F.Cu")
		(net 650)
	)
	(segment
		(start 168.35 80.678288)
		(end 168.35 80.240442)
		(width 0.182)
		(layer "F.Cu")
		(net 650)
	)
	(segment
		(start 168.747531 81.406745)
		(end 168.795614 81.358661)
		(width 0.182)
		(layer "F.Cu")
		(net 650)
	)
	(segment
		(start 169.085877 82.496839)
		(end 169.085877 82.496838)
		(width 0.182)
		(layer "F.Cu")
		(net 650)
	)
	(segment
		(start 169.3 82.282712)
		(end 169.3 81.628288)
		(width 0.182)
		(layer "F.Cu")
		(net 650)
	)
	(segment
		(start 169.3 81.628288)
		(end 169.030373 81.358662)
		(width 0.182)
		(layer "F.Cu")
		(net 650)
	)
	(segment
		(start 168.7384 82.384122)
		(end 168.851117 82.496839)
		(width 0.182)
		(layer "F.Cu")
		(net 650)
	)
	(segment
		(start 169.085877 82.496838)
		(end 169.3 82.282712)
		(width 0.182)
		(layer "F.Cu")
		(net 650)
	)
	(segment
		(start 168.512772 81.171986)
		(end 168.560856 81.123903)
		(width 0.182)
		(layer "F.Cu")
		(net 650)
	)
	(segment
		(start 168.616357 82.731596)
		(end 168.503641 82.61888)
		(width 0.182)
		(layer "F.Cu")
		(net 650)
	)
	(segment
		(start 168.560856 80.889144)
		(end 168.35 80.678288)
		(width 0.182)
		(layer "F.Cu")
		(net 650)
	)
	(arc
		(start 168.503641 82.61888)
		(mid 168.455021 82.5015)
		(end 168.503641 82.38412)
		(width 0.182)
		(layer "F.Cu")
		(net 650)
	)
	(arc
		(start 168.616356 82.966356)
		(mid 168.664977 82.848976)
		(end 168.616356 82.731598)
		(width 0.182)
		(layer "F.Cu")
		(net 650)
	)
	(arc
		(start 168.851117 82.496839)
		(mid 168.968497 82.545459)
		(end 169.085877 82.496839)
		(width 0.182)
		(layer "F.Cu")
		(net 650)
	)
	(arc
		(start 168.747531 81.406744)
		(mid 168.630152 81.455365)
		(end 168.512772 81.406745)
		(width 0.182)
		(layer "F.Cu")
		(net 650)
	)
	(arc
		(start 169.030373 81.358662)
		(mid 168.912994 81.310041)
		(end 168.795614 81.358661)
		(width 0.182)
		(layer "F.Cu")
		(net 650)
	)
	(arc
		(start 168.560855 81.123903)
		(mid 168.609476 81.006524)
		(end 168.560856 80.889144)
		(width 0.182)
		(layer "F.Cu")
		(net 650)
	)
	(arc
		(start 168.512773 81.406745)
		(mid 168.464152 81.289366)
		(end 168.512772 81.171986)
		(width 0.182)
		(layer "F.Cu")
		(net 650)
	)
	(arc
		(start 168.50364 82.384122)
		(mid 168.62102 82.335502)
		(end 168.7384 82.384122)
		(width 0.182)
		(layer "F.Cu")
		(net 650)
	)
	(segment
		(start 168.536328 86.497157)
		(end 169.007328 86.026156)
		(width 0.182)
		(layer "F.Cu")
		(net 651)
	)
	(segment
		(start 168.975328 80.14969)
		(end 168.728 80.397018)
		(width 0.182)
		(layer "F.Cu")
		(net 651)
	)
	(segment
		(start 169.007328 85.302062)
		(end 168.728 85.022734)
		(width 0.182)
		(layer "F.Cu")
		(net 651)
	)
	(segment
		(start 168.728 83.389288)
		(end 168.728 85.028)
		(width 0.182)
		(layer "F.Cu")
		(net 651)
	)
	(segment
		(start 168.728 80.521712)
		(end 169.678 81.471712)
		(width 0.182)
		(layer "F.Cu")
		(net 651)
	)
	(segment
		(start 169.007328 86.026156)
		(end 169.007328 85.302062)
		(width 0.182)
		(layer "F.Cu")
		(net 651)
	)
	(segment
		(start 168.728 80.397018)
		(end 168.728 80.521712)
		(width 0.182)
		(layer "F.Cu")
		(net 651)
	)
	(segment
		(start 169.036328 78.847157)
		(end 169.036328 79.572157)
		(width 0.182)
		(layer "F.Cu")
		(net 651)
	)
	(segment
		(start 168.975328 79.633157)
		(end 168.975328 80.14969)
		(width 0.182)
		(layer "F.Cu")
		(net 651)
	)
	(segment
		(start 169.678 81.471712)
		(end 169.678 82.439288)
		(width 0.182)
		(layer "F.Cu")
		(net 651)
	)
	(segment
		(start 169.036328 79.572157)
		(end 168.975328 79.633157)
		(width 0.182)
		(layer "F.Cu")
		(net 651)
	)
	(segment
		(start 169.678 82.439288)
		(end 168.728 83.389288)
		(width 0.182)
		(layer "F.Cu")
		(net 651)
	)
	(segment
		(start 141.5 111.7875)
		(end 141.5 114.075829)
		(width 0.2)
		(layer "F.Cu")
		(net 652)
	)
	(segment
		(start 141.581328 114.157157)
		(end 141.581328 116.527157)
		(width 0.2)
		(layer "F.Cu")
		(net 652)
	)
	(segment
		(start 141.581328 114.157157)
		(end 141.581328 115.237157)
		(width 0.15)
		(layer "F.Cu")
		(net 652)
	)
	(segment
		(start 141.5 114.075829)
		(end 141.581328 114.157157)
		(width 0.2)
		(layer "F.Cu")
		(net 652)
	)
	(segment
		(start 141.581328 116.527157)
		(end 141.581328 115.237157)
		(width 0.15)
		(layer "F.Cu")
		(net 652)
	)
	(segment
		(start 139.5 111.7875)
		(end 139.5 113.240485)
		(width 0.2)
		(layer "F.Cu")
		(net 653)
	)
	(segment
		(start 138.786328 113.984157)
		(end 138.771328 113.969157)
		(width 0.15)
		(layer "F.Cu")
		(net 653)
	)
	(segment
		(start 138.771328 115.108157)
		(end 138.771328 113.969157)
		(width 0.2)
		(layer "F.Cu")
		(net 653)
	)
	(segment
		(start 138.786328 116.772157)
		(end 138.786328 115.123157)
		(width 0.2)
		(layer "F.Cu")
		(net 653)
	)
	(segment
		(start 138.786328 116.772157)
		(end 138.786328 113.984157)
		(width 0.15)
		(layer "F.Cu")
		(net 653)
	)
	(segment
		(start 138.786328 115.123157)
		(end 138.771328 115.108157)
		(width 0.2)
		(layer "F.Cu")
		(net 653)
	)
	(segment
		(start 139.5 113.240485)
		(end 138.771328 113.969157)
		(width 0.2)
		(layer "F.Cu")
		(net 653)
	)
	(segment
		(start 191.671328 104.209306)
		(end 191.786328 104.324306)
		(width 0.15)
		(layer "F.Cu")
		(net 656)
	)
	(segment
		(start 193.586328 103.989306)
		(end 192.351328 103.989306)
		(width 0.15)
		(layer "F.Cu")
		(net 656)
	)
	(segment
		(start 197.009179 104.297157)
		(end 195.209179 104.297157)
		(width 0.15)
		(layer "F.Cu")
		(net 656)
	)
	(segment
		(start 191.671328 102.874306)
		(end 191.671328 104.209306)
		(width 0.15)
		(layer "F.Cu")
		(net 656)
	)
	(segment
		(start 194.901328 103.989306)
		(end 193.586328 103.989306)
		(width 0.15)
		(layer "F.Cu")
		(net 656)
	)
	(segment
		(start 195.209179 104.297157)
		(end 194.901328 103.989306)
		(width 0.15)
		(layer "F.Cu")
		(net 656)
	)
	(segment
		(start 189.486328 106.124306)
		(end 189.486328 107.659306)
		(width 0.15)
		(layer "F.Cu")
		(net 657)
	)
	(segment
		(start 190.336328 105.274306)
		(end 192.586328 105.274306)
		(width 0.15)
		(layer "F.Cu")
		(net 657)
	)
	(segment
		(start 193.586328 104.959306)
		(end 192.901328 104.959306)
		(width 0.15)
		(layer "F.Cu")
		(net 657)
	)
	(segment
		(start 190.336328 105.274306)
		(end 189.486328 106.124306)
		(width 0.15)
		(layer "F.Cu")
		(net 657)
	)
	(segment
		(start 192.901328 104.959306)
		(end 192.586328 105.274306)
		(width 0.15)
		(layer "F.Cu")
		(net 657)
	)
	(segment
		(start 193.586328 104.959306)
		(end 195.001328 104.959306)
		(width 0.15)
		(layer "F.Cu")
		(net 657)
	)
	(segment
		(start 189.486328 107.659306)
		(end 189.501328 107.674306)
		(width 0.15)
		(layer "F.Cu")
		(net 657)
	)
	(segment
		(start 197.009179 104.797157)
		(end 195.186328 104.774306)
		(width 0.15)
		(layer "F.Cu")
		(net 657)
	)
	(segment
		(start 195.001328 104.959306)
		(end 195.186328 104.774306)
		(width 0.15)
		(layer "F.Cu")
		(net 657)
	)
	(segment
		(start 129.16 55.725)
		(end 129.16 56.725)
		(width 0.15)
		(layer "F.Cu")
		(net 659)
	)
	(segment
		(start 116.497157 117.897157)
		(end 116.58 117.98)
		(width 0.2)
		(layer "F.Cu")
		(net 660)
	)
	(segment
		(start 116.286328 117.897157)
		(end 116.497157 117.897157)
		(width 0.2)
		(layer "F.Cu")
		(net 660)
	)
	(segment
		(start 116.48 118.995)
		(end 117.485 120)
		(width 0.2)
		(layer "F.Cu")
		(net 660)
	)
	(segment
		(start 116.58 117.98)
		(end 116.58 118.975)
		(width 0.2)
		(layer "F.Cu")
		(net 660)
	)
	(segment
		(start 116.48 118.975)
		(end 116.48 118.995)
		(width 0.2)
		(layer "F.Cu")
		(net 660)
	)
	(segment
		(start 154.4715 119.9225)
		(end 154.4715 122.598499)
		(width 0.15)
		(layer "F.Cu")
		(net 663)
	)
	(segment
		(start 154.11 117.028485)
		(end 154.433 116.705485)
		(width 0.15)
		(layer "F.Cu")
		(net 663)
	)
	(segment
		(start 154.14 122.929999)
		(end 154.14 124.88)
		(width 0.15)
		(layer "F.Cu")
		(net 663)
	)
	(segment
		(start 154.4715 122.598499)
		(end 154.14 122.929999)
		(width 0.15)
		(layer "F.Cu")
		(net 663)
	)
	(segment
		(start 154.433 116.705485)
		(end 154.433 113.994)
		(width 0.15)
		(layer "F.Cu")
		(net 663)
	)
	(segment
		(start 154.433 113.994)
		(end 154.059 113.62)
		(width 0.15)
		(layer "F.Cu")
		(net 663)
	)
	(segment
		(start 154.11 118.68)
		(end 154.11 119.561)
		(width 0.15)
		(layer "F.Cu")
		(net 663)
	)
	(segment
		(start 154.11 119.561)
		(end 154.4715 119.9225)
		(width 0.15)
		(layer "F.Cu")
		(net 663)
	)
	(segment
		(start 154.11 118.68)
		(end 154.11 117.028485)
		(width 0.15)
		(layer "F.Cu")
		(net 663)
	)
	(segment
		(start 154.71 116.655829)
		(end 154.71 113.994)
		(width 0.15)
		(layer "F.Cu")
		(net 664)
	)
	(segment
		(start 155.14 122.929999)
		(end 155.14 124.88)
		(width 0.15)
		(layer "F.Cu")
		(net 664)
	)
	(segment
		(start 155.11 117.055829)
		(end 154.71 116.655829)
		(width 0.15)
		(layer "F.Cu")
		(net 664)
	)
	(segment
		(start 154.7485 122.538499)
		(end 155.14 122.929999)
		(width 0.15)
		(layer "F.Cu")
		(net 664)
	)
	(segment
		(start 155.11 119.559)
		(end 154.7485 119.9205)
		(width 0.15)
		(layer "F.Cu")
		(net 664)
	)
	(segment
		(start 155.11 118.68)
		(end 155.11 117.055829)
		(width 0.15)
		(layer "F.Cu")
		(net 664)
	)
	(segment
		(start 154.7485 119.9205)
		(end 154.7485 122.538499)
		(width 0.15)
		(layer "F.Cu")
		(net 664)
	)
	(segment
		(start 154.71 113.994)
		(end 155.084 113.62)
		(width 0.15)
		(layer "F.Cu")
		(net 664)
	)
	(segment
		(start 155.11 118.68)
		(end 155.11 119.559)
		(width 0.15)
		(layer "F.Cu")
		(net 664)
	)
	(segment
		(start 155.61 119.549)
		(end 155.61 118.68)
		(width 0.15)
		(layer "F.Cu")
		(net 665)
	)
	(segment
		(start 155.9715 119.9105)
		(end 155.61 119.549)
		(width 0.15)
		(layer "F.Cu")
		(net 665)
	)
	(segment
		(start 155.9715 116.666985)
		(end 155.61 117.028485)
		(width 0.15)
		(layer "F.Cu")
		(net 665)
	)
	(segment
		(start 155.9715 116.2475)
		(end 155.9715 116.666985)
		(width 0.15)
		(layer "F.Cu")
		(net 665)
	)
	(segment
		(start 155.64 122.929999)
		(end 155.9715 122.598499)
		(width 0.15)
		(layer "F.Cu")
		(net 665)
	)
	(segment
		(start 155.61 117.028485)
		(end 155.61 118.68)
		(width 0.15)
		(layer "F.Cu")
		(net 665)
	)
	(segment
		(start 155.559 115.835)
		(end 155.9715 116.2475)
		(width 0.15)
		(layer "F.Cu")
		(net 665)
	)
	(segment
		(start 155.64 124.88)
		(end 155.64 122.929999)
		(width 0.15)
		(layer "F.Cu")
		(net 665)
	)
	(segment
		(start 155.9715 122.598499)
		(end 155.9715 119.9105)
		(width 0.15)
		(layer "F.Cu")
		(net 665)
	)
	(segment
		(start 156.61 119.536)
		(end 156.61 118.68)
		(width 0.15)
		(layer "F.Cu")
		(net 666)
	)
	(segment
		(start 156.2485 119.8975)
		(end 156.61 119.536)
		(width 0.15)
		(layer "F.Cu")
		(net 666)
	)
	(segment
		(start 156.2485 122.538499)
		(end 156.2485 119.8975)
		(width 0.15)
		(layer "F.Cu")
		(net 666)
	)
	(segment
		(start 156.61 117.065829)
		(end 156.61 118.68)
		(width 0.15)
		(layer "F.Cu")
		(net 666)
	)
	(segment
		(start 156.584 115.835)
		(end 156.2485 116.1705)
		(width 0.15)
		(layer "F.Cu")
		(net 666)
	)
	(segment
		(start 156.2485 116.1705)
		(end 156.2485 116.704329)
		(width 0.15)
		(layer "F.Cu")
		(net 666)
	)
	(segment
		(start 156.2485 116.704329)
		(end 156.61 117.065829)
		(width 0.15)
		(layer "F.Cu")
		(net 666)
	)
	(segment
		(start 156.64 122.929999)
		(end 156.2485 122.538499)
		(width 0.15)
		(layer "F.Cu")
		(net 666)
	)
	(segment
		(start 156.64 124.88)
		(end 156.64 122.929999)
		(width 0.15)
		(layer "F.Cu")
		(net 666)
	)
	(segment
		(start 157.14 124.88)
		(end 157.14 122.929999)
		(width 0.15)
		(layer "F.Cu")
		(net 667)
	)
	(segment
		(start 157.4605 113.9015)
		(end 157.094 113.535)
		(width 0.15)
		(layer "F.Cu")
		(net 667)
	)
	(segment
		(start 157.4715 122.598499)
		(end 157.4715 119.8465)
		(width 0.15)
		(layer "F.Cu")
		(net 667)
	)
	(segment
		(start 157.4715 119.8465)
		(end 157.11 119.485)
		(width 0.15)
		(layer "F.Cu")
		(net 667)
	)
	(segment
		(start 157.11 117.008485)
		(end 157.4605 116.657985)
		(width 0.15)
		(layer "F.Cu")
		(net 667)
	)
	(segment
		(start 157.11 118.68)
		(end 157.11 117.008485)
		(width 0.15)
		(layer "F.Cu")
		(net 667)
	)
	(segment
		(start 157.4605 116.657985)
		(end 157.4605 113.9015)
		(width 0.15)
		(layer "F.Cu")
		(net 667)
	)
	(segment
		(start 157.14 122.929999)
		(end 157.4715 122.598499)
		(width 0.15)
		(layer "F.Cu")
		(net 667)
	)
	(segment
		(start 157.11 119.485)
		(end 157.11 118.68)
		(width 0.15)
		(layer "F.Cu")
		(net 667)
	)
	(segment
		(start 157.7375 113.9015)
		(end 158.104 113.535)
		(width 0.15)
		(layer "F.Cu")
		(net 668)
	)
	(segment
		(start 157.7485 119.861498)
		(end 158.11 119.499998)
		(width 0.15)
		(layer "F.Cu")
		(net 668)
	)
	(segment
		(start 158.14 124.88)
		(end 158.14 122.929999)
		(width 0.15)
		(layer "F.Cu")
		(net 668)
	)
	(segment
		(start 157.7375 116.653329)
		(end 157.7375 113.9015)
		(width 0.15)
		(layer "F.Cu")
		(net 668)
	)
	(segment
		(start 158.14 122.929999)
		(end 157.7485 122.538499)
		(width 0.15)
		(layer "F.Cu")
		(net 668)
	)
	(segment
		(start 158.11 119.499998)
		(end 158.11 118.68)
		(width 0.15)
		(layer "F.Cu")
		(net 668)
	)
	(segment
		(start 157.7485 122.538499)
		(end 157.7485 119.861498)
		(width 0.15)
		(layer "F.Cu")
		(net 668)
	)
	(segment
		(start 158.11 117.025829)
		(end 157.7375 116.653329)
		(width 0.15)
		(layer "F.Cu")
		(net 668)
	)
	(segment
		(start 158.11 118.68)
		(end 158.11 117.025829)
		(width 0.15)
		(layer "F.Cu")
		(net 668)
	)
	(segment
		(start 158.61 118.68)
		(end 158.61 119.586)
		(width 0.15)
		(layer "F.Cu")
		(net 669)
	)
	(segment
		(start 158.61 119.586)
		(end 158.9715 119.9475)
		(width 0.15)
		(layer "F.Cu")
		(net 669)
	)
	(segment
		(start 158.9715 116.2905)
		(end 158.643 115.962)
		(width 0.15)
		(layer "F.Cu")
		(net 669)
	)
	(segment
		(start 158.9715 122.598499)
		(end 158.64 122.929999)
		(width 0.15)
		(layer "F.Cu")
		(net 669)
	)
	(segment
		(start 158.64 122.929999)
		(end 158.64 124.88)
		(width 0.15)
		(layer "F.Cu")
		(net 669)
	)
	(segment
		(start 158.61 118.68)
		(end 158.61 117.038485)
		(width 0.15)
		(layer "F.Cu")
		(net 669)
	)
	(segment
		(start 158.61 117.038485)
		(end 158.9715 116.676985)
		(width 0.15)
		(layer "F.Cu")
		(net 669)
	)
	(segment
		(start 158.9715 119.9475)
		(end 158.9715 122.598499)
		(width 0.15)
		(layer "F.Cu")
		(net 669)
	)
	(segment
		(start 158.9715 116.676985)
		(end 158.9715 116.2905)
		(width 0.15)
		(layer "F.Cu")
		(net 669)
	)
	(segment
		(start 159.2485 122.538499)
		(end 159.64 122.929999)
		(width 0.15)
		(layer "F.Cu")
		(net 670)
	)
	(segment
		(start 159.64 122.929999)
		(end 159.64 124.88)
		(width 0.15)
		(layer "F.Cu")
		(net 670)
	)
	(segment
		(start 159.2485 119.941376)
		(end 159.2485 122.538499)
		(width 0.15)
		(layer "F.Cu")
		(net 670)
	)
	(segment
		(start 159.61 117.095829)
		(end 159.2485 116.734329)
		(width 0.15)
		(layer "F.Cu")
		(net 670)
	)
	(segment
		(start 159.61 119.579876)
		(end 159.2485 119.941376)
		(width 0.15)
		(layer "F.Cu")
		(net 670)
	)
	(segment
		(start 159.2485 116.3725)
		(end 159.659 115.962)
		(width 0.15)
		(layer "F.Cu")
		(net 670)
	)
	(segment
		(start 159.2485 116.734329)
		(end 159.2485 116.3725)
		(width 0.15)
		(layer "F.Cu")
		(net 670)
	)
	(segment
		(start 159.61 118.68)
		(end 159.61 117.095829)
		(width 0.15)
		(layer "F.Cu")
		(net 670)
	)
	(segment
		(start 159.61 118.68)
		(end 159.61 119.579876)
		(width 0.15)
		(layer "F.Cu")
		(net 670)
	)
	(zone
		(net 76)
		(net_name "Net-(J6-Pad1)")
		(layer "F.Cu")
		(hatch edge 0.508)
		(connect_pads yes
			(clearance 0.2)
		)
		(min_thickness 0.1)
		(filled_areas_thickness no)
		(fill yes
			(thermal_gap 0.5)
			(thermal_bridge_width 0.5)
			(smoothing fillet)
			(radius 0.125)
		)
		(polygon
			(pts
				(xy 120.9 123.8) (xy 115.2 123.8) (xy 111.8 123.8) (xy 111.8 121.8) (xy 113.2 121.8) (xy 113.2 121.2)
				(xy 114.6 121.2) (xy 120.9 121.2)
			)
		)
	)
	(zone
		(net 465)
		(net_name "1V0_SYS")
		(layer "F.Cu")
		(hatch edge 0.508)
		(connect_pads yes
			(clearance 0.2)
		)
		(min_thickness 0.254)
		(filled_areas_thickness no)
		(fill yes
			(thermal_gap 0.508)
			(thermal_bridge_width 0.508)
		)
		(polygon
			(pts
				(xy 154.878478 88.618165) (xy 152.378811 88.617037) (xy 152.387122 83.496784) (xy 154.886789 83.497912)
			)
		)
	)
	(zone
		(net 5)
		(net_name "GND")
		(layer "F.Cu")
		(hatch edge 0.508)
		(connect_pads yes
			(clearance 0.2)
		)
		(min_thickness 0.254)
		(filled_areas_thickness no)
		(fill yes
			(thermal_gap 0.508)
			(thermal_bridge_width 0.508)
		)
		(polygon
			(pts
				(xy 151.29328 88.704898) (xy 146.085929 88.708402) (xy 146.064191 83.549534) (xy 151.290942 83.557469)
			)
		)
	)
	(zone
		(net 5)
		(net_name "GND")
		(layer "F.Cu")
		(hatch edge 0.508)
		(connect_pads yes
			(clearance 0.2)
		)
		(min_thickness 0.1)
		(filled_areas_thickness no)
		(fill yes
			(thermal_gap 0.5)
			(thermal_bridge_width 0.5)
		)
		(polygon
			(pts
				(xy 130.25 129.875) (xy 111.715738 129.876406) (xy 111.714135 124.349409) (xy 121.998397 124.348207)
				(xy 122.000057 123.200164) (xy 124.500057 123.19996) (xy 124.5 127.6) (xy 130.25 127.6)
			)
		)
	)
	(zone
		(net 224)
		(net_name "VIN")
		(layer "F.Cu")
		(hatch edge 0.508)
		(connect_pads yes
			(clearance 0.2)
		)
		(min_thickness 0.254)
		(filled_areas_thickness no)
		(fill yes
			(thermal_gap 0.508)
			(thermal_bridge_width 0.508)
		)
		(polygon
			(pts
				(xy 113.4 113.775) (xy 111.9 113.775) (xy 111.6 113.975) (xy 111.6 114.975) (xy 111.8 115.175) (xy 112.8 115.175)
				(xy 112.8 115.775) (xy 111.4 115.775) (xy 110.5 114.875) (xy 108.4 114.875) (xy 108.4 112.275) (xy 113.4 112.275)
			)
		)
	)
	(zone
		(net 42)
		(net_name "Net-(IC2-SW)")
		(layer "F.Cu")
		(hatch edge 0.508)
		(connect_pads yes
			(clearance 0.2)
		)
		(min_thickness 0.1)
		(filled_areas_thickness no)
		(fill yes
			(thermal_gap 0.5)
			(thermal_bridge_width 0.5)
		)
		(polygon
			(pts
				(xy 130.15 114.6) (xy 130.15 127.247157) (xy 124.9 127.247157) (xy 124.9 121.4) (xy 119.85 116.35)
				(xy 119.75 116.35) (xy 118.1 116.35) (xy 117.5 115.75) (xy 115.811328 115.747157) (xy 115.811328 115.247157)
				(xy 117.5 115.25) (xy 118.15 114.6)
			)
		)
	)
	(zone
		(net 463)
		(net_name "VCC5V0_INT")
		(layer "F.Cu")
		(hatch edge 0.508)
		(connect_pads yes
			(clearance 0.125)
		)
		(min_thickness 0.125)
		(filled_areas_thickness no)
		(fill yes
			(thermal_gap 0.508)
			(thermal_bridge_width 0.508)
			(smoothing fillet)
			(radius 0.125)
		)
		(polygon
			(pts
				(xy 184.45 115.41) (xy 186.525 115.41) (xy 186.525 115.785) (xy 185.1 115.785) (xy 185.1 117.11)
				(xy 183.75 117.11) (xy 183.75 115.31) (xy 184.45 115.285)
			)
		)
	)
	(zone
		(net 641)
		(net_name "1V8_DDR")
		(layer "F.Cu")
		(hatch edge 0.508)
		(priority 1)
		(connect_pads yes
			(clearance 0.15)
		)
		(min_thickness 0.15)
		(filled_areas_thickness no)
		(fill yes
			(thermal_gap 0.508)
			(thermal_bridge_width 0.508)
			(smoothing fillet)
			(radius 0.125)
		)
		(polygon
			(pts
				(xy 147.95 71.6) (xy 145.6 71.6) (xy 145.6 67) (xy 147.95 67)
			)
		)
	)
	(zone
		(net 5)
		(net_name "GND")
		(layer "F.Cu")
		(hatch edge 0.508)
		(priority 2)
		(connect_pads yes
			(clearance 0.15)
		)
		(min_thickness 0.15)
		(filled_areas_thickness no)
		(fill yes
			(thermal_gap 0.508)
			(thermal_bridge_width 0.508)
			(smoothing fillet)
			(radius 0.125)
		)
		(polygon
			(pts
				(xy 129.5 71.7) (xy 129.2 72) (xy 129.2 79.8) (xy 116.8 79.8) (xy 116.8 77.3) (xy 117.1 77) (xy 117.1 69.6)
				(xy 129.5 69.6)
			)
		)
	)
	(zone
		(net 5)
		(net_name "GND")
		(layer "F.Cu")
		(hatch edge 0.508)
		(connect_pads yes
			(clearance 0.125)
		)
		(min_thickness 0.254)
		(filled_areas_thickness no)
		(fill yes
			(thermal_gap 0.508)
			(thermal_bridge_width 0.508)
			(smoothing fillet)
			(radius 0.125)
		)
		(polygon
			(pts
				(xy 141.1 63.1) (xy 133.8 63.1) (xy 133.8 61.3) (xy 136.3 61.3) (xy 136.3 60.4) (xy 136.7 60.4)
				(xy 136.7 61.3) (xy 141.1 61.3)
			)
		)
	)
	(zone
		(net 460)
		(net_name "1V8_SYS")
		(layer "F.Cu")
		(hatch edge 0.508)
		(priority 1)
		(connect_pads yes
			(clearance 0.15)
		)
		(min_thickness 0.15)
		(filled_areas_thickness no)
		(fill yes
			(thermal_gap 0.508)
			(thermal_bridge_width 0.508)
			(smoothing fillet)
			(radius 0.125)
		)
		(polygon
			(pts
				(xy 134.7 69.3) (xy 132.3 69.3) (xy 132.3 66.3) (xy 134.7 66.3)
			)
		)
	)
	(zone
		(net 66)
		(net_name "VDDQ")
		(layer "F.Cu")
		(hatch edge 0.508)
		(priority 1)
		(connect_pads yes
			(clearance 0.15)
		)
		(min_thickness 0.15)
		(filled_areas_thickness no)
		(fill yes
			(thermal_gap 0.508)
			(thermal_bridge_width 0.508)
			(smoothing fillet)
			(radius 0.125)
		)
		(polygon
			(pts
				(xy 181.45 73.2) (xy 180.1 73.2) (xy 180.1 69.7) (xy 181.45 69.7)
			)
		)
	)
	(zone
		(net 587)
		(net_name "/Supply/1V1_REG")
		(layer "F.Cu")
		(hatch edge 0.508)
		(priority 2)
		(connect_pads yes
			(clearance 0.15)
		)
		(min_thickness 0.15)
		(filled_areas_thickness no)
		(fill yes
			(thermal_gap 0.508)
			(thermal_bridge_width 0.508)
			(smoothing fillet)
			(radius 0.125)
		)
		(polygon
			(pts
				(xy 125.94 86.075) (xy 123.29 86.075) (xy 123.29 80.625) (xy 125.94 80.625)
			)
		)
	)
	(zone
		(net 5)
		(net_name "GND")
		(layer "F.Cu")
		(hatch edge 0.508)
		(connect_pads yes
			(clearance 0.125)
		)
		(min_thickness 0.125)
		(filled_areas_thickness no)
		(fill yes
			(thermal_gap 0.508)
			(thermal_bridge_width 0.508)
			(smoothing fillet)
			(radius 0.125)
		)
		(polygon
			(pts
				(xy 123.2825 94.85) (xy 123.2825 97.8) (xy 126.5825 97.8) (xy 126.5825 102.1) (xy 126.7825 102.1)
				(xy 126.7825 102.8) (xy 124.8575 102.8) (xy 124.8575 101.5) (xy 125.9825 101.5) (xy 125.9825 100.81)
				(xy 125.0425 100.81) (xy 125.0425 100.45) (xy 125.9825 100.45) (xy 125.9825 98.95) (xy 122.0325 98.95)
				(xy 122.0325 94.85)
			)
		)
	)
	(zone
		(net 641)
		(net_name "1V8_DDR")
		(layer "F.Cu")
		(hatch edge 0.508)
		(priority 1)
		(connect_pads yes
			(clearance 0.15)
		)
		(min_thickness 0.15)
		(filled_areas_thickness no)
		(fill yes
			(thermal_gap 0.508)
			(thermal_bridge_width 0.508)
			(smoothing fillet)
			(radius 0.125)
		)
		(polygon
			(pts
				(xy 184.2 71.6) (xy 181.6 71.6) (xy 181.6 67) (xy 184.2 67)
			)
		)
	)
	(zone
		(net 463)
		(net_name "VCC5V0_INT")
		(layer "F.Cu")
		(hatch edge 0.508)
		(connect_pads yes
			(clearance 0.125)
		)
		(min_thickness 0.125)
		(filled_areas_thickness no)
		(fill yes
			(thermal_gap 0.508)
			(thermal_bridge_width 0.508)
			(smoothing fillet)
			(radius 0.125)
		)
		(polygon
			(pts
				(xy 127.2075 102.1) (xy 127.2075 100.025) (xy 127.5825 100.025) (xy 127.5825 101.45) (xy 128.9075 101.45)
				(xy 128.9075 102.8) (xy 127.0825 102.81) (xy 127.0825 102.1)
			)
		)
	)
	(zone
		(net 224)
		(net_name "VIN")
		(layer "F.Cu")
		(hatch edge 0.508)
		(connect_pads yes
			(clearance 0.2)
		)
		(min_thickness 0.1)
		(filled_areas_thickness no)
		(fill yes
			(thermal_gap 0.5)
			(thermal_bridge_width 0.5)
		)
		(polygon
			(pts
				(xy 119.9 56) (xy 119.9 55) (xy 119.9 54.8) (xy 119.9 53.7) (xy 122.9 53.7) (xy 122.9 56)
			)
		)
	)
	(zone
		(net 5)
		(net_name "GND")
		(layer "F.Cu")
		(hatch edge 0.508)
		(connect_pads yes
			(clearance 0.125)
		)
		(min_thickness 0.125)
		(filled_areas_thickness no)
		(fill yes
			(thermal_gap 0.508)
			(thermal_bridge_width 0.508)
			(smoothing fillet)
			(radius 0.125)
		)
		(polygon
			(pts
				(xy 123 83.375) (xy 123 86.325) (xy 126.55 86.325) (xy 126.55 90.625) (xy 126.75 90.625) (xy 126.75 91.325)
				(xy 124.825 91.325) (xy 124.825 90.025) (xy 125.95 90.025) (xy 125.95 89.335) (xy 125.01 89.335)
				(xy 125.01 88.975) (xy 125.95 88.975) (xy 125.95 87.475) (xy 121.65 87.475) (xy 121.65 83.375)
			)
		)
	)
	(zone
		(net 586)
		(net_name "/Supply/1V2_SW")
		(layer "F.Cu")
		(hatch edge 0.508)
		(connect_pads yes
			(clearance 0.125)
		)
		(min_thickness 0.125)
		(filled_areas_thickness no)
		(fill yes
			(thermal_gap 0.508)
			(thermal_bridge_width 0.508)
			(smoothing fillet)
			(radius 0.125)
		)
		(polygon
			(pts
				(xy 191.5 115.835) (xy 188.8 115.835) (xy 188.7 115.735) (xy 188.025 115.735) (xy 187.575 115.285)
				(xy 185.825 115.285) (xy 185.825 114.91) (xy 191.5 114.91)
			)
		)
	)
	(zone
		(net 459)
		(net_name "3V3_SYS")
		(layer "F.Cu")
		(hatch edge 0.508)
		(priority 2)
		(connect_pads yes
			(clearance 0.15)
		)
		(min_thickness 0.15)
		(filled_areas_thickness no)
		(fill yes
			(thermal_gap 0.508)
			(thermal_bridge_width 0.508)
			(smoothing fillet)
			(radius 0.125)
		)
		(polygon
			(pts
				(xy 117.975 94.45) (xy 114.775 94.45) (xy 114.775 93.05) (xy 117.975 93.05)
			)
		)
	)
	(zone
		(net 460)
		(net_name "1V8_SYS")
		(layer "F.Cu")
		(hatch edge 0.508)
		(priority 2)
		(connect_pads yes
			(clearance 0.15)
		)
		(min_thickness 0.15)
		(filled_areas_thickness no)
		(fill yes
			(thermal_gap 0.508)
			(thermal_bridge_width 0.508)
			(smoothing fillet)
			(radius 0.125)
		)
		(polygon
			(pts
				(xy 117.397806 82.975) (xy 114.197806 82.975) (xy 114.197806 80.375) (xy 117.397806 80.375)
			)
		)
	)
	(zone
		(net 602)
		(net_name "1V2_SYS")
		(layer "F.Cu")
		(hatch edge 0.508)
		(connect_pads yes
			(clearance 0.2)
		)
		(min_thickness 0.1)
		(filled_areas_thickness no)
		(fill yes
			(thermal_gap 0.5)
			(thermal_bridge_width 0.5)
			(smoothing fillet)
			(radius 0.25)
		)
		(polygon
			(pts
				(xy 193.5 111.1) (xy 192.1 111.1) (xy 192.1 108.2) (xy 193.5 108.2)
			)
		)
	)
	(zone
		(net 463)
		(net_name "VCC5V0_INT")
		(layer "F.Cu")
		(hatch edge 0.508)
		(connect_pads yes
			(clearance 0.125)
		)
		(min_thickness 0.125)
		(filled_areas_thickness no)
		(fill yes
			(thermal_gap 0.508)
			(thermal_bridge_width 0.508)
			(smoothing fillet)
			(radius 0.125)
		)
		(polygon
			(pts
				(xy 114.922806 90.625) (xy 114.922806 88.55) (xy 115.297806 88.55) (xy 115.297806 89.975) (xy 116.572806 89.975)
				(xy 116.572806 91.325) (xy 114.797806 91.325) (xy 114.797806 90.625)
			)
		)
	)
	(zone
		(net 224)
		(net_name "VIN")
		(layer "F.Cu")
		(hatch edge 0.508)
		(connect_pads yes
			(clearance 0.125)
		)
		(min_thickness 0.125)
		(filled_areas_thickness no)
		(fill yes
			(thermal_gap 0.508)
			(thermal_bridge_width 0.508)
			(smoothing fillet)
			(radius 0.125)
		)
		(polygon
			(pts
				(xy 111.55 123.9) (xy 110.95 124.5) (xy 110.95 129.5) (xy 108.4 129.5) (xy 108.396117 121.062867)
				(xy 111.546073 121.067936)
			)
		)
	)
	(zone
		(net 550)
		(net_name "VDD1V1")
		(layer "F.Cu")
		(hatch edge 0.508)
		(connect_pads yes
			(clearance 0.2)
		)
		(min_thickness 0.1)
		(filled_areas_thickness no)
		(fill yes
			(thermal_gap 0.5)
			(thermal_bridge_width 0.5)
		)
		(polygon
			(pts
				(xy 133.522157 55.738672) (xy 133.522157 55.188672) (xy 127.229314 55.188672) (xy 127.229314 55.331344)
				(xy 126.629314 55.331344) (xy 126.647157 52.938672) (xy 136.397157 52.938672) (xy 136.397157 54.2)
				(xy 136.397157 55.738672)
			)
		)
	)
	(zone
		(net 551)
		(net_name "/Supply/VDD1V8")
		(layer "F.Cu")
		(hatch edge 0.508)
		(priority 2)
		(connect_pads yes
			(clearance 0.15)
		)
		(min_thickness 0.15)
		(filled_areas_thickness no)
		(fill yes
			(thermal_gap 0.508)
			(thermal_bridge_width 0.508)
			(smoothing fillet)
			(radius 0.125)
		)
		(polygon
			(pts
				(xy 131.75 68.8) (xy 128.85 68.8) (xy 128.85 63.5) (xy 131.75 63.5)
			)
		)
	)
	(zone
		(net 463)
		(net_name "VCC5V0_INT")
		(layer "F.Cu")
		(hatch edge 0.508)
		(connect_pads yes
			(clearance 0.125)
		)
		(min_thickness 0.125)
		(filled_areas_thickness no)
		(fill yes
			(thermal_gap 0.508)
			(thermal_bridge_width 0.508)
			(smoothing fillet)
			(radius 0.125)
		)
		(polygon
			(pts
				(xy 127.175 90.625) (xy 127.175 88.55) (xy 127.55 88.55) (xy 127.55 89.975) (xy 128.87 89.975) (xy 128.875 91.325)
				(xy 127.07 91.325) (xy 127.07 90.625)
			)
		)
	)
	(zone
		(net 273)
		(net_name "1V1_DDR")
		(layer "F.Cu")
		(hatch edge 0.508)
		(priority 1)
		(connect_pads yes
			(clearance 0.15)
		)
		(min_thickness 0.15)
		(filled_areas_thickness no)
		(fill yes
			(thermal_gap 0.508)
			(thermal_bridge_width 0.508)
			(smoothing fillet)
			(radius 0.125)
		)
		(polygon
			(pts
				(xy 183.75 79.75) (xy 179.85 79.75) (xy 179.85 75.5) (xy 183.75 75.5)
			)
		)
	)
	(zone
		(net 461)
		(net_name "1V1_SYS")
		(layer "F.Cu")
		(hatch edge 0.508)
		(priority 1)
		(connect_pads yes
			(clearance 0.15)
		)
		(min_thickness 0.15)
		(filled_areas_thickness no)
		(fill yes
			(thermal_gap 0.508)
			(thermal_bridge_width 0.508)
			(smoothing fillet)
			(radius 0.125)
		)
		(polygon
			(pts
				(xy 140.4 61.15) (xy 136.85 61.15) (xy 136.85 60.4) (xy 139.2 60.4) (xy 139.2 58.3) (xy 133.7 58.3)
				(xy 133.7 56.5) (xy 140.4 56.5)
			)
		)
	)
	(zone
		(net 576)
		(net_name "/Supply/3V3_REG")
		(layer "F.Cu")
		(hatch edge 0.508)
		(connect_pads yes
			(clearance 0.125)
		)
		(min_thickness 0.125)
		(filled_areas_thickness no)
		(fill yes
			(thermal_gap 0.508)
			(thermal_bridge_width 0.508)
			(smoothing fillet)
			(radius 0.125)
		)
		(polygon
			(pts
				(xy 112.675012 94.897437) (xy 112.675 93.05) (xy 113.975 93.05) (xy 113.975 97.6) (xy 111.875 97.6)
				(xy 111.875 94.9)
			)
		)
	)
	(zone
		(net 628)
		(net_name "/Supply/VDD1_SW")
		(layer "F.Cu")
		(hatch edge 0.508)
		(connect_pads yes
			(clearance 0.2)
		)
		(min_thickness 0.1)
		(filled_areas_thickness no)
		(fill yes
			(thermal_gap 0.5)
			(thermal_bridge_width 0.5)
		)
		(polygon
			(pts
				(xy 126.647157 61.813672) (xy 126.647157 57.438672) (xy 127.272157 57.438672) (xy 127.272157 58.938672)
				(xy 132.272157 58.938672) (xy 132.272157 61.813672)
			)
		)
	)
	(zone
		(net 625)
		(net_name "/Supply/VDD2_SW")
		(layer "F.Cu")
		(hatch edge 0.508)
		(priority 1)
		(connect_pads yes
			(clearance 0.15)
		)
		(min_thickness 0.1)
		(filled_areas_thickness no)
		(fill yes
			(thermal_gap 0.5)
			(thermal_bridge_width 0.5)
		)
		(polygon
			(pts
				(xy 127.522157 58.438672) (xy 127.522157 56.688672) (xy 126.397157 56.688672) (xy 126.397157 56.188672)
				(xy 133.129314 56.177344) (xy 133.144314 58.437344)
			)
		)
	)
	(zone
		(net 55)
		(net_name "Net-(C141-Pad1)")
		(layer "F.Cu")
		(hatch edge 0.508)
		(priority 2)
		(connect_pads yes
			(clearance 0.15)
		)
		(min_thickness 0.15)
		(filled_areas_thickness no)
		(fill yes
			(thermal_gap 0.508)
			(thermal_bridge_width 0.508)
			(smoothing fillet)
			(radius 0.125)
		)
		(polygon
			(pts
				(xy 121.9 110.3) (xy 128.7 110.3) (xy 128.7 113.9) (xy 120.4 113.9) (xy 120.4 108) (xy 121.9 108)
			)
		)
	)
	(zone
		(net 5)
		(net_name "GND")
		(layer "F.Cu")
		(hatch edge 0.508)
		(connect_pads yes
			(clearance 0.2)
		)
		(min_thickness 0.1)
		(filled_areas_thickness no)
		(fill yes
			(thermal_gap 0.5)
			(thermal_bridge_width 0.5)
		)
		(polygon
			(pts
				(xy 123.2 58.9) (xy 119.9 58.9) (xy 119.9 56.3) (xy 122.9 56.3) (xy 122.905686 56.722656) (xy 126.205686 56.722656)
				(xy 126.405686 56.922656) (xy 127.305686 56.922656) (xy 127.305686 57.222656) (xy 126.205686 57.222656)
				(xy 126.1 57.1) (xy 123.9 57.1) (xy 123.2 57.8)
			)
		)
	)
	(zone
		(net 633)
		(net_name "/Supply/0V6_REG")
		(layer "F.Cu")
		(hatch edge 0.508)
		(connect_pads yes
			(clearance 0.125)
		)
		(min_thickness 0.254)
		(filled_areas_thickness no)
		(fill yes
			(thermal_gap 0.508)
			(thermal_bridge_width 0.508)
			(smoothing fillet)
			(radius 0.125)
		)
		(polygon
			(pts
				(xy 142.9 65.1) (xy 137.2 65.1) (xy 137.2 64.5) (xy 136.8 64.1) (xy 136.8 63.25) (xy 142.9 63.25)
			)
		)
	)
	(zone
		(net 582)
		(net_name "/Supply/1V0_SW")
		(layer "F.Cu")
		(hatch edge 0.508)
		(connect_pads yes
			(clearance 0.125)
		)
		(min_thickness 0.125)
		(filled_areas_thickness no)
		(fill yes
			(thermal_gap 0.508)
			(thermal_bridge_width 0.508)
			(smoothing fillet)
			(radius 0.125)
		)
		(polygon
			(pts
				(xy 127.6325 95.05) (xy 127.6325 97.75) (xy 127.5325 97.85) (xy 127.5325 98.525) (xy 127.0825 98.975)
				(xy 127.0825 100.725) (xy 126.7075 100.725) (xy 126.7075 95.05)
			)
		)
	)
	(zone
		(net 584)
		(net_name "/Supply/1V8_SW")
		(layer "F.Cu")
		(hatch edge 0.508)
		(connect_pads yes
			(clearance 0.125)
		)
		(min_thickness 0.125)
		(filled_areas_thickness no)
		(fill yes
			(thermal_gap 0.508)
			(thermal_bridge_width 0.508)
			(smoothing fillet)
			(radius 0.125)
		)
		(polygon
			(pts
				(xy 115.347806 83.575) (xy 115.347806 86.275) (xy 115.247806 86.375) (xy 115.247806 87.05) (xy 114.797806 87.5)
				(xy 114.797806 89.25) (xy 114.422806 89.25) (xy 114.422806 83.575)
			)
		)
	)
	(zone
		(net 583)
		(net_name "/Supply/1V8_REG")
		(layer "F.Cu")
		(hatch edge 0.508)
		(connect_pads yes
			(clearance 0.125)
		)
		(min_thickness 0.125)
		(filled_areas_thickness no)
		(fill yes
			(thermal_gap 0.508)
			(thermal_bridge_width 0.508)
			(smoothing fillet)
			(radius 0.125)
		)
		(polygon
			(pts
				(xy 112.097806 83.425) (xy 112.097806 81.575) (xy 113.397806 81.575) (xy 113.397806 86.125) (xy 111.297806 86.125)
				(xy 111.297806 83.425)
			)
		)
	)
	(zone
		(net 640)
		(net_name "0V6_DDR")
		(layer "F.Cu")
		(hatch edge 0.508)
		(priority 1)
		(connect_pads yes
			(clearance 0.15)
		)
		(min_thickness 0.15)
		(filled_areas_thickness no)
		(fill yes
			(thermal_gap 0.508)
			(thermal_bridge_width 0.508)
			(smoothing fillet)
			(radius 0.125)
		)
		(polygon
			(pts
				(xy 149.55 64.6) (xy 143.65 64.6) (xy 143.65 63.2) (xy 146.85 63.2) (xy 146.85 51.3) (xy 132 51.3)
				(xy 132 48.6) (xy 149.55 48.6)
			)
		)
	)
	(zone
		(net 5)
		(net_name "GND")
		(layer "F.Cu")
		(hatch edge 0.508)
		(priority 1)
		(connect_pads yes
			(clearance 0.15)
		)
		(min_thickness 0.15)
		(filled_areas_thickness no)
		(fill yes
			(thermal_gap 0.508)
			(thermal_bridge_width 0.508)
			(smoothing fillet)
			(radius 0.125)
		)
		(polygon
			(pts
				(xy 119.75 114) (xy 118 114) (xy 118 110) (xy 119.75 110)
			)
		)
	)
	(zone
		(net 66)
		(net_name "VDDQ")
		(layer "F.Cu")
		(hatch edge 0.508)
		(priority 1)
		(connect_pads yes
			(clearance 0.15)
		)
		(min_thickness 0.15)
		(filled_areas_thickness no)
		(fill yes
			(thermal_gap 0.508)
			(thermal_bridge_width 0.508)
			(smoothing fillet)
			(radius 0.125)
		)
		(polygon
			(pts
				(xy 149.45 73.2) (xy 148.125 73.2) (xy 148.125 69.7) (xy 149.45 69.7)
			)
		)
	)
	(zone
		(net 463)
		(net_name "VCC5V0_INT")
		(layer "F.Cu")
		(hatch edge 0.508)
		(connect_pads yes
			(clearance 0.2)
		)
		(min_thickness 0.1)
		(filled_areas_thickness no)
		(fill yes
			(thermal_gap 0.5)
			(thermal_bridge_width 0.5)
		)
		(polygon
			(pts
				(xy 126.9 63.691932) (xy 126.9 65.9) (xy 125.1 65.9) (xy 125.1 63.8) (xy 125.6 63.3) (xy 125.647157 61.938672)
				(xy 125.647157 57.438672) (xy 126.397157 57.438672) (xy 126.419282 63.2) (xy 126.5 63.3)
			)
		)
	)
	(zone
		(net 463)
		(net_name "VCC5V0_INT")
		(layer "F.Cu")
		(hatch edge 0.508)
		(connect_pads yes
			(clearance 0.125)
		)
		(min_thickness 0.125)
		(filled_areas_thickness no)
		(fill yes
			(thermal_gap 0.508)
			(thermal_bridge_width 0.508)
			(smoothing fillet)
			(radius 0.125)
		)
		(polygon
			(pts
				(xy 115.5 102.1) (xy 115.5 100.025) (xy 115.875 100.025) (xy 115.875 101.45) (xy 117.2 101.45) (xy 117.2 102.8)
				(xy 115.425 102.8) (xy 115.425 102.1)
			)
		)
	)
	(zone
		(net 273)
		(net_name "1V1_DDR")
		(layer "F.Cu")
		(hatch edge 0.508)
		(priority 1)
		(connect_pads yes
			(clearance 0.15)
		)
		(min_thickness 0.15)
		(filled_areas_thickness no)
		(fill yes
			(thermal_gap 0.508)
			(thermal_bridge_width 0.508)
			(smoothing fillet)
			(radius 0.125)
		)
		(polygon
			(pts
				(xy 143.75 79.8) (xy 139.85 79.8) (xy 139.85 75.55) (xy 143.75 75.55)
			)
		)
	)
	(zone
		(net 589)
		(net_name "/Supply/1V2_REG")
		(layer "F.Cu")
		(hatch edge 0.508)
		(connect_pads yes
			(clearance 0.125)
		)
		(min_thickness 0.125)
		(filled_areas_thickness no)
		(fill yes
			(thermal_gap 0.508)
			(thermal_bridge_width 0.508)
			(smoothing fillet)
			(radius 0.125)
		)
		(polygon
			(pts
				(xy 193.45 113) (xy 193.45 113.15) (xy 193.45 113.885) (xy 188.95 113.885) (xy 188.95 111.785) (xy 193.45 111.785)
			)
		)
	)
	(zone
		(net 5)
		(net_name "GND")
		(layer "F.Cu")
		(hatch edge 0.508)
		(connect_pads yes
			(clearance 0.125)
		)
		(min_thickness 0.125)
		(filled_areas_thickness no)
		(fill yes
			(thermal_gap 0.508)
			(thermal_bridge_width 0.508)
			(smoothing fillet)
			(radius 0.125)
		)
		(polygon
			(pts
				(xy 191.7 111.485) (xy 188.75 111.485) (xy 188.75 114.785) (xy 184.45 114.785) (xy 184.45 114.985)
				(xy 183.75 114.985) (xy 183.75 113.06) (xy 185.05 113.06) (xy 185.05 114.185) (xy 185.74 114.185)
				(xy 185.74 113.245) (xy 186.1 113.245) (xy 186.1 114.185) (xy 187.6 114.185) (xy 187.6 110.185)
				(xy 191.7 110.185)
			)
		)
	)
	(zone
		(net 575)
		(net_name "/Supply/3V3_SW")
		(layer "F.Cu")
		(hatch edge 0.508)
		(connect_pads yes
			(clearance 0.125)
		)
		(min_thickness 0.125)
		(filled_areas_thickness no)
		(fill yes
			(thermal_gap 0.508)
			(thermal_bridge_width 0.508)
			(smoothing fillet)
			(radius 0.125)
		)
		(polygon
			(pts
				(xy 115.925 95.05) (xy 115.925 97.75) (xy 115.825 97.85) (xy 115.825 98.525) (xy 115.375 98.975)
				(xy 115.375 100.725) (xy 115 100.725) (xy 115 95.05)
			)
		)
	)
	(zone
		(net 5)
		(net_name "GND")
		(layer "F.Cu")
		(hatch edge 0.508)
		(priority 2)
		(connect_pads yes
			(clearance 0.15)
		)
		(min_thickness 0.15)
		(filled_areas_thickness no)
		(fill yes
			(thermal_gap 0.508)
			(thermal_bridge_width 0.508)
			(smoothing fillet)
			(radius 0.125)
		)
		(polygon
			(pts
				(xy 115.65 120.25) (xy 112.95 120.25) (xy 112.95 114.75) (xy 115.65 114.75)
			)
		)
	)
	(zone
		(net 588)
		(net_name "/Supply/1V0_REG")
		(layer "F.Cu")
		(hatch edge 0.508)
		(connect_pads yes
			(clearance 0.125)
		)
		(min_thickness 0.125)
		(filled_areas_thickness no)
		(fill yes
			(thermal_gap 0.508)
			(thermal_bridge_width 0.508)
			(smoothing fillet)
			(radius 0.125)
		)
		(polygon
			(pts
				(xy 124.3825 94.9) (xy 124.3825 93.05) (xy 125.6825 93.05) (xy 125.6825 97.6) (xy 123.5825 97.6)
				(xy 123.5825 94.9)
			)
		)
	)
	(zone
		(net 5)
		(net_name "GND")
		(layer "F.Cu")
		(hatch edge 0.508)
		(priority 2)
		(connect_pads yes
			(clearance 0.2)
		)
		(min_thickness 0.254)
		(filled_areas_thickness no)
		(fill yes
			(thermal_gap 0.508)
			(thermal_bridge_width 0.508)
		)
		(polygon
			(pts
				(xy 113.4 111.675) (xy 108.4 111.675) (xy 108.4 109.175) (xy 113.4 109.175)
			)
		)
	)
	(zone
		(net 579)
		(net_name "/Supply/1V1_SW")
		(layer "F.Cu")
		(hatch edge 0.508)
		(connect_pads yes
			(clearance 0.125)
		)
		(min_thickness 0.125)
		(filled_areas_thickness no)
		(fill yes
			(thermal_gap 0.508)
			(thermal_bridge_width 0.508)
			(smoothing fillet)
			(radius 0.125)
		)
		(polygon
			(pts
				(xy 128.05 82.615) (xy 128.05 86.275) (xy 127.79 86.475) (xy 127.79 87.225) (xy 127.05 87.225) (xy 127.05 89.275)
				(xy 126.68 89.275) (xy 126.68 82.615)
			)
		)
	)
	(zone
		(net 461)
		(net_name "1V1_SYS")
		(layer "F.Cu")
		(hatch edge 0.508)
		(priority 1)
		(connect_pads yes
			(clearance 0.15)
		)
		(min_thickness 0.15)
		(filled_areas_thickness no)
		(fill yes
			(thermal_gap 0.508)
			(thermal_bridge_width 0.508)
			(smoothing fillet)
			(radius 0.125)
		)
		(polygon
			(pts
				(xy 132 83) (xy 129.35 83) (xy 129.35 82) (xy 126.65 82) (xy 126.65 80.6) (xy 132 80.6)
			)
		)
	)
	(zone
		(net 463)
		(net_name "VCC5V0_INT")
		(layer "F.Cu")
		(hatch edge 0.508)
		(priority 2)
		(connect_pads yes
			(clearance 0.15)
		)
		(min_thickness 0.15)
		(filled_areas_thickness no)
		(fill yes
			(thermal_gap 0.508)
			(thermal_bridge_width 0.508)
			(smoothing fillet)
			(radius 0.125)
		)
		(polygon
			(pts
				(xy 116.58 91.6) (xy 127.225 91.6) (xy 127.225 90.2) (xy 128.925 90.2) (xy 128.925 92.7) (xy 121.8 92.7)
				(xy 121.8 102.9) (xy 127.1 102.9) (xy 127.1 102.1) (xy 128.9 102.1) (xy 128.9 102.9) (xy 128.9 105)
				(xy 126 105) (xy 126 109.7) (xy 122.6 109.7) (xy 122.6 105) (xy 115.43 105) (xy 115.43 101.6) (xy 117.2 101.6)
				(xy 117.2 102.8) (xy 119.7 102.8) (xy 119.7 92.7) (xy 114.885 92.7) (xy 114.885 90.2) (xy 116.58 90.2)
			)
		)
	)
	(zone
		(net 465)
		(net_name "1V0_SYS")
		(layer "F.Cu")
		(hatch edge 0.508)
		(priority 2)
		(connect_pads yes
			(clearance 0.15)
		)
		(min_thickness 0.15)
		(filled_areas_thickness no)
		(fill yes
			(thermal_gap 0.508)
			(thermal_bridge_width 0.508)
			(smoothing fillet)
			(radius 0.125)
		)
		(polygon
			(pts
				(xy 129.6825 94.45) (xy 126.4825 94.45) (xy 126.4825 93.05) (xy 129.6825 93.05)
			)
		)
	)
	(zone
		(net 5)
		(net_name "GND")
		(layer "F.Cu")
		(hatch edge 0.508)
		(priority 1)
		(connect_pads yes
			(clearance 0.15)
		)
		(min_thickness 0.15)
		(filled_areas_thickness no)
		(fill yes
			(thermal_gap 0.508)
			(thermal_bridge_width 0.508)
			(smoothing fillet)
			(radius 0.125)
		)
		(polygon
			(pts
				(xy 138.2 55.5) (xy 136.9 55.5) (xy 136.9 52.5) (xy 126.9 52.5) (xy 126.9 51.5) (xy 138.2 51.5)
			)
		)
	)
	(zone
		(net 627)
		(net_name "/Supply/VDDQ_0V6")
		(layer "F.Cu")
		(hatch edge 0.508)
		(priority 1)
		(connect_pads yes
			(clearance 0.15)
		)
		(min_thickness 0.15)
		(filled_areas_thickness no)
		(fill yes
			(thermal_gap 0.508)
			(thermal_bridge_width 0.508)
			(smoothing fillet)
			(radius 0.125)
		)
		(polygon
			(pts
				(xy 131.2 51.3) (xy 126.55 51.3) (xy 126.55 53.5) (xy 126.45 53.6) (xy 126.45 55.35) (xy 126.1 55.35)
				(xy 126.1 53.9) (xy 125.8 53.6) (xy 125.8 49.8) (xy 131.2 49.8)
			)
		)
	)
	(zone
		(net 5)
		(net_name "GND")
		(layer "F.Cu")
		(hatch edge 0.508)
		(connect_pads yes
			(clearance 0.125)
		)
		(min_thickness 0.125)
		(filled_areas_thickness no)
		(fill yes
			(thermal_gap 0.508)
			(thermal_bridge_width 0.508)
			(smoothing fillet)
			(radius 0.125)
		)
		(polygon
			(pts
				(xy 110.997806 83.375) (xy 110.997806 86.325) (xy 114.297806 86.325) (xy 114.297806 90.625) (xy 114.497806 90.625)
				(xy 114.497806 91.325) (xy 112.572806 91.325) (xy 112.572806 90.025) (xy 113.697806 90.025) (xy 113.697806 89.335)
				(xy 112.757806 89.335) (xy 112.757806 88.975) (xy 113.697806 88.975) (xy 113.697806 87.475) (xy 109.947806 87.475)
				(xy 109.947806 83.375)
			)
		)
	)
	(zone
		(net 5)
		(net_name "GND")
		(layer "F.Cu")
		(hatch edge 0.508)
		(connect_pads yes
			(clearance 0.125)
		)
		(min_thickness 0.125)
		(filled_areas_thickness no)
		(fill yes
			(thermal_gap 0.508)
			(thermal_bridge_width 0.508)
			(smoothing fillet)
			(radius 0.125)
		)
		(polygon
			(pts
				(xy 111.575 94.85) (xy 111.575 97.8) (xy 114.875 97.8) (xy 114.875 102.1) (xy 115.075 102.1) (xy 115.075 102.8)
				(xy 113.15 102.8) (xy 113.15 101.5) (xy 114.275 101.5) (xy 114.275 100.81) (xy 113.335 100.81) (xy 113.335 100.45)
				(xy 114.275 100.45) (xy 114.275 98.95) (xy 110.225 98.95) (xy 110.225 94.85)
			)
		)
	)
	(zone
		(net 460)
		(net_name "1V8_SYS")
		(layers "F.Cu" "B.Cu")
		(hatch edge 0.508)
		(priority 1)
		(connect_pads yes
			(clearance 0.15)
		)
		(min_thickness 0.15)
		(filled_areas_thickness no)
		(fill yes
			(thermal_gap 0.508)
			(thermal_bridge_width 0.508)
			(smoothing fillet)
			(radius 0.125)
		)
		(polygon
			(pts
				(xy 136.2 69.4) (xy 133.45 69.4) (xy 133.45 66.3) (xy 136.2 66.3)
			)
		)
	)
	(zone
		(net 461)
		(net_name "1V1_SYS")
		(layer "B.Cu")
		(hatch edge 0.508)
		(priority 1)
		(connect_pads yes
			(clearance 0.15)
		)
		(min_thickness 0.15)
		(filled_areas_thickness no)
		(fill yes
			(thermal_gap 0.508)
			(thermal_bridge_width 0.508)
			(smoothing fillet)
			(radius 0.125)
		)
		(polygon
			(pts
				(xy 139.4 58.3) (xy 132 58.3) (xy 132 74.9) (xy 136.15 74.9) (xy 136.15 77.8) (xy 132 77.8) (xy 132 83)
				(xy 129.35 83) (xy 129.35 56.45) (xy 139.4 56.45)
			)
		)
	)
	(zone
		(net 641)
		(net_name "1V8_DDR")
		(layer "B.Cu")
		(hatch edge 0.508)
		(priority 1)
		(connect_pads yes
			(clearance 0.15)
		)
		(min_thickness 0.15)
		(filled_areas_thickness no)
		(fill yes
			(thermal_gap 0.508)
			(thermal_bridge_width 0.508)
			(smoothing fillet)
			(radius 0.125)
		)
		(polygon
			(pts
				(xy 184.2 66.5) (xy 184.2 69.4) (xy 136.4 69.5) (xy 136.4 66.5)
			)
		)
	)
	(zone
		(net 273)
		(net_name "1V1_DDR")
		(layer "B.Cu")
		(hatch edge 0.508)
		(priority 1)
		(connect_pads yes
			(clearance 0.15)
		)
		(min_thickness 0.15)
		(filled_areas_thickness no)
		(fill yes
			(thermal_gap 0.508)
			(thermal_bridge_width 0.508)
			(smoothing fillet)
			(radius 0.125)
		)
		(polygon
			(pts
				(xy 183.8 74.8) (xy 183.8 77.8) (xy 136.4 77.9) (xy 136.4 74.8)
			)
		)
	)
	(zone
		(net 5)
		(net_name "GND")
		(layer "In1.Cu")
		(hatch edge 0.508)
		(connect_pads yes
			(clearance 0.125)
		)
		(min_thickness 0.254)
		(filled_areas_thickness no)
		(fill yes
			(thermal_gap 0.508)
			(thermal_bridge_width 0.508)
		)
		(polygon
			(pts
				(xy 216.690828 135.972157) (xy 107 136) (xy 107 46) (xy 217 46)
			)
		)
	)
	(zone
		(net 0)
		(net_name "")
		(layer "F.SilkS")
		(hatch edge 0.508)
		(connect_pads yes
			(clearance 0.2)
		)
		(min_thickness 0.254)
		(filled_areas_thickness no)
		(fill yes
			(thermal_gap 0.508)
			(thermal_bridge_width 0.508)
		)
		(polygon
			(pts
				(xy 112.736328 66.66054) (xy 112.736328 79.96054) (xy 108.836328 79.96054) (xy 108.836328 66.66054)
			)
		)
	)
	(zone
		(net 5)
		(net_name "GND")
		(layer "In2.Cu")
		(hatch edge 0.508)
		(connect_pads
			(clearance 0.25)
		)
		(min_thickness 0.254)
		(filled_areas_thickness no)
		(fill yes
			(thermal_gap 0.508)
			(thermal_bridge_width 0.508)
		)
		(polygon
			(pts
				(xy 216.636328 46.397157) (xy 216.636328 135.697157) (xy 107.336328 135.697157) (xy 107.236328 46.297157)
			)
		)
	)
	(zone
		(net 0)
		(net_name "")
		(layer "In2.Cu")
		(hatch edge 0.508)
		(connect_pads
			(clearance 0)
		)
		(min_thickness 0.254)
		(filled_areas_thickness no)
		(keepout
			(tracks allowed)
			(vias allowed)
			(pads allowed)
			(copperpour not_allowed)
			(footprints allowed)
		)
		(placement
			(enabled no)
			(sheetname "")
		)
		(fill
			(thermal_gap 0.508)
			(thermal_bridge_width 0.508)
		)
		(polygon
			(pts
				(xy 171 88.4) (xy 156.6 88.4) (xy 156.6 71.4) (xy 171 71.4)
			)
		)
	)
	(zone
		(net 5)
		(net_name "GND")
		(layer "In3.Cu")
		(hatch edge 0.508)
		(connect_pads yes
			(clearance 0.15)
		)
		(min_thickness 0.1)
		(filled_areas_thickness no)
		(fill yes
			(thermal_gap 0.5)
			(thermal_bridge_width 0.5)
		)
		(polygon
			(pts
				(xy 216.875 136) (xy 107 136) (xy 107 46) (xy 217 46)
			)
		)
	)
	(zone
		(net 460)
		(net_name "1V8_SYS")
		(layer "In4.Cu")
		(hatch edge 0.508)
		(priority 3)
		(connect_pads yes
			(clearance 0.15)
		)
		(min_thickness 0.15)
		(filled_areas_thickness no)
		(fill yes
			(thermal_gap 0.508)
			(thermal_bridge_width 0.508)
			(smoothing fillet)
			(radius 0.125)
		)
		(polygon
			(pts
				(xy 147.8 98.75) (xy 164.6 98.75) (xy 164.6 90.6) (xy 172 90.6) (xy 172 85.75) (xy 181.75 85.75)
				(xy 181.761233 108.749017) (xy 115.011233 108.999017) (xy 115.25 78.2) (xy 129.4 78.2) (xy 129.4 66.1)
				(xy 134.8 66.1) (xy 134.8 78.2) (xy 147.8 78.2)
			)
		)
	)
	(zone
		(net 5)
		(net_name "GND")
		(layer "In4.Cu")
		(hatch edge 0.508)
		(connect_pads yes
			(clearance 0.15)
		)
		(min_thickness 0.2)
		(filled_areas_thickness no)
		(fill yes
			(thermal_gap 0.508)
			(thermal_bridge_width 0.508)
			(smoothing fillet)
			(radius 0.125)
		)
		(polygon
			(pts
				(xy 217 136) (xy 107 136) (xy 107 46) (xy 217 46)
			)
		)
	)
	(zone
		(net 273)
		(net_name "1V1_DDR")
		(layer "In4.Cu")
		(hatch edge 0.508)
		(priority 1)
		(connect_pads yes
			(clearance 0.15)
		)
		(min_thickness 0.15)
		(filled_areas_thickness no)
		(fill yes
			(thermal_gap 0.508)
			(thermal_bridge_width 0.508)
			(smoothing fillet)
			(radius 0.125)
		)
		(polygon
			(pts
				(xy 144.1 78.1) (xy 139.85 78.1) (xy 139.85 75.75) (xy 141.7 75.75) (xy 141.7 55.5) (xy 144.1 55.5)
			)
		)
	)
	(zone
		(net 66)
		(net_name "VDDQ")
		(layer "In4.Cu")
		(hatch edge 0.508)
		(priority 1)
		(connect_pads yes
			(clearance 0.15)
		)
		(min_thickness 0.15)
		(filled_areas_thickness no)
		(fill yes
			(thermal_gap 0.508)
			(thermal_bridge_width 0.508)
			(smoothing fillet)
			(radius 0.125)
		)
		(polygon
			(pts
				(xy 146.5 57.5) (xy 181.75 57.5) (xy 181.75 85.5) (xy 171.75 85.5) (xy 171.75 90.4) (xy 164.4 90.4)
				(xy 164.4 98.5) (xy 148.1 98.5) (xy 148.1 77.9) (xy 144.4 77.9) (xy 144.4 55.5) (xy 146.5 55.5)
			)
		)
	)
	(zone
		(net 459)
		(net_name "3V3_SYS")
		(layer "In5.Cu")
		(hatch edge 0.508)
		(connect_pads yes
			(clearance 0.15)
		)
		(min_thickness 0.15)
		(filled_areas_thickness no)
		(fill yes
			(thermal_gap 0.508)
			(thermal_bridge_width 0.508)
			(smoothing fillet)
			(radius 0.125)
		)
		(polygon
			(pts
				(xy 217 136) (xy 107 136) (xy 107 46) (xy 217 46)
			)
		)
	)
	(zone
		(net 463)
		(net_name "VCC5V0_INT")
		(layer "In5.Cu")
		(hatch edge 0.508)
		(priority 2)
		(connect_pads yes
			(clearance 0.2)
		)
		(min_thickness 0.1)
		(filled_areas_thickness no)
		(fill yes
			(thermal_gap 0.5)
			(thermal_bridge_width 0.5)
			(smoothing fillet)
			(radius 0.25)
		)
		(polygon
			(pts
				(xy 184.9 117.09) (xy 183.8 117.09) (xy 183.8 115.985) (xy 184.9 115.985)
			)
		)
	)
	(zone
		(net 602)
		(net_name "1V2_SYS")
		(layer "In6.Cu")
		(hatch edge 0.508)
		(priority 1)
		(connect_pads
			(clearance 0.3)
		)
		(min_thickness 0.15)
		(filled_areas_thickness no)
		(fill yes
			(thermal_gap 0.508)
			(thermal_bridge_width 0.508)
		)
		(polygon
			(pts
				(xy 216.491025 135.819746) (xy 186.586337 135.820008) (xy 186.586328 98.320008) (xy 216.481641 98.320149)
			)
		)
	)
	(zone
		(net 224)
		(net_name "VIN")
		(layer "In6.Cu")
		(hatch edge 0.508)
		(priority 2)
		(connect_pads yes
			(clearance 0.3)
		)
		(min_thickness 0.15)
		(filled_areas_thickness no)
		(fill yes
			(thermal_gap 0.508)
			(thermal_bridge_width 0.508)
			(smoothing fillet)
			(radius 0.125)
		)
		(polygon
			(pts
				(xy 112.2 129.2) (xy 108.4 129.2) (xy 108.4 116.2) (xy 108.4 53.5) (xy 122.9 53.5) (xy 122.9 56)
				(xy 118.6 56) (xy 118.6 129.2)
			)
		)
	)
	(zone
		(net 2)
		(net_name "/Interfaces/1V8_FT")
		(layer "In6.Cu")
		(hatch edge 0.508)
		(priority 1)
		(connect_pads yes
			(clearance 0.15)
		)
		(min_thickness 0.15)
		(filled_areas_thickness no)
		(fill yes
			(thermal_gap 0.508)
			(thermal_bridge_width 0.508)
		)
		(polygon
			(pts
				(xy 147.999191 114.706552) (xy 133.848911 114.752175) (xy 133.93215 100.312355) (xy 148.108602 100.266732)
			)
		)
	)
	(zone
		(net 463)
		(net_name "VCC5V0_INT")
		(layer "In6.Cu")
		(hatch edge 0.508)
		(priority 2)
		(connect_pads yes
			(clearance 0.3)
		)
		(min_thickness 0.15)
		(filled_areas_thickness no)
		(fill yes
			(thermal_gap 0.508)
			(thermal_bridge_width 0.508)
			(smoothing fillet)
			(radius 0.125)
		)
		(polygon
			(pts
				(xy 127.1 65.9) (xy 122.15 65.9) (xy 122.15 107.8) (xy 126 107.8) (xy 126 109.7) (xy 119.1 109.7)
				(xy 119.1 63.7) (xy 127.1 63.7)
			)
		)
	)
	(zone
		(net 5)
		(net_name "GND")
		(layer "In6.Cu")
		(hatch edge 0.508)
		(connect_pads
			(clearance 0.15)
		)
		(min_thickness 0.15)
		(filled_areas_thickness no)
		(fill yes
			(thermal_gap 0.508)
			(thermal_bridge_width 0.508)
			(smoothing fillet)
			(radius 0.125)
		)
		(polygon
			(pts
				(xy 217 136) (xy 107 136) (xy 107 46) (xy 217 46)
			)
		)
	)
	(zone
		(net 465)
		(net_name "1V0_SYS")
		(layer "In6.Cu")
		(hatch edge 0.508)
		(priority 1)
		(connect_pads
			(clearance 0.15)
		)
		(min_thickness 0.15)
		(filled_areas_thickness no)
		(fill yes
			(thermal_gap 0.508)
			(thermal_bridge_width 0.508)
			(smoothing fillet)
			(radius 0.125)
		)
		(polygon
			(pts
				(xy 172.575 100.5) (xy 157.5 100.5) (xy 157.5 98.2) (xy 127.5 98.2) (xy 127.5 84.5) (xy 172.575 84.5)
			)
		)
	)
)
